G04*
G04 #@! TF.GenerationSoftware,Altium Limited,Altium Designer,23.0.1 (38)*
G04*
G04 Layer_Physical_Order=1*
G04 Layer_Color=255*
%FSLAX25Y25*%
%MOIN*%
G70*
G04*
G04 #@! TF.SameCoordinates,C48E81DB-6E20-4E2D-80E6-7C5AFAA1A21F*
G04*
G04*
G04 #@! TF.FilePolarity,Positive*
G04*
G01*
G75*
%ADD12C,0.02000*%
%ADD14C,0.01000*%
%ADD19C,0.00500*%
%ADD24C,0.00800*%
%ADD28C,0.02500*%
%ADD34R,0.04331X0.04134*%
%ADD35R,0.01772X0.01772*%
%ADD36R,0.01968X0.01870*%
%ADD37R,0.02047X0.02205*%
%ADD38R,0.07835X0.09173*%
%ADD39R,0.09500X0.13500*%
%ADD40R,0.02165X0.02165*%
%ADD41R,0.01772X0.01968*%
%ADD42R,0.01968X0.01772*%
%ADD43R,0.02631X0.02648*%
%ADD44R,0.03150X0.03150*%
%ADD45R,0.03740X0.03740*%
%ADD46R,0.02362X0.03150*%
%ADD47R,0.04134X0.04331*%
%ADD48R,0.04724X0.01772*%
G04:AMPARAMS|DCode=49|XSize=33.06mil|YSize=8.76mil|CornerRadius=4.38mil|HoleSize=0mil|Usage=FLASHONLY|Rotation=90.000|XOffset=0mil|YOffset=0mil|HoleType=Round|Shape=RoundedRectangle|*
%AMROUNDEDRECTD49*
21,1,0.03306,0.00000,0,0,90.0*
21,1,0.02430,0.00876,0,0,90.0*
1,1,0.00876,0.00000,0.01215*
1,1,0.00876,0.00000,-0.01215*
1,1,0.00876,0.00000,-0.01215*
1,1,0.00876,0.00000,0.01215*
%
%ADD49ROUNDEDRECTD49*%
%ADD50R,0.00876X0.03306*%
%ADD51R,0.04166X0.05142*%
%ADD52R,0.02165X0.02165*%
%ADD53R,0.02029X0.01860*%
%ADD54R,0.02288X0.02016*%
%ADD55R,0.01968X0.01968*%
%ADD56R,0.01968X0.01968*%
%ADD57R,0.02016X0.02288*%
%ADD58R,0.02992X0.04921*%
%ADD59R,0.03150X0.03150*%
%ADD60R,0.02648X0.02631*%
%ADD61R,0.02559X0.02362*%
%ADD62R,0.09173X0.07835*%
%ADD63R,0.02648X0.02816*%
%ADD64R,0.07284X0.05906*%
%ADD65R,0.02323X0.01772*%
%ADD66R,0.02756X0.02756*%
%ADD67R,0.02165X0.02559*%
%ADD68R,0.11142X0.03543*%
%ADD69R,0.11142X0.08661*%
%ADD70R,0.02816X0.02648*%
%ADD71R,0.02559X0.02165*%
%ADD72R,0.01968X0.02165*%
%ADD73R,0.03543X0.03150*%
%ADD74R,0.03150X0.03543*%
%ADD75R,0.02756X0.02559*%
%ADD76R,0.05315X0.04331*%
%ADD77R,0.02648X0.02911*%
G04:AMPARAMS|DCode=78|XSize=61.02mil|YSize=23.62mil|CornerRadius=2.01mil|HoleSize=0mil|Usage=FLASHONLY|Rotation=180.000|XOffset=0mil|YOffset=0mil|HoleType=Round|Shape=RoundedRectangle|*
%AMROUNDEDRECTD78*
21,1,0.06102,0.01961,0,0,180.0*
21,1,0.05701,0.02362,0,0,180.0*
1,1,0.00402,-0.02850,0.00980*
1,1,0.00402,0.02850,0.00980*
1,1,0.00402,0.02850,-0.00980*
1,1,0.00402,-0.02850,-0.00980*
%
%ADD78ROUNDEDRECTD78*%
%ADD79R,0.01772X0.01772*%
%ADD80R,0.06717X0.04546*%
%ADD81R,0.02165X0.02362*%
%ADD82R,0.02520X0.02677*%
%ADD83R,0.02559X0.02756*%
%ADD84R,0.12362X0.06063*%
%ADD85R,0.09449X0.12992*%
%ADD86R,0.05906X0.07284*%
%ADD87R,0.02911X0.02648*%
%ADD88R,0.02362X0.02165*%
%ADD89R,0.01860X0.02029*%
%ADD90R,0.04331X0.05315*%
%ADD91R,0.02756X0.02756*%
%ADD92R,0.02677X0.02520*%
G04:AMPARAMS|DCode=93|XSize=61.02mil|YSize=23.62mil|CornerRadius=2.01mil|HoleSize=0mil|Usage=FLASHONLY|Rotation=270.000|XOffset=0mil|YOffset=0mil|HoleType=Round|Shape=RoundedRectangle|*
%AMROUNDEDRECTD93*
21,1,0.06102,0.01961,0,0,270.0*
21,1,0.05701,0.02362,0,0,270.0*
1,1,0.00402,-0.00980,-0.02850*
1,1,0.00402,-0.00980,0.02850*
1,1,0.00402,0.00980,0.02850*
1,1,0.00402,0.00980,-0.02850*
%
%ADD93ROUNDEDRECTD93*%
%ADD94R,0.01870X0.00984*%
%ADD95R,0.01378X0.01870*%
%ADD96R,0.04921X0.03937*%
%ADD97R,0.03937X0.04921*%
%ADD98R,0.08287X0.04409*%
%ADD99R,0.05315X0.06693*%
%ADD100R,0.00984X0.06102*%
%ADD101R,0.06693X0.05315*%
%ADD102R,0.06102X0.00984*%
%ADD103R,0.07087X0.00984*%
%ADD104R,0.05709X0.07480*%
%ADD105R,0.06063X0.12362*%
%ADD106R,0.05000X0.20000*%
%ADD107R,0.03740X0.05709*%
%ADD108R,0.05709X0.03740*%
%ADD109R,0.03543X0.01968*%
%ADD110R,0.01968X0.03543*%
%ADD111R,0.05709X0.04528*%
%ADD112R,0.03347X0.01181*%
%ADD113R,0.03740X0.03150*%
%ADD114R,0.03543X0.01024*%
%ADD115R,0.01024X0.03543*%
%ADD116R,0.12795X0.12795*%
%ADD117R,0.03543X0.02362*%
%ADD118R,0.02165X0.02362*%
%ADD119R,0.03543X0.03150*%
%ADD120R,0.03543X0.02953*%
%ADD121R,0.08661X0.04134*%
%ADD122R,0.04134X0.03937*%
%ADD123R,0.03740X0.03740*%
%ADD124R,0.02756X0.03543*%
%ADD125R,0.02953X0.03347*%
%ADD126R,0.05512X0.05512*%
%ADD127R,0.03937X0.05512*%
%ADD128R,0.02800X0.16500*%
%ADD129R,0.02800X0.12600*%
%ADD130O,0.08661X0.02362*%
%ADD131O,0.07480X0.02362*%
%ADD132R,0.02835X0.03937*%
%ADD133R,0.01968X0.01378*%
G04:AMPARAMS|DCode=134|XSize=40.88mil|YSize=20.95mil|CornerRadius=10.48mil|HoleSize=0mil|Usage=FLASHONLY|Rotation=270.000|XOffset=0mil|YOffset=0mil|HoleType=Round|Shape=RoundedRectangle|*
%AMROUNDEDRECTD134*
21,1,0.04088,0.00000,0,0,270.0*
21,1,0.01993,0.02095,0,0,270.0*
1,1,0.02095,0.00000,-0.00996*
1,1,0.02095,0.00000,0.00996*
1,1,0.02095,0.00000,0.00996*
1,1,0.02095,0.00000,-0.00996*
%
%ADD134ROUNDEDRECTD134*%
%ADD135R,0.02095X0.04088*%
G04:AMPARAMS|DCode=155|XSize=43.31mil|YSize=139.76mil|CornerRadius=21.65mil|HoleSize=0mil|Usage=FLASHONLY|Rotation=90.000|XOffset=0mil|YOffset=0mil|HoleType=Round|Shape=RoundedRectangle|*
%AMROUNDEDRECTD155*
21,1,0.04331,0.09646,0,0,90.0*
21,1,0.00000,0.13976,0,0,90.0*
1,1,0.04331,0.04823,0.00000*
1,1,0.04331,0.04823,0.00000*
1,1,0.04331,-0.04823,0.00000*
1,1,0.04331,-0.04823,0.00000*
%
%ADD155ROUNDEDRECTD155*%
%ADD156R,0.10039X0.06496*%
%ADD158R,0.02362X0.00787*%
%ADD159R,0.00787X0.02362*%
%ADD160C,0.00709*%
%ADD161R,0.00787X0.02362*%
%ADD162R,0.02362X0.00787*%
%ADD167R,0.01575X0.01181*%
%ADD168R,0.01181X0.01575*%
%ADD169R,0.06299X0.14567*%
G04:AMPARAMS|DCode=212|XSize=43.31mil|YSize=70.87mil|CornerRadius=21.65mil|HoleSize=0mil|Usage=FLASHONLY|Rotation=90.000|XOffset=0mil|YOffset=0mil|HoleType=Round|Shape=RoundedRectangle|*
%AMROUNDEDRECTD212*
21,1,0.04331,0.02756,0,0,90.0*
21,1,0.00000,0.07087,0,0,90.0*
1,1,0.04331,0.01378,0.00000*
1,1,0.04331,0.01378,0.00000*
1,1,0.04331,-0.01378,0.00000*
1,1,0.04331,-0.01378,0.00000*
%
%ADD212ROUNDEDRECTD212*%
G04:AMPARAMS|DCode=213|XSize=47.24mil|YSize=62.99mil|CornerRadius=23.62mil|HoleSize=0mil|Usage=FLASHONLY|Rotation=90.000|XOffset=0mil|YOffset=0mil|HoleType=Round|Shape=RoundedRectangle|*
%AMROUNDEDRECTD213*
21,1,0.04724,0.01575,0,0,90.0*
21,1,0.00000,0.06299,0,0,90.0*
1,1,0.04724,0.00787,0.00000*
1,1,0.04724,0.00787,0.00000*
1,1,0.04724,-0.00787,0.00000*
1,1,0.04724,-0.00787,0.00000*
%
%ADD213ROUNDEDRECTD213*%
%ADD214C,0.11800*%
%ADD215R,0.10827X0.10827*%
%ADD216C,0.10827*%
%ADD234C,0.01500*%
%ADD235C,0.03000*%
%ADD236R,0.09478X0.29380*%
%ADD237R,0.09941X0.06791*%
%ADD238R,0.11043X0.06693*%
%ADD239R,0.06102X0.06102*%
%ADD240C,0.06102*%
%ADD241C,0.10000*%
%ADD242C,0.02166*%
%ADD243C,0.24000*%
%ADD244C,0.06598*%
%ADD245C,0.08661*%
%ADD246R,0.07874X0.07874*%
%ADD247R,0.05906X0.05906*%
%ADD248C,0.05906*%
%ADD249C,0.25000*%
%ADD250C,0.01600*%
%ADD251C,0.05000*%
%ADD252C,0.20000*%
%ADD253C,0.01968*%
G36*
X615748Y-90551D02*
X613386D01*
Y-89764D01*
X615158D01*
Y-88976D01*
X615748D01*
Y-90551D01*
D02*
G37*
G36*
X582874D02*
X580512D01*
Y-89764D01*
X582283D01*
Y-88976D01*
X582874D01*
Y-90551D01*
D02*
G37*
G36*
X385433Y-116339D02*
X368665D01*
X368315Y-115981D01*
X368504Y-107087D01*
Y-103543D01*
X385433D01*
Y-116339D01*
D02*
G37*
G36*
X571260Y-109449D02*
X586221D01*
Y-119291D01*
X564961D01*
Y-113779D01*
X566142D01*
Y-106693D01*
X571260D01*
Y-109449D01*
D02*
G37*
G36*
X245669Y-125000D02*
X244882D01*
Y-123228D01*
X244094D01*
Y-122638D01*
X245669D01*
Y-125000D01*
D02*
G37*
G36*
X383465Y-129921D02*
X368504D01*
Y-118504D01*
X383465D01*
Y-129921D01*
D02*
G37*
G36*
X361811Y-139764D02*
X346063D01*
Y-103543D01*
X361811D01*
Y-139764D01*
D02*
G37*
G36*
X73902Y-135327D02*
X76772D01*
Y-135827D01*
X77272D01*
Y-138697D01*
X79642D01*
Y-138697D01*
X79807D01*
Y-138697D01*
X85151D01*
X85485Y-139197D01*
X85454Y-139271D01*
Y-139987D01*
X85728Y-140648D01*
X86235Y-141155D01*
X86896Y-141429D01*
X87612D01*
X88027Y-141257D01*
X88041Y-141290D01*
X88547Y-141796D01*
X89209Y-142070D01*
X89925D01*
X90135Y-141983D01*
X90551Y-142261D01*
Y-159730D01*
X90089Y-159921D01*
X87624Y-157455D01*
X87160Y-157146D01*
X86614Y-157037D01*
X86614Y-157037D01*
X83677D01*
Y-156874D01*
X81004D01*
Y-156496D01*
X80504D01*
Y-154905D01*
X78331D01*
Y-154967D01*
X77405D01*
X73380Y-150941D01*
Y-148649D01*
X73592Y-148138D01*
X70109D01*
X70321Y-148649D01*
Y-151575D01*
X70437Y-152160D01*
X70769Y-152656D01*
X75690Y-157578D01*
X76186Y-157909D01*
X76772Y-158026D01*
X78331D01*
Y-161094D01*
X78145Y-161131D01*
X77682Y-161441D01*
X77682Y-161441D01*
X76747Y-162376D01*
X76730Y-162401D01*
X76525Y-162401D01*
X76207Y-162284D01*
X76122Y-161855D01*
X75813Y-161392D01*
X73844Y-159424D01*
X73381Y-159114D01*
X72835Y-159006D01*
X72835Y-159006D01*
X71276D01*
Y-154905D01*
X65929D01*
Y-155072D01*
X65399Y-155177D01*
X64935Y-155487D01*
X64369Y-156053D01*
X62221D01*
Y-154709D01*
X57465D01*
Y-160252D01*
X62221D01*
Y-158908D01*
X64369D01*
X64935Y-159474D01*
X64935Y-159474D01*
X65399Y-159783D01*
X65929Y-159889D01*
Y-163992D01*
X70321D01*
Y-165016D01*
X68916Y-166421D01*
X64748D01*
Y-167962D01*
X64179Y-168075D01*
X63682Y-168407D01*
X62895Y-169194D01*
X62563Y-169690D01*
X62447Y-170276D01*
Y-178122D01*
X62176Y-178776D01*
Y-179492D01*
X62450Y-180154D01*
X62957Y-180660D01*
X63618Y-180934D01*
X64334D01*
X64996Y-180660D01*
X65502Y-180154D01*
X65776Y-179492D01*
Y-178776D01*
X66154Y-178380D01*
X66424Y-178368D01*
X66486Y-178444D01*
X66561Y-178821D01*
X70315D01*
X70209Y-178567D01*
X70518Y-178067D01*
X71079D01*
Y-175500D01*
X67913D01*
Y-174500D01*
X71079D01*
Y-172555D01*
Y-168584D01*
X71471Y-168192D01*
X71933Y-168383D01*
Y-172161D01*
X71933D01*
Y-172327D01*
X71933D01*
Y-178067D01*
X72756D01*
X73090Y-178567D01*
X73003Y-178776D01*
Y-179492D01*
X73277Y-180154D01*
X73783Y-180660D01*
X74445Y-180934D01*
X75161D01*
X75823Y-180660D01*
X76329Y-180154D01*
X76603Y-179492D01*
Y-178776D01*
X76517Y-178567D01*
X76848Y-178071D01*
X77313Y-178150D01*
X77421Y-178696D01*
X77731Y-179159D01*
X78909Y-180337D01*
Y-180476D01*
X79183Y-181138D01*
X79689Y-181644D01*
X80351Y-181918D01*
X81067D01*
X81728Y-181644D01*
X82235Y-181138D01*
X82509Y-180476D01*
Y-179760D01*
X82235Y-179098D01*
X81728Y-178592D01*
X81667Y-178567D01*
X81767Y-178067D01*
X85547D01*
Y-177244D01*
X86047Y-176910D01*
X86256Y-176997D01*
X86972D01*
X87634Y-176723D01*
X88140Y-176216D01*
X88414Y-175555D01*
Y-174839D01*
X88140Y-174177D01*
X87634Y-173671D01*
X86972Y-173397D01*
X86256D01*
X86047Y-173483D01*
X85547Y-173149D01*
Y-172327D01*
X85547D01*
Y-172161D01*
X85547D01*
Y-171235D01*
X85963Y-170957D01*
X86204Y-171057D01*
X86920D01*
X87582Y-170783D01*
X88088Y-170277D01*
X88362Y-169615D01*
Y-168899D01*
X88201Y-168510D01*
X88484Y-167980D01*
X88625Y-167928D01*
X89209Y-168170D01*
X89925D01*
X90135Y-168083D01*
X90551Y-168361D01*
Y-235741D01*
X90165Y-236058D01*
X90041Y-236033D01*
X78899D01*
X78740Y-236002D01*
X77960Y-236157D01*
X77298Y-236599D01*
X76856Y-237261D01*
X76701Y-238041D01*
X76856Y-238821D01*
X77298Y-239483D01*
X77330Y-239514D01*
X77991Y-239956D01*
X78772Y-240112D01*
X89196D01*
X90551Y-241466D01*
Y-354331D01*
X-27320D01*
Y-317092D01*
X-26820Y-316885D01*
X-26579Y-317126D01*
X-26059Y-317341D01*
Y-315600D01*
Y-313859D01*
X-26579Y-314074D01*
X-26820Y-314315D01*
X-27320Y-314108D01*
Y-301092D01*
X-26820Y-300885D01*
X-26579Y-301126D01*
X-26059Y-301341D01*
Y-299600D01*
Y-297859D01*
X-26579Y-298074D01*
X-26820Y-298315D01*
X-27320Y-298108D01*
Y-269092D01*
X-26820Y-268885D01*
X-26579Y-269126D01*
X-26059Y-269341D01*
Y-267600D01*
Y-265859D01*
X-26579Y-266074D01*
X-26820Y-266315D01*
X-27320Y-266108D01*
Y-261092D01*
X-26820Y-260885D01*
X-26579Y-261126D01*
X-26059Y-261341D01*
Y-259600D01*
Y-257859D01*
X-26579Y-258074D01*
X-26820Y-258315D01*
X-27320Y-258108D01*
Y-213092D01*
X-26820Y-212885D01*
X-26579Y-213126D01*
X-26059Y-213341D01*
Y-211600D01*
Y-209859D01*
X-26579Y-210074D01*
X-26820Y-210315D01*
X-27320Y-210108D01*
Y-157092D01*
X-26820Y-156885D01*
X-26579Y-157126D01*
X-26059Y-157341D01*
Y-155600D01*
Y-153859D01*
X-26579Y-154074D01*
X-26820Y-154315D01*
X-27320Y-154108D01*
Y-141092D01*
X-26820Y-140885D01*
X-26579Y-141126D01*
X-26059Y-141341D01*
Y-139600D01*
Y-137859D01*
X-26579Y-138074D01*
X-26820Y-138315D01*
X-27320Y-138108D01*
Y-133858D01*
X73902D01*
Y-135327D01*
D02*
G37*
G36*
X581496Y-134646D02*
X580413D01*
Y-142657D01*
X580058Y-143009D01*
X568504Y-142913D01*
X564173D01*
Y-122146D01*
X581496D01*
Y-134646D01*
D02*
G37*
G36*
X383071Y-144882D02*
X369291D01*
Y-132677D01*
X383071D01*
Y-144882D01*
D02*
G37*
G36*
X628740Y-149606D02*
X608661D01*
Y-124803D01*
X587402D01*
Y-106693D01*
X628740D01*
Y-149606D01*
D02*
G37*
G36*
X682979Y-161130D02*
X682846Y-161453D01*
Y-162169D01*
X683120Y-162831D01*
X683626Y-163337D01*
X684288Y-163611D01*
X685004D01*
X685665Y-163337D01*
X685720Y-163282D01*
X686221Y-163489D01*
Y-173661D01*
X685201D01*
Y-184252D01*
X679921D01*
Y-180315D01*
X670079D01*
Y-175531D01*
X655650D01*
Y-169291D01*
X650787D01*
Y-160630D01*
X678136D01*
X678395Y-161256D01*
X678902Y-161762D01*
X679563Y-162036D01*
X680279D01*
X680941Y-161762D01*
X681447Y-161256D01*
X681706Y-160630D01*
X682645D01*
X682979Y-161130D01*
D02*
G37*
G36*
X651575Y-159055D02*
X647638D01*
Y-174685D01*
X635256D01*
Y-155512D01*
X651575D01*
Y-159055D01*
D02*
G37*
G36*
X605118Y-151181D02*
X615138D01*
Y-163774D01*
Y-174685D01*
X598228D01*
Y-162992D01*
X595669D01*
Y-153150D01*
X589882D01*
Y-144311D01*
X605118D01*
Y-151181D01*
D02*
G37*
G36*
X580413Y-155118D02*
X593701D01*
Y-162205D01*
X592323D01*
Y-171457D01*
X592478Y-172856D01*
X592145Y-173228D01*
X582677D01*
Y-175787D01*
X573228D01*
Y-162795D01*
X570866D01*
Y-147539D01*
X580413D01*
Y-155118D01*
D02*
G37*
G36*
X602756Y-181102D02*
X599422D01*
Y-185833D01*
X582677D01*
Y-177559D01*
X602756D01*
Y-181102D01*
D02*
G37*
G36*
X550394Y-162795D02*
X556693D01*
Y-169291D01*
Y-187008D01*
X543307D01*
Y-154724D01*
X550394D01*
Y-162795D01*
D02*
G37*
G36*
X639370Y-190157D02*
X633090D01*
Y-195925D01*
X625256D01*
Y-181890D01*
X639370D01*
Y-190157D01*
D02*
G37*
G36*
X681038Y-185704D02*
X684685D01*
Y-201575D01*
X683465D01*
Y-206518D01*
X680882D01*
Y-206102D01*
X668253D01*
Y-206862D01*
X664605D01*
Y-207087D01*
X662992D01*
Y-213386D01*
X648032D01*
Y-203642D01*
X637303D01*
Y-191339D01*
X671260D01*
Y-189370D01*
X679921D01*
Y-185655D01*
X681038D01*
Y-185704D01*
D02*
G37*
G36*
X609390Y-201181D02*
X599213D01*
Y-207604D01*
X598892D01*
Y-210192D01*
X595426D01*
Y-204724D01*
X583071D01*
Y-201969D01*
X584646D01*
Y-196850D01*
X583255D01*
Y-191332D01*
X600394D01*
Y-186833D01*
X600422D01*
Y-186752D01*
X609390D01*
Y-201181D01*
D02*
G37*
G36*
X682677Y-214961D02*
X664173D01*
Y-208858D01*
X682677D01*
Y-214961D01*
D02*
G37*
G36*
X645669Y-218012D02*
X639461D01*
Y-221373D01*
X639138Y-221856D01*
X639022Y-222441D01*
Y-222498D01*
X623285D01*
Y-207480D01*
X645669D01*
Y-218012D01*
D02*
G37*
G36*
X609785Y-222498D02*
X602756D01*
Y-228740D01*
X593504D01*
Y-227362D01*
X595426D01*
Y-219740D01*
X590158D01*
Y-212205D01*
X596214Y-211570D01*
X602085D01*
Y-208998D01*
X609785D01*
Y-222498D01*
D02*
G37*
G36*
X581844Y-197019D02*
X581138D01*
X580476Y-197293D01*
X579970Y-197799D01*
X579696Y-198461D01*
Y-198546D01*
X579545Y-198772D01*
X579428Y-199357D01*
Y-202204D01*
X579367D01*
Y-205779D01*
X581844D01*
Y-221102D01*
X579367D01*
Y-224677D01*
X581844D01*
Y-225197D01*
X585485D01*
Y-222102D01*
X594344D01*
Y-225984D01*
X592126D01*
Y-231890D01*
X575197D01*
Y-228147D01*
X576179Y-227165D01*
X577808D01*
Y-220724D01*
X575545D01*
Y-207633D01*
X572396D01*
Y-205906D01*
X572279Y-205320D01*
X571948Y-204824D01*
X568224Y-201101D01*
Y-197324D01*
X568305Y-197244D01*
X569685D01*
Y-195880D01*
X570311Y-195621D01*
X570817Y-195114D01*
X571091Y-194453D01*
Y-193737D01*
X571115Y-193701D01*
X581844D01*
Y-197019D01*
D02*
G37*
G36*
X635374Y-258917D02*
X610236D01*
Y-251181D01*
X602153D01*
Y-250291D01*
X591129D01*
Y-248521D01*
Y-244291D01*
X596441D01*
Y-245291D01*
X601984D01*
Y-244291D01*
X603150D01*
Y-243701D01*
X607760D01*
X608303Y-243926D01*
X609020D01*
X609563Y-243701D01*
X635374D01*
Y-258917D01*
D02*
G37*
G36*
X557421Y-251575D02*
X550000D01*
Y-255268D01*
X549819Y-255693D01*
X545850D01*
Y-255906D01*
X543701D01*
Y-240295D01*
X557421D01*
Y-251575D01*
D02*
G37*
G36*
X587795Y-256293D02*
X591129D01*
Y-256687D01*
X608516D01*
X608869Y-257041D01*
X608847Y-261233D01*
X593701D01*
Y-268799D01*
X584252D01*
Y-263386D01*
X571752D01*
Y-260975D01*
X572097Y-260630D01*
X575591D01*
Y-255512D01*
X581122D01*
Y-249468D01*
X575137D01*
Y-240295D01*
X587795D01*
Y-256293D01*
D02*
G37*
G36*
X606242Y-282382D02*
X589426D01*
Y-279035D01*
X583189D01*
Y-278346D01*
X579528D01*
Y-270177D01*
X596742D01*
Y-269234D01*
X606242D01*
Y-282382D01*
D02*
G37*
G36*
X637106Y-282734D02*
X619742D01*
Y-265650D01*
X637106D01*
Y-282734D01*
D02*
G37*
G36*
X679134Y-284252D02*
X675984D01*
X665528Y-284327D01*
X665173Y-283974D01*
Y-280910D01*
X665193Y-280811D01*
Y-278702D01*
X665115Y-278311D01*
X665091Y-278275D01*
Y-274481D01*
X665115Y-274444D01*
X665193Y-274054D01*
Y-273228D01*
X665624Y-272835D01*
X669685D01*
Y-263386D01*
X667323D01*
Y-249606D01*
X679134D01*
Y-284252D01*
D02*
G37*
G36*
X664761Y-249979D02*
Y-254626D01*
X664998D01*
Y-255906D01*
X663976D01*
Y-264961D01*
X659842D01*
Y-273228D01*
X664173D01*
Y-274054D01*
X664043D01*
Y-278702D01*
X664173D01*
Y-280811D01*
X663961D01*
Y-285331D01*
X664173D01*
Y-287795D01*
X642126D01*
X642007Y-280317D01*
X642358Y-279961D01*
X642437D01*
Y-275945D01*
X641906D01*
X641643Y-266008D01*
X641992Y-265650D01*
X651240D01*
Y-249744D01*
X664359D01*
X664761Y-249979D01*
D02*
G37*
G36*
X572047Y-256483D02*
X571421Y-256742D01*
X570915Y-257248D01*
X570641Y-257910D01*
Y-258049D01*
X568774Y-259916D01*
X568465Y-260379D01*
X568379Y-260811D01*
X568193D01*
Y-264386D01*
X569193D01*
Y-264764D01*
X570669D01*
Y-279331D01*
Y-279709D01*
X568193D01*
Y-283283D01*
X573933D01*
Y-280709D01*
X584646D01*
Y-283350D01*
X579610D01*
Y-285451D01*
X577266Y-287795D01*
X571490D01*
X571348Y-287581D01*
Y-286865D01*
X571073Y-286204D01*
X570567Y-285697D01*
X569906Y-285423D01*
X569190D01*
X568528Y-285697D01*
X568022Y-286204D01*
X567747Y-286865D01*
Y-287581D01*
X567604Y-287795D01*
X564971D01*
X564801Y-287295D01*
X566107Y-285989D01*
X566549Y-285328D01*
X566705Y-284547D01*
Y-281496D01*
X566549Y-280716D01*
X566256Y-280277D01*
Y-279709D01*
X565590D01*
X565446Y-279612D01*
X564665Y-279457D01*
X564512Y-279331D01*
X564370D01*
Y-279215D01*
Y-277417D01*
Y-266240D01*
X556693D01*
Y-263241D01*
X556729Y-263217D01*
X557445D01*
X558106Y-262943D01*
X558613Y-262437D01*
X558887Y-261775D01*
Y-261059D01*
X558613Y-260398D01*
X558106Y-259891D01*
X558053Y-259869D01*
X557936Y-259280D01*
X558154Y-259062D01*
X558428Y-258400D01*
Y-257684D01*
X558154Y-257023D01*
X557647Y-256516D01*
X556986Y-256242D01*
X556693D01*
Y-254331D01*
X572047D01*
Y-256483D01*
D02*
G37*
G36*
X403920Y-325796D02*
X404242D01*
Y-325828D01*
X404404D01*
Y-325861D01*
X404533D01*
Y-325893D01*
X404597D01*
Y-325925D01*
X404694D01*
Y-325957D01*
X404759D01*
Y-325990D01*
X404855D01*
Y-326022D01*
X404888D01*
Y-326054D01*
X404952D01*
Y-326086D01*
X405017D01*
Y-326119D01*
X405049D01*
Y-326151D01*
X405113D01*
Y-326183D01*
X405146D01*
Y-326216D01*
X405210D01*
Y-326248D01*
X405242D01*
Y-326280D01*
X405275D01*
Y-326312D01*
X405307D01*
Y-326345D01*
X405339D01*
Y-326377D01*
X405372D01*
Y-326409D01*
X405404D01*
Y-326441D01*
X405436D01*
Y-326474D01*
X405468D01*
Y-326506D01*
X405501D01*
Y-326538D01*
X405533D01*
Y-326570D01*
X405565D01*
Y-326603D01*
Y-326635D01*
X405597D01*
Y-326667D01*
X405630D01*
Y-326699D01*
Y-326732D01*
X405662D01*
Y-326764D01*
X405694D01*
Y-326796D01*
Y-326829D01*
X405726D01*
Y-326861D01*
Y-326893D01*
X405759D01*
Y-326925D01*
X405791D01*
Y-326958D01*
Y-326990D01*
X405823D01*
Y-327022D01*
Y-327054D01*
Y-327087D01*
X405855D01*
Y-327119D01*
Y-327151D01*
X405888D01*
Y-327183D01*
Y-327216D01*
Y-327248D01*
X405920D01*
Y-327280D01*
Y-327312D01*
Y-327345D01*
Y-327377D01*
X405952D01*
Y-327409D01*
Y-327442D01*
Y-327474D01*
Y-327506D01*
X405984D01*
Y-327538D01*
Y-327571D01*
Y-327603D01*
Y-327635D01*
Y-327667D01*
Y-327700D01*
Y-327732D01*
Y-327764D01*
Y-327796D01*
Y-327829D01*
X406017D01*
Y-327861D01*
Y-327893D01*
Y-327925D01*
Y-327958D01*
X405984D01*
Y-327990D01*
Y-328022D01*
Y-328054D01*
Y-328087D01*
Y-328119D01*
Y-328151D01*
Y-328184D01*
Y-328216D01*
Y-328248D01*
X405952D01*
Y-328280D01*
Y-328313D01*
Y-328345D01*
Y-328377D01*
Y-328409D01*
X405920D01*
Y-328442D01*
Y-328474D01*
Y-328506D01*
X405888D01*
Y-328538D01*
Y-328571D01*
Y-328603D01*
X405855D01*
Y-328635D01*
Y-328667D01*
Y-328700D01*
X405823D01*
Y-328732D01*
Y-328764D01*
X405791D01*
Y-328797D01*
Y-328829D01*
X405759D01*
Y-328861D01*
Y-328893D01*
X405726D01*
Y-328925D01*
Y-328958D01*
X405694D01*
Y-328990D01*
Y-329022D01*
X405662D01*
Y-329055D01*
X405630D01*
Y-329087D01*
Y-329119D01*
X405597D01*
Y-329151D01*
X405565D01*
Y-329184D01*
X405533D01*
Y-329216D01*
Y-329248D01*
X405501D01*
Y-329280D01*
X405468D01*
Y-329313D01*
X405436D01*
Y-329345D01*
X405404D01*
Y-329377D01*
X405372D01*
Y-329410D01*
X405339D01*
Y-329442D01*
X405307D01*
Y-329474D01*
X405275D01*
Y-329506D01*
X405210D01*
Y-329538D01*
X405178D01*
Y-329571D01*
X405146D01*
Y-329603D01*
X405113D01*
Y-329635D01*
X405049D01*
Y-329667D01*
X405017D01*
Y-329700D01*
X404952D01*
Y-329732D01*
X404888D01*
Y-329764D01*
X404823D01*
Y-329797D01*
X404759D01*
Y-329829D01*
X404694D01*
Y-329861D01*
X404597D01*
Y-329893D01*
X404500D01*
Y-329926D01*
X404371D01*
Y-329958D01*
X404210D01*
Y-329990D01*
X401081D01*
Y-329958D01*
X400919D01*
Y-329926D01*
X400823D01*
Y-329893D01*
X400726D01*
Y-329861D01*
X400629D01*
Y-329829D01*
X400564D01*
Y-329797D01*
X400468D01*
Y-329764D01*
X400435D01*
Y-329732D01*
X400371D01*
Y-329700D01*
X400306D01*
Y-329667D01*
X400274D01*
Y-329635D01*
X400210D01*
Y-329603D01*
X400177D01*
Y-329571D01*
X400113D01*
Y-329538D01*
X400081D01*
Y-329506D01*
X400048D01*
Y-329474D01*
X400016D01*
Y-329442D01*
X399984D01*
Y-329410D01*
X399952D01*
Y-329377D01*
X399919D01*
Y-329345D01*
X399887D01*
Y-329313D01*
X399855D01*
Y-329280D01*
X399822D01*
Y-329248D01*
X399790D01*
Y-329216D01*
X399758D01*
Y-329184D01*
Y-329151D01*
X399726D01*
Y-329119D01*
X399693D01*
Y-329087D01*
X399661D01*
Y-329055D01*
Y-329022D01*
X399629D01*
Y-328990D01*
Y-328958D01*
X399597D01*
Y-328925D01*
X399564D01*
Y-328893D01*
Y-328861D01*
X399532D01*
Y-328829D01*
Y-328797D01*
X399500D01*
Y-328764D01*
Y-328732D01*
X399468D01*
Y-328700D01*
Y-328667D01*
Y-328635D01*
X399435D01*
Y-328603D01*
Y-328571D01*
Y-328538D01*
X399403D01*
Y-328506D01*
Y-328474D01*
Y-328442D01*
X399371D01*
Y-328409D01*
Y-328377D01*
Y-328345D01*
Y-328313D01*
Y-328280D01*
X399339D01*
Y-328248D01*
Y-328216D01*
Y-328184D01*
Y-328151D01*
Y-328119D01*
X399306D01*
Y-328087D01*
Y-328054D01*
Y-328022D01*
Y-327990D01*
Y-327958D01*
Y-327925D01*
Y-327893D01*
Y-327861D01*
Y-327829D01*
Y-327796D01*
Y-327764D01*
Y-327732D01*
Y-327700D01*
X399339D01*
Y-327667D01*
Y-327635D01*
Y-327603D01*
Y-327571D01*
Y-327538D01*
Y-327506D01*
Y-327474D01*
X399371D01*
Y-327442D01*
Y-327409D01*
Y-327377D01*
Y-327345D01*
X399403D01*
Y-327312D01*
Y-327280D01*
Y-327248D01*
Y-327216D01*
X399435D01*
Y-327183D01*
Y-327151D01*
X399468D01*
Y-327119D01*
Y-327087D01*
Y-327054D01*
X399500D01*
Y-327022D01*
Y-326990D01*
X399532D01*
Y-326958D01*
Y-326925D01*
X399564D01*
Y-326893D01*
Y-326861D01*
X399597D01*
Y-326829D01*
Y-326796D01*
X399629D01*
Y-326764D01*
X399661D01*
Y-326732D01*
Y-326699D01*
X399693D01*
Y-326667D01*
X399726D01*
Y-326635D01*
Y-326603D01*
X399758D01*
Y-326570D01*
X399790D01*
Y-326538D01*
X399822D01*
Y-326506D01*
X399855D01*
Y-326474D01*
X399887D01*
Y-326441D01*
X399919D01*
Y-326409D01*
X399952D01*
Y-326377D01*
X399984D01*
Y-326345D01*
X400016D01*
Y-326312D01*
X400048D01*
Y-326280D01*
X400081D01*
Y-326248D01*
X400113D01*
Y-326216D01*
X400145D01*
Y-326183D01*
X400210D01*
Y-326151D01*
X400242D01*
Y-326119D01*
X400306D01*
Y-326086D01*
X400339D01*
Y-326054D01*
X400403D01*
Y-326022D01*
X400468D01*
Y-325990D01*
X400532D01*
Y-325957D01*
X400629D01*
Y-325925D01*
X400694D01*
Y-325893D01*
X400790D01*
Y-325861D01*
X400919D01*
Y-325828D01*
X401048D01*
Y-325796D01*
X401403D01*
Y-325764D01*
X403855D01*
Y-325796D01*
X403888D01*
Y-325764D01*
X403920D01*
Y-325796D01*
D02*
G37*
G36*
X322515Y-210485D02*
X322313Y-212402D01*
X277037D01*
Y-261614D01*
X322313D01*
X322515Y-263530D01*
Y-336022D01*
X122712D01*
Y-136219D01*
X322515D01*
Y-210485D01*
D02*
G37*
G36*
X355043Y-339282D02*
X355172D01*
Y-339314D01*
X355269D01*
Y-339346D01*
X355333D01*
Y-339378D01*
X355398D01*
Y-339411D01*
X355430D01*
Y-339443D01*
X355495D01*
Y-339475D01*
X355527D01*
Y-339507D01*
X355592D01*
Y-339540D01*
X355624D01*
Y-339572D01*
X355656D01*
Y-339604D01*
X355688D01*
Y-339636D01*
X355721D01*
Y-339669D01*
X355753D01*
Y-339701D01*
Y-339733D01*
X355785D01*
Y-339766D01*
X355817D01*
Y-339798D01*
Y-339830D01*
X355850D01*
Y-339862D01*
X355882D01*
Y-339895D01*
Y-339927D01*
X355914D01*
Y-339959D01*
Y-339991D01*
Y-340024D01*
X355946D01*
Y-340056D01*
Y-340088D01*
Y-340120D01*
X355979D01*
Y-340153D01*
Y-340185D01*
Y-340217D01*
Y-340249D01*
X356011D01*
Y-340282D01*
Y-340314D01*
Y-340346D01*
Y-340378D01*
Y-340411D01*
Y-340443D01*
Y-340475D01*
Y-340508D01*
Y-340540D01*
Y-340572D01*
Y-340604D01*
Y-340637D01*
Y-340669D01*
X355979D01*
Y-340701D01*
Y-340733D01*
Y-340766D01*
Y-340798D01*
X355946D01*
Y-340830D01*
Y-340862D01*
Y-340895D01*
X355914D01*
Y-340927D01*
Y-340959D01*
X355882D01*
Y-340991D01*
Y-341024D01*
X355850D01*
Y-341056D01*
Y-341088D01*
X355817D01*
Y-341121D01*
X355785D01*
Y-341153D01*
Y-341185D01*
X355753D01*
Y-341217D01*
X355721D01*
Y-341249D01*
X355688D01*
Y-341282D01*
X355656D01*
Y-341314D01*
X355624D01*
Y-341346D01*
X355592D01*
Y-341379D01*
X355559D01*
Y-341411D01*
X355527D01*
Y-341443D01*
X355463D01*
Y-341475D01*
X355430D01*
Y-341508D01*
X355366D01*
Y-341540D01*
X355301D01*
Y-341572D01*
X355204D01*
Y-341604D01*
X355108D01*
Y-341637D01*
X354914D01*
Y-341669D01*
X354688D01*
Y-341637D01*
X354495D01*
Y-341604D01*
X354398D01*
Y-341572D01*
X354333D01*
Y-341540D01*
X354237D01*
Y-341508D01*
X354204D01*
Y-341475D01*
X354140D01*
Y-341443D01*
X354107D01*
Y-341411D01*
X354043D01*
Y-341379D01*
X354011D01*
Y-341346D01*
X353978D01*
Y-341314D01*
X353946D01*
Y-341282D01*
X353914D01*
Y-341249D01*
X353882D01*
Y-341217D01*
X353849D01*
Y-341185D01*
X353817D01*
Y-341153D01*
Y-341121D01*
X353785D01*
Y-341088D01*
Y-341056D01*
X353753D01*
Y-341024D01*
X353720D01*
Y-340991D01*
Y-340959D01*
X353688D01*
Y-340927D01*
Y-340895D01*
Y-340862D01*
X353656D01*
Y-340830D01*
Y-340798D01*
Y-340766D01*
X353624D01*
Y-340733D01*
Y-340701D01*
Y-340669D01*
Y-340637D01*
Y-340604D01*
X353591D01*
Y-340572D01*
Y-340540D01*
Y-340508D01*
Y-340475D01*
Y-340443D01*
Y-340411D01*
Y-340378D01*
Y-340346D01*
Y-340314D01*
Y-340282D01*
X353624D01*
Y-340249D01*
Y-340217D01*
Y-340185D01*
Y-340153D01*
Y-340120D01*
X353656D01*
Y-340088D01*
Y-340056D01*
Y-340024D01*
X353688D01*
Y-339991D01*
Y-339959D01*
X353720D01*
Y-339927D01*
Y-339895D01*
X353753D01*
Y-339862D01*
Y-339830D01*
X353785D01*
Y-339798D01*
Y-339766D01*
X353817D01*
Y-339733D01*
X353849D01*
Y-339701D01*
X353882D01*
Y-339669D01*
Y-339636D01*
X353914D01*
Y-339604D01*
X353946D01*
Y-339572D01*
X353978D01*
Y-339540D01*
X354043D01*
Y-339507D01*
X354075D01*
Y-339475D01*
X354107D01*
Y-339443D01*
X354172D01*
Y-339411D01*
X354204D01*
Y-339378D01*
X354269D01*
Y-339346D01*
X354366D01*
Y-339314D01*
X354430D01*
Y-339282D01*
X354559D01*
Y-339249D01*
X355043D01*
Y-339282D01*
D02*
G37*
G36*
X355011Y-343637D02*
X355140D01*
Y-343669D01*
X355237D01*
Y-343701D01*
X355301D01*
Y-343734D01*
X355366D01*
Y-343766D01*
X355430D01*
Y-343798D01*
X355495D01*
Y-343830D01*
X355527D01*
Y-343863D01*
X355559D01*
Y-343895D01*
X355624D01*
Y-343927D01*
X355656D01*
Y-343959D01*
X355688D01*
Y-343992D01*
X355721D01*
Y-344024D01*
Y-344056D01*
X355753D01*
Y-344089D01*
X355785D01*
Y-344121D01*
X355817D01*
Y-344153D01*
Y-344185D01*
X355850D01*
Y-344218D01*
Y-344250D01*
X355882D01*
Y-344282D01*
Y-344314D01*
X355914D01*
Y-344347D01*
Y-344379D01*
X355946D01*
Y-344411D01*
Y-344443D01*
Y-344476D01*
X355979D01*
Y-344508D01*
Y-344540D01*
Y-344572D01*
Y-344605D01*
X356011D01*
Y-344637D01*
Y-344669D01*
Y-344702D01*
Y-344734D01*
Y-344766D01*
Y-344798D01*
Y-344831D01*
Y-344863D01*
Y-344895D01*
Y-344927D01*
Y-344960D01*
Y-344992D01*
Y-345024D01*
X355979D01*
Y-345056D01*
Y-345089D01*
Y-345121D01*
Y-345153D01*
X355946D01*
Y-345185D01*
Y-345218D01*
Y-345250D01*
X355914D01*
Y-345282D01*
Y-345315D01*
X355882D01*
Y-345347D01*
Y-345379D01*
X355850D01*
Y-345411D01*
Y-345444D01*
X355817D01*
Y-345476D01*
Y-345508D01*
X355785D01*
Y-345540D01*
X355753D01*
Y-345573D01*
X355721D01*
Y-345605D01*
Y-345637D01*
X355688D01*
Y-345669D01*
X355656D01*
Y-345702D01*
X355592D01*
Y-345734D01*
X355559D01*
Y-345766D01*
X355527D01*
Y-345798D01*
X355495D01*
Y-345831D01*
X355430D01*
Y-345863D01*
X355366D01*
Y-345895D01*
X355301D01*
Y-345928D01*
X355237D01*
Y-345960D01*
X355140D01*
Y-345992D01*
X354979D01*
Y-346024D01*
X354624D01*
Y-345992D01*
X354462D01*
Y-345960D01*
X354366D01*
Y-345928D01*
X354301D01*
Y-345895D01*
X354237D01*
Y-345863D01*
X354172D01*
Y-345831D01*
X354140D01*
Y-345798D01*
X354075D01*
Y-345766D01*
X354043D01*
Y-345734D01*
X354011D01*
Y-345702D01*
X353978D01*
Y-345669D01*
X353946D01*
Y-345637D01*
X353914D01*
Y-345605D01*
X353882D01*
Y-345573D01*
X353849D01*
Y-345540D01*
X353817D01*
Y-345508D01*
Y-345476D01*
X353785D01*
Y-345444D01*
X353753D01*
Y-345411D01*
Y-345379D01*
X353720D01*
Y-345347D01*
Y-345315D01*
X353688D01*
Y-345282D01*
Y-345250D01*
Y-345218D01*
X353656D01*
Y-345185D01*
Y-345153D01*
Y-345121D01*
X353624D01*
Y-345089D01*
Y-345056D01*
Y-345024D01*
Y-344992D01*
X353591D01*
Y-344960D01*
Y-344927D01*
Y-344895D01*
Y-344863D01*
Y-344831D01*
Y-344798D01*
Y-344766D01*
Y-344734D01*
Y-344702D01*
Y-344669D01*
Y-344637D01*
X353624D01*
Y-344605D01*
Y-344572D01*
Y-344540D01*
Y-344508D01*
X353656D01*
Y-344476D01*
Y-344443D01*
Y-344411D01*
Y-344379D01*
X353688D01*
Y-344347D01*
Y-344314D01*
X353720D01*
Y-344282D01*
Y-344250D01*
X353753D01*
Y-344218D01*
Y-344185D01*
X353785D01*
Y-344153D01*
X353817D01*
Y-344121D01*
Y-344089D01*
X353849D01*
Y-344056D01*
X353882D01*
Y-344024D01*
X353914D01*
Y-343992D01*
X353946D01*
Y-343959D01*
X353978D01*
Y-343927D01*
X354011D01*
Y-343895D01*
X354043D01*
Y-343863D01*
X354075D01*
Y-343830D01*
X354140D01*
Y-343798D01*
X354172D01*
Y-343766D01*
X354237D01*
Y-343734D01*
X354301D01*
Y-343701D01*
X354366D01*
Y-343669D01*
X354462D01*
Y-343637D01*
X354624D01*
Y-343605D01*
X355011D01*
Y-343637D01*
D02*
G37*
G36*
X411340Y-342637D02*
X411533D01*
Y-342669D01*
X411663D01*
Y-342701D01*
X411759D01*
Y-342734D01*
X411856D01*
Y-342766D01*
X411921D01*
Y-342798D01*
X412017D01*
Y-342830D01*
X412082D01*
Y-342863D01*
X412114D01*
Y-342895D01*
X412179D01*
Y-342927D01*
X412243D01*
Y-342959D01*
X412276D01*
Y-342992D01*
X412340D01*
Y-343024D01*
X412372D01*
Y-343056D01*
X412405D01*
Y-343089D01*
X412437D01*
Y-343121D01*
X412501D01*
Y-343153D01*
X412534D01*
Y-343185D01*
X412566D01*
Y-343217D01*
X412598D01*
Y-343250D01*
X412630D01*
Y-343282D01*
X412663D01*
Y-343314D01*
X412695D01*
Y-343347D01*
X412727D01*
Y-343379D01*
Y-343411D01*
X412759D01*
Y-343443D01*
X412792D01*
Y-343476D01*
X412824D01*
Y-343508D01*
Y-343540D01*
X412856D01*
Y-343572D01*
X412888D01*
Y-343605D01*
Y-343637D01*
X412921D01*
Y-343669D01*
Y-343701D01*
X412953D01*
Y-343734D01*
X412985D01*
Y-343766D01*
Y-343798D01*
X413018D01*
Y-343830D01*
Y-343863D01*
Y-343895D01*
X413050D01*
Y-343927D01*
Y-343959D01*
X413082D01*
Y-343992D01*
Y-344024D01*
Y-344056D01*
X413114D01*
Y-344089D01*
Y-344121D01*
Y-344153D01*
X413147D01*
Y-344185D01*
Y-344218D01*
Y-344250D01*
Y-344282D01*
X413179D01*
Y-344314D01*
Y-344347D01*
Y-344379D01*
Y-344411D01*
Y-344443D01*
Y-344476D01*
X413211D01*
Y-344508D01*
Y-344540D01*
Y-344572D01*
Y-344605D01*
Y-344637D01*
Y-344669D01*
Y-344702D01*
Y-344734D01*
Y-344766D01*
Y-344798D01*
Y-344831D01*
Y-344863D01*
Y-344895D01*
Y-344927D01*
Y-344960D01*
X413179D01*
Y-344992D01*
Y-345024D01*
Y-345056D01*
Y-345089D01*
Y-345121D01*
Y-345153D01*
X413147D01*
Y-345185D01*
Y-345218D01*
Y-345250D01*
Y-345282D01*
X413114D01*
Y-345315D01*
Y-345347D01*
Y-345379D01*
X413082D01*
Y-345411D01*
Y-345444D01*
Y-345476D01*
X413050D01*
Y-345508D01*
Y-345540D01*
X413018D01*
Y-345573D01*
Y-345605D01*
X412985D01*
Y-345637D01*
Y-345669D01*
X412953D01*
Y-345702D01*
Y-345734D01*
X412921D01*
Y-345766D01*
Y-345798D01*
X412888D01*
Y-345831D01*
X412856D01*
Y-345863D01*
Y-345895D01*
X412824D01*
Y-345928D01*
X412792D01*
Y-345960D01*
Y-345992D01*
X412759D01*
Y-346024D01*
X412727D01*
Y-346057D01*
X412695D01*
Y-346089D01*
X412663D01*
Y-346121D01*
X412630D01*
Y-346153D01*
X412598D01*
Y-346186D01*
X412566D01*
Y-346218D01*
X412534D01*
Y-346250D01*
X412501D01*
Y-346282D01*
X412469D01*
Y-346315D01*
X412437D01*
Y-346347D01*
X412405D01*
Y-346379D01*
X412340D01*
Y-346411D01*
X412308D01*
Y-346444D01*
X412276D01*
Y-346476D01*
X412211D01*
Y-346508D01*
X412147D01*
Y-346540D01*
X412114D01*
Y-346573D01*
X412050D01*
Y-346605D01*
X411985D01*
Y-346637D01*
X411888D01*
Y-346670D01*
X411824D01*
Y-346702D01*
X411727D01*
Y-346734D01*
X411598D01*
Y-346766D01*
X411437D01*
Y-346799D01*
X411243D01*
Y-346831D01*
X411211D01*
Y-346799D01*
X411179D01*
Y-346831D01*
X411146D01*
Y-346799D01*
X411114D01*
Y-346831D01*
X410888D01*
Y-346799D01*
X410662D01*
Y-346766D01*
X410501D01*
Y-346734D01*
X410404D01*
Y-346702D01*
X410308D01*
Y-346670D01*
X410211D01*
Y-346637D01*
X410146D01*
Y-346605D01*
X410082D01*
Y-346573D01*
X410017D01*
Y-346540D01*
X409953D01*
Y-346508D01*
X409920D01*
Y-346476D01*
X409856D01*
Y-346444D01*
X409824D01*
Y-346411D01*
X409759D01*
Y-346379D01*
X409727D01*
Y-346347D01*
X409695D01*
Y-346315D01*
X409662D01*
Y-346282D01*
X409598D01*
Y-346250D01*
X409565D01*
Y-346218D01*
X409533D01*
Y-346186D01*
X409501D01*
Y-346153D01*
X409469D01*
Y-346121D01*
X409437D01*
Y-346089D01*
Y-346057D01*
X409404D01*
Y-346024D01*
X409372D01*
Y-345992D01*
X409340D01*
Y-345960D01*
X409307D01*
Y-345928D01*
Y-345895D01*
X409275D01*
Y-345863D01*
X409243D01*
Y-345831D01*
Y-345798D01*
X409211D01*
Y-345766D01*
Y-345734D01*
X409178D01*
Y-345702D01*
X409146D01*
Y-345669D01*
Y-345637D01*
X409114D01*
Y-345605D01*
Y-345573D01*
X409082D01*
Y-345540D01*
Y-345508D01*
Y-345476D01*
X409049D01*
Y-345444D01*
Y-345411D01*
X409017D01*
Y-345379D01*
Y-345347D01*
Y-345315D01*
X408985D01*
Y-345282D01*
Y-345250D01*
Y-345218D01*
Y-345185D01*
X408953D01*
Y-345153D01*
Y-345121D01*
Y-345089D01*
Y-345056D01*
Y-345024D01*
X408920D01*
Y-344992D01*
Y-344960D01*
Y-344927D01*
Y-344895D01*
Y-344863D01*
Y-344831D01*
Y-344798D01*
Y-344766D01*
Y-344734D01*
Y-344702D01*
Y-344669D01*
Y-344637D01*
Y-344605D01*
Y-344572D01*
Y-344540D01*
Y-344508D01*
Y-344476D01*
Y-344443D01*
Y-344411D01*
X408953D01*
Y-344379D01*
Y-344347D01*
Y-344314D01*
Y-344282D01*
Y-344250D01*
X408985D01*
Y-344218D01*
Y-344185D01*
Y-344153D01*
Y-344121D01*
X409017D01*
Y-344089D01*
Y-344056D01*
Y-344024D01*
X409049D01*
Y-343992D01*
Y-343959D01*
Y-343927D01*
X409082D01*
Y-343895D01*
Y-343863D01*
X409114D01*
Y-343830D01*
Y-343798D01*
X409146D01*
Y-343766D01*
Y-343734D01*
X409178D01*
Y-343701D01*
Y-343669D01*
X409211D01*
Y-343637D01*
Y-343605D01*
X409243D01*
Y-343572D01*
X409275D01*
Y-343540D01*
Y-343508D01*
X409307D01*
Y-343476D01*
X409340D01*
Y-343443D01*
X409372D01*
Y-343411D01*
Y-343379D01*
X409404D01*
Y-343347D01*
X409437D01*
Y-343314D01*
X409469D01*
Y-343282D01*
X409501D01*
Y-343250D01*
X409533D01*
Y-343217D01*
X409565D01*
Y-343185D01*
X409598D01*
Y-343153D01*
X409630D01*
Y-343121D01*
X409662D01*
Y-343089D01*
X409695D01*
Y-343056D01*
X409759D01*
Y-343024D01*
X409791D01*
Y-342992D01*
X409856D01*
Y-342959D01*
X409888D01*
Y-342927D01*
X409953D01*
Y-342895D01*
X409985D01*
Y-342863D01*
X410049D01*
Y-342830D01*
X410114D01*
Y-342798D01*
X410179D01*
Y-342766D01*
X410275D01*
Y-342734D01*
X410372D01*
Y-342701D01*
X410469D01*
Y-342669D01*
X410598D01*
Y-342637D01*
X410759D01*
Y-342604D01*
X411340D01*
Y-342637D01*
D02*
G37*
G36*
X394209Y-325796D02*
X394564D01*
Y-325828D01*
X394693D01*
Y-325861D01*
X394822D01*
Y-325893D01*
X394919D01*
Y-325925D01*
X395016D01*
Y-325957D01*
X395080D01*
Y-325990D01*
X395145D01*
Y-326022D01*
X395209D01*
Y-326054D01*
X395274D01*
Y-326086D01*
X395338D01*
Y-326119D01*
X395370D01*
Y-326151D01*
X395435D01*
Y-326183D01*
X395467D01*
Y-326216D01*
X395499D01*
Y-326248D01*
X395564D01*
Y-326280D01*
X395596D01*
Y-326312D01*
X395628D01*
Y-326345D01*
X395661D01*
Y-326377D01*
X395693D01*
Y-326409D01*
X395725D01*
Y-326441D01*
X395758D01*
Y-326474D01*
X395790D01*
Y-326506D01*
X395822D01*
Y-326538D01*
X395854D01*
Y-326570D01*
X395886D01*
Y-326603D01*
Y-326635D01*
X395919D01*
Y-326667D01*
X395951D01*
Y-326699D01*
X395983D01*
Y-326732D01*
Y-326764D01*
X396016D01*
Y-326796D01*
Y-326829D01*
X396048D01*
Y-326861D01*
X396080D01*
Y-326893D01*
Y-326925D01*
X396112D01*
Y-326958D01*
Y-326990D01*
X396145D01*
Y-327022D01*
Y-327054D01*
X396177D01*
Y-327087D01*
Y-327119D01*
Y-327151D01*
X396209D01*
Y-327183D01*
Y-327216D01*
Y-327248D01*
X396241D01*
Y-327280D01*
Y-327312D01*
Y-327345D01*
X396274D01*
Y-327377D01*
Y-327409D01*
Y-327442D01*
Y-327474D01*
X396306D01*
Y-327506D01*
Y-327538D01*
Y-327571D01*
Y-327603D01*
Y-327635D01*
Y-327667D01*
X396338D01*
Y-327700D01*
Y-327732D01*
Y-327764D01*
Y-327796D01*
Y-327829D01*
Y-327861D01*
Y-327893D01*
Y-327925D01*
Y-327958D01*
Y-327990D01*
Y-328022D01*
X396306D01*
Y-328054D01*
X396338D01*
Y-328087D01*
X396306D01*
Y-328119D01*
Y-328151D01*
Y-328184D01*
Y-328216D01*
Y-328248D01*
Y-328280D01*
Y-328313D01*
X396274D01*
Y-328345D01*
Y-328377D01*
Y-328409D01*
Y-328442D01*
X396241D01*
Y-328474D01*
Y-328506D01*
Y-328538D01*
X396209D01*
Y-328571D01*
Y-328603D01*
Y-328635D01*
X396177D01*
Y-328667D01*
Y-328700D01*
Y-328732D01*
X396145D01*
Y-328764D01*
Y-328797D01*
X396112D01*
Y-328829D01*
Y-328861D01*
X396080D01*
Y-328893D01*
Y-328925D01*
X396048D01*
Y-328958D01*
X396016D01*
Y-328990D01*
Y-329022D01*
X395983D01*
Y-329055D01*
X395951D01*
Y-329087D01*
Y-329119D01*
X395919D01*
Y-329151D01*
X395886D01*
Y-329184D01*
X395854D01*
Y-329216D01*
Y-329248D01*
X395822D01*
Y-329280D01*
X395790D01*
Y-329313D01*
X395758D01*
Y-329345D01*
X395725D01*
Y-329377D01*
X395693D01*
Y-329410D01*
X395661D01*
Y-329442D01*
X395628D01*
Y-329474D01*
X395596D01*
Y-329506D01*
X395532D01*
Y-329538D01*
X395499D01*
Y-329571D01*
X395467D01*
Y-329603D01*
X395403D01*
Y-329635D01*
X395370D01*
Y-329667D01*
X395306D01*
Y-329700D01*
X395274D01*
Y-329732D01*
X395209D01*
Y-329764D01*
X395145D01*
Y-329797D01*
X395080D01*
Y-329829D01*
X394983D01*
Y-329861D01*
X394919D01*
Y-329893D01*
X394790D01*
Y-329926D01*
X394693D01*
Y-329958D01*
X394499D01*
Y-329990D01*
X389628D01*
Y-330022D01*
X389370D01*
Y-330055D01*
X389241D01*
Y-330087D01*
X389112D01*
Y-330119D01*
X389047D01*
Y-330152D01*
X388950D01*
Y-330184D01*
X388886D01*
Y-330216D01*
X388821D01*
Y-330248D01*
X388757D01*
Y-330280D01*
X388692D01*
Y-330313D01*
X388660D01*
Y-330345D01*
X388595D01*
Y-330377D01*
X388531D01*
Y-330410D01*
X388499D01*
Y-330442D01*
X388466D01*
Y-330474D01*
X388434D01*
Y-330506D01*
X388369D01*
Y-330539D01*
X388337D01*
Y-330571D01*
X388305D01*
Y-330603D01*
X388273D01*
Y-330635D01*
X388241D01*
Y-330668D01*
X388208D01*
Y-330700D01*
X388176D01*
Y-330732D01*
X388144D01*
Y-330764D01*
Y-330797D01*
X388111D01*
Y-330829D01*
X388079D01*
Y-330861D01*
X388047D01*
Y-330893D01*
Y-330926D01*
X388015D01*
Y-330958D01*
X387982D01*
Y-330990D01*
Y-331023D01*
X387950D01*
Y-331055D01*
X387918D01*
Y-331087D01*
Y-331119D01*
X387886D01*
Y-331152D01*
Y-331184D01*
X387853D01*
Y-331216D01*
Y-331248D01*
X387821D01*
Y-331281D01*
Y-331313D01*
Y-331345D01*
X387789D01*
Y-331377D01*
Y-331410D01*
X387757D01*
Y-331442D01*
Y-331474D01*
Y-331506D01*
X387724D01*
Y-331539D01*
Y-331571D01*
Y-331603D01*
Y-331635D01*
X387692D01*
Y-331668D01*
Y-331700D01*
Y-331732D01*
Y-331765D01*
Y-331797D01*
Y-331829D01*
X387660D01*
Y-331861D01*
Y-331894D01*
Y-331926D01*
Y-331958D01*
Y-331990D01*
Y-332023D01*
Y-332055D01*
Y-332087D01*
Y-332119D01*
Y-332152D01*
Y-332184D01*
Y-332216D01*
Y-332248D01*
Y-332281D01*
Y-332313D01*
Y-332345D01*
X387692D01*
Y-332378D01*
Y-332410D01*
Y-332442D01*
Y-332474D01*
Y-332507D01*
Y-332539D01*
X387724D01*
Y-332571D01*
Y-332603D01*
Y-332636D01*
Y-332668D01*
X387757D01*
Y-332700D01*
Y-332732D01*
Y-332765D01*
X387789D01*
Y-332797D01*
Y-332829D01*
Y-332861D01*
X387821D01*
Y-332894D01*
Y-332926D01*
X387853D01*
Y-332958D01*
Y-332991D01*
X387886D01*
Y-333023D01*
Y-333055D01*
X387918D01*
Y-333087D01*
Y-333120D01*
X387950D01*
Y-333152D01*
Y-333184D01*
X387982D01*
Y-333216D01*
X388015D01*
Y-333249D01*
Y-333281D01*
X388047D01*
Y-333313D01*
X388079D01*
Y-333345D01*
Y-333378D01*
X388111D01*
Y-333410D01*
X388144D01*
Y-333442D01*
X388176D01*
Y-333474D01*
X388208D01*
Y-333507D01*
X388241D01*
Y-333539D01*
X388273D01*
Y-333571D01*
X388305D01*
Y-333604D01*
X388337D01*
Y-333636D01*
X388369D01*
Y-333668D01*
X388402D01*
Y-333700D01*
X388434D01*
Y-333733D01*
X388466D01*
Y-333765D01*
X388531D01*
Y-333797D01*
X388563D01*
Y-333829D01*
X388628D01*
Y-333862D01*
X388660D01*
Y-333894D01*
X388724D01*
Y-333926D01*
X388789D01*
Y-333958D01*
X388854D01*
Y-333991D01*
X388918D01*
Y-334023D01*
X388983D01*
Y-334055D01*
X389079D01*
Y-334087D01*
X389176D01*
Y-334120D01*
X389305D01*
Y-334152D01*
X389466D01*
Y-334184D01*
X414986D01*
Y-334216D01*
X415018D01*
Y-334184D01*
X415050D01*
Y-334216D01*
X415276D01*
Y-334249D01*
X415405D01*
Y-334281D01*
X415502D01*
Y-334313D01*
X415598D01*
Y-334346D01*
X415695D01*
Y-334378D01*
X415760D01*
Y-334410D01*
X415824D01*
Y-334442D01*
X415889D01*
Y-334474D01*
X415953D01*
Y-334507D01*
X415986D01*
Y-334539D01*
X416050D01*
Y-334571D01*
X416082D01*
Y-334604D01*
X416147D01*
Y-334636D01*
X416179D01*
Y-334668D01*
X416212D01*
Y-334700D01*
X416244D01*
Y-334733D01*
X416308D01*
Y-334765D01*
X416340D01*
Y-334797D01*
X416373D01*
Y-334829D01*
X416405D01*
Y-334862D01*
X416437D01*
Y-334894D01*
X416470D01*
Y-334926D01*
Y-334959D01*
X416502D01*
Y-334991D01*
X416534D01*
Y-335023D01*
X416566D01*
Y-335055D01*
X416599D01*
Y-335087D01*
Y-335120D01*
X416631D01*
Y-335152D01*
X416663D01*
Y-335184D01*
Y-335217D01*
X416695D01*
Y-335249D01*
X416728D01*
Y-335281D01*
Y-335313D01*
X416760D01*
Y-335346D01*
Y-335378D01*
X416792D01*
Y-335410D01*
Y-335442D01*
X416824D01*
Y-335475D01*
Y-335507D01*
Y-335539D01*
X416857D01*
Y-335572D01*
Y-335604D01*
X416889D01*
Y-335636D01*
Y-335668D01*
Y-335700D01*
X416921D01*
Y-335733D01*
Y-335765D01*
Y-335797D01*
Y-335830D01*
X416954D01*
Y-335862D01*
Y-335894D01*
Y-335926D01*
Y-335959D01*
Y-335991D01*
X416986D01*
Y-336023D01*
Y-336055D01*
Y-336088D01*
Y-336120D01*
Y-336152D01*
Y-336184D01*
Y-336217D01*
Y-336249D01*
Y-336281D01*
Y-336314D01*
Y-336346D01*
Y-336378D01*
Y-336410D01*
Y-336442D01*
Y-336475D01*
Y-336507D01*
Y-336539D01*
Y-336572D01*
Y-336604D01*
X416954D01*
Y-336636D01*
Y-336668D01*
Y-336701D01*
Y-336733D01*
Y-336765D01*
X416921D01*
Y-336797D01*
Y-336830D01*
Y-336862D01*
Y-336894D01*
X416889D01*
Y-336927D01*
Y-336959D01*
Y-336991D01*
X416857D01*
Y-337023D01*
Y-337055D01*
Y-337088D01*
X416824D01*
Y-337120D01*
Y-337152D01*
X416792D01*
Y-337185D01*
Y-337217D01*
X416760D01*
Y-337249D01*
Y-337281D01*
X416728D01*
Y-337314D01*
Y-337346D01*
X416695D01*
Y-337378D01*
Y-337410D01*
X416663D01*
Y-337443D01*
X416631D01*
Y-337475D01*
Y-337507D01*
X416599D01*
Y-337539D01*
X416566D01*
Y-337572D01*
X416534D01*
Y-337604D01*
X416502D01*
Y-337636D01*
Y-337668D01*
X416470D01*
Y-337701D01*
X416437D01*
Y-337733D01*
X416405D01*
Y-337765D01*
X416373D01*
Y-337797D01*
X416340D01*
Y-337830D01*
X416308D01*
Y-337862D01*
X416276D01*
Y-337894D01*
X416244D01*
Y-337927D01*
X416179D01*
Y-337959D01*
X416147D01*
Y-337991D01*
X416115D01*
Y-338023D01*
X416050D01*
Y-338056D01*
X416018D01*
Y-338088D01*
X415953D01*
Y-338120D01*
X415889D01*
Y-338152D01*
X415857D01*
Y-338185D01*
X415760D01*
Y-338217D01*
X415695D01*
Y-338249D01*
X415631D01*
Y-338281D01*
X415534D01*
Y-338314D01*
X415437D01*
Y-338346D01*
X415308D01*
Y-338378D01*
X415115D01*
Y-338410D01*
X398371D01*
Y-338443D01*
X398177D01*
Y-338475D01*
X398048D01*
Y-338507D01*
X397919D01*
Y-338540D01*
X397854D01*
Y-338572D01*
X397758D01*
Y-338604D01*
X397693D01*
Y-338636D01*
X397629D01*
Y-338669D01*
X397564D01*
Y-338701D01*
X397500D01*
Y-338733D01*
X397467D01*
Y-338765D01*
X397403D01*
Y-338798D01*
X397371D01*
Y-338830D01*
X397338D01*
Y-338862D01*
X397274D01*
Y-338894D01*
X397241D01*
Y-338927D01*
X397209D01*
Y-338959D01*
X397177D01*
Y-338991D01*
X397145D01*
Y-339023D01*
X397112D01*
Y-339056D01*
X397080D01*
Y-339088D01*
X397048D01*
Y-339120D01*
X397016D01*
Y-339153D01*
X396983D01*
Y-339185D01*
X396951D01*
Y-339217D01*
X396919D01*
Y-339249D01*
Y-339282D01*
X396887D01*
Y-339314D01*
X396854D01*
Y-339346D01*
Y-339378D01*
X396822D01*
Y-339411D01*
X396790D01*
Y-339443D01*
Y-339475D01*
X396758D01*
Y-339507D01*
Y-339540D01*
X396725D01*
Y-339572D01*
Y-339604D01*
X396693D01*
Y-339636D01*
Y-339669D01*
X396661D01*
Y-339701D01*
Y-339733D01*
X396629D01*
Y-339766D01*
Y-339798D01*
Y-339830D01*
X396596D01*
Y-339862D01*
Y-339895D01*
Y-339927D01*
X396564D01*
Y-339959D01*
Y-339991D01*
Y-340024D01*
Y-340056D01*
X396532D01*
Y-340088D01*
Y-340120D01*
Y-340153D01*
Y-340185D01*
Y-340217D01*
Y-340249D01*
X396499D01*
Y-340282D01*
Y-340314D01*
Y-340346D01*
Y-340378D01*
Y-340411D01*
Y-340443D01*
Y-340475D01*
Y-340508D01*
Y-340540D01*
Y-340572D01*
Y-340604D01*
Y-340637D01*
Y-340669D01*
Y-340701D01*
Y-340733D01*
Y-340766D01*
X396532D01*
Y-340798D01*
Y-340830D01*
Y-340862D01*
Y-340895D01*
Y-340927D01*
Y-340959D01*
X396564D01*
Y-340991D01*
Y-341024D01*
Y-341056D01*
Y-341088D01*
X396596D01*
Y-341121D01*
Y-341153D01*
Y-341185D01*
X396629D01*
Y-341217D01*
Y-341249D01*
Y-341282D01*
X396661D01*
Y-341314D01*
Y-341346D01*
X396693D01*
Y-341379D01*
Y-341411D01*
X396725D01*
Y-341443D01*
Y-341475D01*
X396758D01*
Y-341508D01*
Y-341540D01*
X396790D01*
Y-341572D01*
Y-341604D01*
X396822D01*
Y-341637D01*
X396854D01*
Y-341669D01*
Y-341701D01*
X396887D01*
Y-341734D01*
X396919D01*
Y-341766D01*
X396951D01*
Y-341798D01*
Y-341830D01*
X396983D01*
Y-341863D01*
X397016D01*
Y-341895D01*
X397048D01*
Y-341927D01*
X397080D01*
Y-341959D01*
X397112D01*
Y-341992D01*
X397145D01*
Y-342024D01*
X397177D01*
Y-342056D01*
X397209D01*
Y-342088D01*
X397241D01*
Y-342121D01*
X397306D01*
Y-342153D01*
X397338D01*
Y-342185D01*
X397371D01*
Y-342217D01*
X397435D01*
Y-342250D01*
X397467D01*
Y-342282D01*
X397532D01*
Y-342314D01*
X397596D01*
Y-342346D01*
X397629D01*
Y-342379D01*
X397693D01*
Y-342411D01*
X397790D01*
Y-342443D01*
X397854D01*
Y-342476D01*
X397951D01*
Y-342508D01*
X398048D01*
Y-342540D01*
X398177D01*
Y-342572D01*
X398403D01*
Y-342604D01*
X404597D01*
Y-342637D01*
X404759D01*
Y-342669D01*
X404888D01*
Y-342701D01*
X404984D01*
Y-342734D01*
X405081D01*
Y-342766D01*
X405178D01*
Y-342798D01*
X405242D01*
Y-342830D01*
X405307D01*
Y-342863D01*
X405372D01*
Y-342895D01*
X405436D01*
Y-342927D01*
X405468D01*
Y-342959D01*
X405533D01*
Y-342992D01*
X405565D01*
Y-343024D01*
X405597D01*
Y-343056D01*
X405662D01*
Y-343089D01*
X405694D01*
Y-343121D01*
X405726D01*
Y-343153D01*
X405759D01*
Y-343185D01*
X405791D01*
Y-343217D01*
X405823D01*
Y-343250D01*
X405855D01*
Y-343282D01*
X405888D01*
Y-343314D01*
X405920D01*
Y-343347D01*
X405952D01*
Y-343379D01*
X405984D01*
Y-343411D01*
X406017D01*
Y-343443D01*
Y-343476D01*
X406049D01*
Y-343508D01*
X406081D01*
Y-343540D01*
X406113D01*
Y-343572D01*
Y-343605D01*
X406146D01*
Y-343637D01*
Y-343669D01*
X406178D01*
Y-343701D01*
X406210D01*
Y-343734D01*
Y-343766D01*
X406243D01*
Y-343798D01*
Y-343830D01*
X406275D01*
Y-343863D01*
Y-343895D01*
Y-343927D01*
X406307D01*
Y-343959D01*
Y-343992D01*
X406339D01*
Y-344024D01*
Y-344056D01*
Y-344089D01*
X406372D01*
Y-344121D01*
Y-344153D01*
Y-344185D01*
Y-344218D01*
X406404D01*
Y-344250D01*
Y-344282D01*
Y-344314D01*
Y-344347D01*
Y-344379D01*
X406436D01*
Y-344411D01*
Y-344443D01*
Y-344476D01*
Y-344508D01*
Y-344540D01*
Y-344572D01*
Y-344605D01*
Y-344637D01*
Y-344669D01*
Y-344702D01*
Y-344734D01*
Y-344766D01*
Y-344798D01*
Y-344831D01*
Y-344863D01*
Y-344895D01*
Y-344927D01*
Y-344960D01*
Y-344992D01*
Y-345024D01*
Y-345056D01*
X406404D01*
Y-345089D01*
Y-345121D01*
Y-345153D01*
Y-345185D01*
Y-345218D01*
X406372D01*
Y-345250D01*
Y-345282D01*
Y-345315D01*
X406339D01*
Y-345347D01*
Y-345379D01*
Y-345411D01*
X406307D01*
Y-345444D01*
Y-345476D01*
Y-345508D01*
X406275D01*
Y-345540D01*
Y-345573D01*
X406243D01*
Y-345605D01*
Y-345637D01*
X406210D01*
Y-345669D01*
Y-345702D01*
X406178D01*
Y-345734D01*
Y-345766D01*
X406146D01*
Y-345798D01*
Y-345831D01*
X406113D01*
Y-345863D01*
X406081D01*
Y-345895D01*
Y-345928D01*
X406049D01*
Y-345960D01*
X406017D01*
Y-345992D01*
X405984D01*
Y-346024D01*
X405952D01*
Y-346057D01*
Y-346089D01*
X405920D01*
Y-346121D01*
X405888D01*
Y-346153D01*
X405855D01*
Y-346186D01*
X405823D01*
Y-346218D01*
X405791D01*
Y-346250D01*
X405759D01*
Y-346282D01*
X405726D01*
Y-346315D01*
X405662D01*
Y-346347D01*
X405630D01*
Y-346379D01*
X405597D01*
Y-346411D01*
X405533D01*
Y-346444D01*
X405501D01*
Y-346476D01*
X405436D01*
Y-346508D01*
X405404D01*
Y-346540D01*
X405339D01*
Y-346573D01*
X405275D01*
Y-346605D01*
X405210D01*
Y-346637D01*
X405146D01*
Y-346670D01*
X405049D01*
Y-346702D01*
X404952D01*
Y-346734D01*
X404855D01*
Y-346766D01*
X404694D01*
Y-346799D01*
X404468D01*
Y-346831D01*
X404404D01*
Y-346799D01*
X404371D01*
Y-346831D01*
X394693D01*
Y-346799D01*
X394661D01*
Y-346831D01*
X394338D01*
Y-346863D01*
X394177D01*
Y-346895D01*
X394048D01*
Y-346928D01*
X393951D01*
Y-346960D01*
X393886D01*
Y-346992D01*
X393790D01*
Y-347024D01*
X393725D01*
Y-347057D01*
X393660D01*
Y-347089D01*
X393628D01*
Y-347121D01*
X393564D01*
Y-347153D01*
X393499D01*
Y-347186D01*
X393467D01*
Y-347218D01*
X393402D01*
Y-347250D01*
X393370D01*
Y-347283D01*
X393338D01*
Y-347315D01*
X393306D01*
Y-347347D01*
X393241D01*
Y-347379D01*
X393209D01*
Y-347411D01*
X393177D01*
Y-347444D01*
X393144D01*
Y-347476D01*
X393112D01*
Y-347508D01*
X393080D01*
Y-347541D01*
Y-347573D01*
X393047D01*
Y-347605D01*
X393015D01*
Y-347637D01*
X392983D01*
Y-347670D01*
X392951D01*
Y-347702D01*
Y-347734D01*
X392918D01*
Y-347766D01*
X392886D01*
Y-347799D01*
Y-347831D01*
X392854D01*
Y-347863D01*
X392822D01*
Y-347896D01*
Y-347928D01*
X392789D01*
Y-347960D01*
Y-347992D01*
X392757D01*
Y-348025D01*
Y-348057D01*
X392725D01*
Y-348089D01*
Y-348121D01*
X392693D01*
Y-348154D01*
Y-348186D01*
Y-348218D01*
X392660D01*
Y-348250D01*
Y-348283D01*
Y-348315D01*
X392628D01*
Y-348347D01*
Y-348379D01*
Y-348412D01*
X392596D01*
Y-348444D01*
Y-348476D01*
Y-348508D01*
Y-348541D01*
Y-348573D01*
X392564D01*
Y-348605D01*
Y-348638D01*
Y-348670D01*
Y-348702D01*
Y-348734D01*
Y-348766D01*
Y-348799D01*
Y-348831D01*
Y-348863D01*
Y-348896D01*
Y-348928D01*
Y-348960D01*
Y-348992D01*
Y-349025D01*
Y-349057D01*
Y-349089D01*
Y-349121D01*
Y-349154D01*
Y-349186D01*
Y-349218D01*
Y-349251D01*
X392596D01*
Y-349283D01*
Y-349315D01*
Y-349347D01*
Y-349379D01*
Y-349412D01*
X392628D01*
Y-349444D01*
Y-349476D01*
Y-349509D01*
X392660D01*
Y-349541D01*
Y-349573D01*
Y-349605D01*
X392693D01*
Y-349638D01*
Y-349670D01*
Y-349702D01*
X392725D01*
Y-349734D01*
Y-349767D01*
X392757D01*
Y-349799D01*
Y-349831D01*
X392789D01*
Y-349863D01*
Y-349896D01*
X392822D01*
Y-349928D01*
Y-349960D01*
X392854D01*
Y-349992D01*
Y-350025D01*
X392886D01*
Y-350057D01*
X392918D01*
Y-350089D01*
Y-350121D01*
X392951D01*
Y-350154D01*
X392983D01*
Y-350186D01*
X393015D01*
Y-350218D01*
Y-350251D01*
X393047D01*
Y-350283D01*
X393080D01*
Y-350315D01*
X393112D01*
Y-350347D01*
X393144D01*
Y-350380D01*
X393177D01*
Y-350412D01*
X393209D01*
Y-350444D01*
X393241D01*
Y-350476D01*
X393273D01*
Y-350509D01*
X393306D01*
Y-350541D01*
X393370D01*
Y-350573D01*
X393402D01*
Y-350606D01*
X393435D01*
Y-350638D01*
X393499D01*
Y-350670D01*
X393531D01*
Y-350702D01*
X393596D01*
Y-350734D01*
X393660D01*
Y-350767D01*
X393725D01*
Y-350799D01*
X393790D01*
Y-350831D01*
X393854D01*
Y-350864D01*
X393951D01*
Y-350896D01*
X394015D01*
Y-350928D01*
X394144D01*
Y-350960D01*
X394306D01*
Y-350993D01*
X394596D01*
Y-351025D01*
X401274D01*
Y-351057D01*
X401436D01*
Y-351089D01*
X401532D01*
Y-351122D01*
X401629D01*
Y-351154D01*
X401726D01*
Y-351186D01*
X401823D01*
Y-351218D01*
X401887D01*
Y-351251D01*
X401952D01*
Y-351283D01*
X401984D01*
Y-351315D01*
X402048D01*
Y-351347D01*
X402113D01*
Y-351380D01*
X402145D01*
Y-351412D01*
X402210D01*
Y-351444D01*
X402242D01*
Y-351477D01*
X402274D01*
Y-351509D01*
X402307D01*
Y-351541D01*
X402371D01*
Y-351573D01*
X402403D01*
Y-351606D01*
X402436D01*
Y-351638D01*
X402468D01*
Y-351670D01*
X402500D01*
Y-351702D01*
X402532D01*
Y-351735D01*
Y-351767D01*
X402565D01*
Y-351799D01*
X402597D01*
Y-351831D01*
X402629D01*
Y-351864D01*
X402662D01*
Y-351896D01*
Y-351928D01*
X402694D01*
Y-351960D01*
X402726D01*
Y-351993D01*
Y-352025D01*
X402758D01*
Y-352057D01*
X402791D01*
Y-352090D01*
Y-352122D01*
X402823D01*
Y-352154D01*
Y-352186D01*
X402855D01*
Y-352219D01*
Y-352251D01*
X402887D01*
Y-352283D01*
Y-352315D01*
X402920D01*
Y-352348D01*
Y-352380D01*
Y-352412D01*
X402952D01*
Y-352444D01*
Y-352477D01*
Y-352509D01*
X402984D01*
Y-352541D01*
Y-352573D01*
Y-352606D01*
X403016D01*
Y-352638D01*
Y-352670D01*
Y-352702D01*
Y-352735D01*
Y-352767D01*
Y-352799D01*
X403049D01*
Y-352832D01*
Y-352864D01*
Y-352896D01*
Y-352928D01*
Y-352961D01*
Y-352993D01*
Y-353025D01*
Y-353057D01*
Y-353090D01*
X403081D01*
Y-353122D01*
Y-353154D01*
X403049D01*
Y-353186D01*
Y-353219D01*
Y-353251D01*
Y-353283D01*
Y-353315D01*
Y-353348D01*
Y-353380D01*
Y-353412D01*
Y-353445D01*
Y-353477D01*
X403016D01*
Y-353509D01*
Y-353541D01*
Y-353573D01*
Y-353606D01*
Y-353638D01*
X402984D01*
Y-353670D01*
Y-353703D01*
Y-353735D01*
X402952D01*
Y-353767D01*
Y-353799D01*
Y-353832D01*
X402920D01*
Y-353864D01*
Y-353896D01*
Y-353928D01*
X402887D01*
Y-353961D01*
Y-353993D01*
Y-354025D01*
X402855D01*
Y-354058D01*
Y-354090D01*
X402823D01*
Y-354122D01*
Y-354154D01*
X402791D01*
Y-354187D01*
Y-354219D01*
X402758D01*
Y-354251D01*
X402726D01*
Y-354283D01*
Y-354316D01*
X402694D01*
Y-354348D01*
X402662D01*
Y-354380D01*
Y-354412D01*
X402629D01*
Y-354445D01*
X402597D01*
Y-354477D01*
X402565D01*
Y-354509D01*
Y-354541D01*
X402532D01*
Y-354574D01*
X402500D01*
Y-354606D01*
X402468D01*
Y-354638D01*
X402436D01*
Y-354670D01*
X402403D01*
Y-354703D01*
X402371D01*
Y-354735D01*
X402339D01*
Y-354767D01*
X402307D01*
Y-354800D01*
X402274D01*
Y-354832D01*
X402242D01*
Y-354864D01*
X402178D01*
Y-354896D01*
X402145D01*
Y-354928D01*
X402113D01*
Y-354961D01*
X402048D01*
Y-354993D01*
X402016D01*
Y-355025D01*
X401952D01*
Y-355058D01*
X401887D01*
Y-355090D01*
X401823D01*
Y-355122D01*
X401758D01*
Y-355154D01*
X401661D01*
Y-355187D01*
X401532D01*
Y-355219D01*
X378304D01*
Y-355251D01*
X378239D01*
Y-355283D01*
X378207D01*
Y-355316D01*
X378175D01*
Y-355348D01*
X378143D01*
Y-355380D01*
Y-355413D01*
X378110D01*
Y-355445D01*
Y-355477D01*
Y-355509D01*
Y-355541D01*
Y-355574D01*
Y-355606D01*
Y-355638D01*
Y-355671D01*
Y-355703D01*
Y-355735D01*
Y-355767D01*
Y-355800D01*
Y-355832D01*
Y-355864D01*
Y-355896D01*
Y-355929D01*
Y-355961D01*
Y-355993D01*
Y-356025D01*
Y-356058D01*
Y-356090D01*
Y-356122D01*
Y-356154D01*
Y-356187D01*
Y-356219D01*
Y-356251D01*
Y-356283D01*
Y-356316D01*
Y-356348D01*
Y-356380D01*
Y-356413D01*
Y-356445D01*
Y-356477D01*
Y-356509D01*
Y-356542D01*
Y-356574D01*
Y-356606D01*
Y-356638D01*
Y-356671D01*
Y-356703D01*
Y-356735D01*
Y-356768D01*
Y-356800D01*
Y-356832D01*
Y-356864D01*
Y-356896D01*
Y-356929D01*
Y-356961D01*
Y-356993D01*
Y-357026D01*
Y-357058D01*
Y-357090D01*
Y-357122D01*
Y-357155D01*
Y-357187D01*
Y-357219D01*
Y-357251D01*
Y-357284D01*
Y-357316D01*
Y-357348D01*
Y-357380D01*
Y-357413D01*
Y-357445D01*
Y-357477D01*
Y-357509D01*
Y-357542D01*
Y-357574D01*
Y-357606D01*
Y-357639D01*
Y-357671D01*
Y-357703D01*
Y-357735D01*
Y-357768D01*
Y-357800D01*
Y-357832D01*
Y-357864D01*
Y-357897D01*
Y-357929D01*
Y-357961D01*
Y-357993D01*
Y-358026D01*
Y-358058D01*
Y-358090D01*
Y-358122D01*
Y-358155D01*
Y-358187D01*
Y-358219D01*
Y-358252D01*
Y-358284D01*
Y-358316D01*
Y-358348D01*
Y-358381D01*
Y-358413D01*
Y-358445D01*
Y-358477D01*
Y-358510D01*
Y-358542D01*
Y-358574D01*
Y-358606D01*
X378078D01*
Y-358639D01*
Y-358671D01*
X378046D01*
Y-358703D01*
Y-358735D01*
X378013D01*
Y-358768D01*
X377949D01*
Y-358800D01*
X377885D01*
Y-358832D01*
X371723D01*
Y-358800D01*
X371626D01*
Y-358768D01*
X371593D01*
Y-358735D01*
X371561D01*
Y-358703D01*
X371529D01*
Y-358671D01*
Y-358639D01*
X371497D01*
Y-358606D01*
Y-358574D01*
Y-358542D01*
Y-358510D01*
Y-358477D01*
Y-358445D01*
Y-358413D01*
Y-358381D01*
Y-358348D01*
Y-358316D01*
Y-358284D01*
Y-358252D01*
Y-358219D01*
Y-358187D01*
Y-358155D01*
Y-358122D01*
Y-358090D01*
Y-358058D01*
Y-358026D01*
Y-357993D01*
Y-357961D01*
Y-357929D01*
Y-357897D01*
Y-357864D01*
Y-357832D01*
Y-357800D01*
Y-357768D01*
Y-357735D01*
Y-357703D01*
Y-357671D01*
Y-357639D01*
Y-357606D01*
Y-357574D01*
Y-357542D01*
Y-357509D01*
Y-357477D01*
Y-357445D01*
Y-357413D01*
Y-357380D01*
Y-357348D01*
Y-357316D01*
Y-357284D01*
Y-357251D01*
Y-357219D01*
Y-357187D01*
Y-357155D01*
Y-357122D01*
Y-357090D01*
Y-357058D01*
Y-357026D01*
Y-356993D01*
Y-356961D01*
Y-356929D01*
Y-356896D01*
Y-356864D01*
Y-356832D01*
Y-356800D01*
Y-356768D01*
Y-356735D01*
Y-356703D01*
Y-356671D01*
X371464D01*
Y-356638D01*
Y-356606D01*
Y-356574D01*
X371432D01*
Y-356542D01*
Y-356509D01*
X371400D01*
Y-356477D01*
X371335D01*
Y-356445D01*
X371238D01*
Y-356413D01*
X371142D01*
Y-356445D01*
X371045D01*
Y-356477D01*
X371013D01*
Y-356509D01*
X370981D01*
Y-356542D01*
X370948D01*
Y-356574D01*
X370916D01*
Y-356606D01*
Y-356638D01*
Y-356671D01*
Y-356703D01*
X370884D01*
Y-356735D01*
Y-356768D01*
Y-356800D01*
Y-356832D01*
Y-356864D01*
Y-356896D01*
Y-356929D01*
Y-356961D01*
Y-356993D01*
Y-357026D01*
Y-357058D01*
Y-357090D01*
Y-357122D01*
Y-357155D01*
Y-357187D01*
Y-357219D01*
Y-357251D01*
Y-357284D01*
Y-357316D01*
Y-357348D01*
Y-357380D01*
Y-357413D01*
Y-357445D01*
Y-357477D01*
Y-357509D01*
Y-357542D01*
Y-357574D01*
Y-357606D01*
Y-357639D01*
Y-357671D01*
Y-357703D01*
Y-357735D01*
Y-357768D01*
Y-357800D01*
Y-357832D01*
Y-357864D01*
Y-357897D01*
Y-357929D01*
Y-357961D01*
Y-357993D01*
Y-358026D01*
Y-358058D01*
Y-358090D01*
Y-358122D01*
Y-358155D01*
Y-358187D01*
Y-358219D01*
Y-358252D01*
Y-358284D01*
Y-358316D01*
Y-358348D01*
Y-358381D01*
Y-358413D01*
Y-358445D01*
Y-358477D01*
Y-358510D01*
Y-358542D01*
Y-358574D01*
Y-358606D01*
Y-358639D01*
Y-358671D01*
X370851D01*
Y-358703D01*
X370819D01*
Y-358735D01*
X370787D01*
Y-358768D01*
X370755D01*
Y-358800D01*
X370658D01*
Y-358832D01*
X367496D01*
Y-358800D01*
X367432D01*
Y-358768D01*
X367367D01*
Y-358735D01*
X367335D01*
Y-358703D01*
Y-358671D01*
X367303D01*
Y-358639D01*
Y-358606D01*
Y-358574D01*
X367270D01*
Y-358542D01*
Y-358510D01*
Y-358477D01*
Y-358445D01*
Y-358413D01*
Y-358381D01*
Y-358348D01*
Y-358316D01*
Y-358284D01*
Y-358252D01*
Y-358219D01*
Y-358187D01*
Y-358155D01*
Y-358122D01*
Y-358090D01*
Y-358058D01*
Y-358026D01*
Y-357993D01*
Y-357961D01*
Y-357929D01*
Y-357897D01*
Y-357864D01*
Y-357832D01*
Y-357800D01*
Y-357768D01*
Y-357735D01*
Y-357703D01*
Y-357671D01*
Y-357639D01*
Y-357606D01*
Y-357574D01*
Y-357542D01*
Y-357509D01*
Y-357477D01*
Y-357445D01*
Y-357413D01*
Y-357380D01*
Y-357348D01*
Y-357316D01*
Y-357284D01*
Y-357251D01*
Y-357219D01*
Y-357187D01*
Y-357155D01*
Y-357122D01*
Y-357090D01*
Y-357058D01*
Y-357026D01*
Y-356993D01*
Y-356961D01*
Y-356929D01*
Y-356896D01*
Y-356864D01*
Y-356832D01*
Y-356800D01*
Y-356768D01*
Y-356735D01*
Y-356703D01*
Y-356671D01*
Y-356638D01*
Y-356606D01*
Y-356574D01*
Y-356542D01*
Y-356509D01*
Y-356477D01*
Y-356445D01*
Y-356413D01*
Y-356380D01*
Y-356348D01*
Y-356316D01*
Y-356283D01*
Y-356251D01*
Y-356219D01*
Y-356187D01*
Y-356154D01*
Y-356122D01*
Y-356090D01*
Y-356058D01*
Y-356025D01*
Y-355993D01*
Y-355961D01*
X367303D01*
Y-355929D01*
X367270D01*
Y-355896D01*
Y-355864D01*
Y-355832D01*
Y-355800D01*
Y-355767D01*
Y-355735D01*
Y-355703D01*
Y-355671D01*
Y-355638D01*
X367238D01*
Y-355606D01*
Y-355574D01*
X367206D01*
Y-355541D01*
Y-355509D01*
X367174D01*
Y-355477D01*
Y-355445D01*
X367141D01*
Y-355413D01*
X367109D01*
Y-355380D01*
X367077D01*
Y-355348D01*
X367044D01*
Y-355316D01*
X366980D01*
Y-355283D01*
X366915D01*
Y-355251D01*
X366819D01*
Y-355219D01*
X366561D01*
Y-355251D01*
X366464D01*
Y-355283D01*
X366399D01*
Y-355316D01*
X366335D01*
Y-355348D01*
X366302D01*
Y-355380D01*
X366270D01*
Y-355413D01*
X366238D01*
Y-355445D01*
X366206D01*
Y-355477D01*
X366173D01*
Y-355509D01*
Y-355541D01*
X366141D01*
Y-355574D01*
Y-355606D01*
X366109D01*
Y-355638D01*
Y-355671D01*
Y-355703D01*
Y-355735D01*
Y-355767D01*
Y-355800D01*
X366077D01*
Y-355832D01*
X366109D01*
Y-355864D01*
Y-355896D01*
X366077D01*
Y-355929D01*
X366109D01*
Y-355961D01*
Y-355993D01*
Y-356025D01*
Y-356058D01*
Y-356090D01*
Y-356122D01*
Y-356154D01*
Y-356187D01*
Y-356219D01*
Y-356251D01*
Y-356283D01*
Y-356316D01*
Y-356348D01*
Y-356380D01*
Y-356413D01*
Y-356445D01*
Y-356477D01*
Y-356509D01*
Y-356542D01*
Y-356574D01*
Y-356606D01*
Y-356638D01*
Y-356671D01*
Y-356703D01*
Y-356735D01*
Y-356768D01*
Y-356800D01*
Y-356832D01*
Y-356864D01*
Y-356896D01*
Y-356929D01*
Y-356961D01*
Y-356993D01*
Y-357026D01*
Y-357058D01*
Y-357090D01*
Y-357122D01*
Y-357155D01*
Y-357187D01*
Y-357219D01*
Y-357251D01*
Y-357284D01*
Y-357316D01*
X366077D01*
Y-357348D01*
Y-357380D01*
Y-357413D01*
Y-357445D01*
X366044D01*
Y-357477D01*
X366012D01*
Y-357509D01*
X365980D01*
Y-357542D01*
X365948D01*
Y-357574D01*
X365851D01*
Y-357606D01*
X363915D01*
Y-357574D01*
X363818D01*
Y-357542D01*
X363786D01*
Y-357509D01*
X363754D01*
Y-357477D01*
X363721D01*
Y-357445D01*
X363689D01*
Y-357413D01*
Y-357380D01*
Y-357348D01*
X363657D01*
Y-357316D01*
Y-357284D01*
Y-357251D01*
Y-357219D01*
Y-357187D01*
Y-357155D01*
Y-357122D01*
Y-357090D01*
Y-357058D01*
Y-357026D01*
Y-356993D01*
Y-356961D01*
Y-356929D01*
Y-356896D01*
Y-356864D01*
Y-356832D01*
Y-356800D01*
Y-356768D01*
Y-356735D01*
Y-356703D01*
Y-356671D01*
Y-356638D01*
Y-356606D01*
Y-356574D01*
Y-356542D01*
Y-356509D01*
Y-356477D01*
Y-356445D01*
Y-356413D01*
Y-356380D01*
Y-356348D01*
Y-356316D01*
Y-356283D01*
Y-356251D01*
Y-356219D01*
Y-356187D01*
Y-356154D01*
Y-356122D01*
Y-356090D01*
Y-356058D01*
Y-356025D01*
Y-355993D01*
Y-355961D01*
Y-355929D01*
Y-355896D01*
Y-355864D01*
Y-355832D01*
Y-355800D01*
Y-355767D01*
Y-355735D01*
Y-355703D01*
X363689D01*
Y-355671D01*
Y-355638D01*
X363657D01*
Y-355606D01*
X363689D01*
Y-355574D01*
X363657D01*
Y-355541D01*
Y-355509D01*
Y-355477D01*
Y-355445D01*
Y-355413D01*
Y-355380D01*
X363625D01*
Y-355348D01*
Y-355316D01*
X363593D01*
Y-355283D01*
X363528D01*
Y-355251D01*
X363463D01*
Y-355219D01*
X358463D01*
Y-355251D01*
X358398D01*
Y-355283D01*
X358366D01*
Y-355316D01*
X358334D01*
Y-355348D01*
X358302D01*
Y-355380D01*
Y-355413D01*
X358269D01*
Y-355445D01*
Y-355477D01*
Y-355509D01*
Y-355541D01*
Y-355574D01*
Y-355606D01*
Y-355638D01*
Y-355671D01*
Y-355703D01*
Y-355735D01*
Y-355767D01*
Y-355800D01*
Y-355832D01*
Y-355864D01*
Y-355896D01*
Y-355929D01*
Y-355961D01*
Y-355993D01*
Y-356025D01*
Y-356058D01*
Y-356090D01*
Y-356122D01*
Y-356154D01*
Y-356187D01*
Y-356219D01*
Y-356251D01*
Y-356283D01*
Y-356316D01*
Y-356348D01*
Y-356380D01*
Y-356413D01*
Y-356445D01*
Y-356477D01*
Y-356509D01*
Y-356542D01*
Y-356574D01*
Y-356606D01*
Y-356638D01*
Y-356671D01*
Y-356703D01*
Y-356735D01*
Y-356768D01*
Y-356800D01*
Y-356832D01*
Y-356864D01*
Y-356896D01*
Y-356929D01*
Y-356961D01*
Y-356993D01*
Y-357026D01*
Y-357058D01*
Y-357090D01*
Y-357122D01*
Y-357155D01*
Y-357187D01*
Y-357219D01*
Y-357251D01*
Y-357284D01*
Y-357316D01*
Y-357348D01*
Y-357380D01*
Y-357413D01*
Y-357445D01*
Y-357477D01*
Y-357509D01*
Y-357542D01*
Y-357574D01*
Y-357606D01*
Y-357639D01*
Y-357671D01*
Y-357703D01*
Y-357735D01*
Y-357768D01*
Y-357800D01*
Y-357832D01*
Y-357864D01*
Y-357897D01*
Y-357929D01*
Y-357961D01*
Y-357993D01*
Y-358026D01*
Y-358058D01*
Y-358090D01*
Y-358122D01*
Y-358155D01*
Y-358187D01*
Y-358219D01*
X353462D01*
Y-358187D01*
Y-358155D01*
Y-358122D01*
Y-358090D01*
Y-358058D01*
Y-358026D01*
Y-357993D01*
Y-357961D01*
Y-357929D01*
Y-357897D01*
Y-357864D01*
Y-357832D01*
Y-357800D01*
Y-357768D01*
Y-357735D01*
Y-357703D01*
Y-357671D01*
Y-357639D01*
Y-357606D01*
Y-357574D01*
Y-357542D01*
Y-357509D01*
Y-357477D01*
Y-357445D01*
Y-357413D01*
Y-357380D01*
Y-357348D01*
Y-357316D01*
Y-357284D01*
Y-357251D01*
Y-357219D01*
Y-357187D01*
Y-357155D01*
Y-357122D01*
Y-357090D01*
Y-357058D01*
Y-357026D01*
Y-356993D01*
Y-356961D01*
Y-356929D01*
Y-356896D01*
Y-356864D01*
Y-356832D01*
Y-356800D01*
Y-356768D01*
Y-356735D01*
Y-356703D01*
Y-356671D01*
Y-356638D01*
Y-356606D01*
Y-356574D01*
Y-356542D01*
Y-356509D01*
Y-356477D01*
Y-356445D01*
Y-356413D01*
Y-356380D01*
Y-356348D01*
Y-356316D01*
Y-356283D01*
Y-356251D01*
Y-356219D01*
Y-356187D01*
Y-356154D01*
Y-356122D01*
Y-356090D01*
Y-356058D01*
Y-356025D01*
Y-355993D01*
Y-355961D01*
Y-355929D01*
Y-355896D01*
Y-355864D01*
Y-355832D01*
Y-355800D01*
Y-355767D01*
Y-355735D01*
Y-355703D01*
Y-355671D01*
Y-355638D01*
Y-355606D01*
Y-355574D01*
Y-355541D01*
Y-355509D01*
Y-355477D01*
Y-355445D01*
Y-355413D01*
Y-355380D01*
Y-355348D01*
Y-355316D01*
X356592D01*
Y-355283D01*
Y-355251D01*
Y-355219D01*
Y-355187D01*
Y-355154D01*
Y-355122D01*
Y-355090D01*
Y-355058D01*
Y-355025D01*
Y-354993D01*
Y-354961D01*
Y-354928D01*
Y-354896D01*
Y-354864D01*
Y-354832D01*
Y-354800D01*
Y-354767D01*
Y-354735D01*
Y-354703D01*
Y-354670D01*
Y-354638D01*
Y-354606D01*
Y-354574D01*
Y-354541D01*
Y-354509D01*
Y-354477D01*
Y-354445D01*
Y-354412D01*
Y-354380D01*
Y-354348D01*
Y-354316D01*
Y-354283D01*
Y-354251D01*
Y-354219D01*
Y-354187D01*
Y-354154D01*
Y-354122D01*
Y-354090D01*
Y-354058D01*
Y-354025D01*
Y-353993D01*
Y-353961D01*
Y-353928D01*
Y-353896D01*
Y-353864D01*
Y-353832D01*
Y-353799D01*
Y-353767D01*
Y-353735D01*
Y-353703D01*
Y-353670D01*
Y-353638D01*
Y-353606D01*
Y-353573D01*
Y-353541D01*
Y-353509D01*
Y-353477D01*
Y-353445D01*
Y-353412D01*
Y-353380D01*
Y-353348D01*
Y-353315D01*
Y-353283D01*
Y-353251D01*
Y-353219D01*
Y-353186D01*
Y-353154D01*
Y-353122D01*
Y-353090D01*
Y-353057D01*
Y-353025D01*
Y-352993D01*
Y-352961D01*
Y-352928D01*
Y-352896D01*
Y-352864D01*
Y-352832D01*
Y-352799D01*
Y-352767D01*
Y-352735D01*
Y-352702D01*
Y-352670D01*
Y-352638D01*
Y-352606D01*
Y-352573D01*
Y-352541D01*
Y-352509D01*
Y-352477D01*
Y-352444D01*
Y-352412D01*
Y-352380D01*
Y-352348D01*
Y-352315D01*
Y-352283D01*
Y-352251D01*
Y-352219D01*
Y-352186D01*
Y-352154D01*
Y-352122D01*
Y-352090D01*
Y-352057D01*
Y-352025D01*
Y-351993D01*
Y-351960D01*
Y-351928D01*
Y-351896D01*
Y-351864D01*
Y-351831D01*
Y-351799D01*
Y-351767D01*
X353462D01*
Y-351735D01*
Y-351702D01*
Y-351670D01*
Y-351638D01*
Y-351606D01*
Y-351573D01*
Y-351541D01*
Y-351509D01*
Y-351477D01*
Y-351444D01*
Y-351412D01*
Y-351380D01*
Y-351347D01*
Y-351315D01*
Y-351283D01*
Y-351251D01*
Y-351218D01*
Y-351186D01*
Y-351154D01*
Y-351122D01*
Y-351089D01*
Y-351057D01*
Y-351025D01*
Y-350993D01*
Y-350960D01*
X356592D01*
Y-350928D01*
Y-350896D01*
Y-350864D01*
Y-350831D01*
Y-350799D01*
Y-350767D01*
Y-350734D01*
Y-350702D01*
Y-350670D01*
Y-350638D01*
Y-350606D01*
Y-350573D01*
Y-350541D01*
Y-350509D01*
Y-350476D01*
Y-350444D01*
Y-350412D01*
Y-350380D01*
Y-350347D01*
Y-350315D01*
Y-350283D01*
Y-350251D01*
Y-350218D01*
Y-350186D01*
Y-350154D01*
Y-350121D01*
Y-350089D01*
Y-350057D01*
Y-350025D01*
Y-349992D01*
Y-349960D01*
Y-349928D01*
Y-349896D01*
Y-349863D01*
Y-349831D01*
Y-349799D01*
Y-349767D01*
Y-349734D01*
Y-349702D01*
Y-349670D01*
Y-349638D01*
Y-349605D01*
Y-349573D01*
Y-349541D01*
Y-349509D01*
Y-349476D01*
Y-349444D01*
Y-349412D01*
Y-349379D01*
Y-349347D01*
Y-349315D01*
Y-349283D01*
Y-349251D01*
Y-349218D01*
Y-349186D01*
Y-349154D01*
Y-349121D01*
Y-349089D01*
Y-349057D01*
Y-349025D01*
Y-348992D01*
Y-348960D01*
Y-348928D01*
Y-348896D01*
Y-348863D01*
Y-348831D01*
Y-348799D01*
Y-348766D01*
Y-348734D01*
Y-348702D01*
Y-348670D01*
Y-348638D01*
Y-348605D01*
Y-348573D01*
Y-348541D01*
Y-348508D01*
Y-348476D01*
Y-348444D01*
Y-348412D01*
Y-348379D01*
Y-348347D01*
Y-348315D01*
Y-348283D01*
Y-348250D01*
Y-348218D01*
Y-348186D01*
Y-348154D01*
Y-348121D01*
Y-348089D01*
Y-348057D01*
Y-348025D01*
Y-347992D01*
Y-347960D01*
Y-347928D01*
Y-347896D01*
Y-347863D01*
Y-347831D01*
Y-347799D01*
Y-347766D01*
Y-347734D01*
Y-347702D01*
Y-347670D01*
Y-347637D01*
Y-347605D01*
Y-347573D01*
Y-347541D01*
Y-347508D01*
Y-347476D01*
Y-347444D01*
Y-347411D01*
X353495D01*
Y-347379D01*
X353462D01*
Y-347347D01*
Y-347315D01*
Y-347283D01*
Y-347250D01*
Y-347218D01*
Y-347186D01*
Y-347153D01*
Y-347121D01*
Y-347089D01*
Y-347057D01*
Y-347024D01*
Y-346992D01*
Y-346960D01*
Y-346928D01*
Y-346895D01*
Y-346863D01*
Y-346831D01*
Y-346799D01*
Y-346766D01*
Y-346734D01*
Y-346702D01*
Y-346670D01*
Y-346637D01*
Y-346605D01*
X356592D01*
Y-346573D01*
Y-346540D01*
Y-346508D01*
Y-346476D01*
Y-346444D01*
Y-346411D01*
Y-346379D01*
Y-346347D01*
Y-346315D01*
Y-346282D01*
Y-346250D01*
Y-346218D01*
Y-346186D01*
Y-346153D01*
Y-346121D01*
Y-346089D01*
Y-346057D01*
Y-346024D01*
Y-345992D01*
Y-345960D01*
Y-345928D01*
Y-345895D01*
Y-345863D01*
Y-345831D01*
Y-345798D01*
Y-345766D01*
Y-345734D01*
Y-345702D01*
Y-345669D01*
Y-345637D01*
Y-345605D01*
Y-345573D01*
Y-345540D01*
Y-345508D01*
Y-345476D01*
Y-345444D01*
Y-345411D01*
Y-345379D01*
Y-345347D01*
Y-345315D01*
Y-345282D01*
Y-345250D01*
Y-345218D01*
Y-345185D01*
Y-345153D01*
Y-345121D01*
Y-345089D01*
Y-345056D01*
Y-345024D01*
Y-344992D01*
Y-344960D01*
Y-344927D01*
Y-344895D01*
Y-344863D01*
Y-344831D01*
Y-344798D01*
Y-344766D01*
Y-344734D01*
Y-344702D01*
Y-344669D01*
Y-344637D01*
Y-344605D01*
Y-344572D01*
Y-344540D01*
Y-344508D01*
Y-344476D01*
Y-344443D01*
Y-344411D01*
Y-344379D01*
Y-344347D01*
Y-344314D01*
Y-344282D01*
Y-344250D01*
Y-344218D01*
Y-344185D01*
Y-344153D01*
Y-344121D01*
Y-344089D01*
Y-344056D01*
Y-344024D01*
Y-343992D01*
Y-343959D01*
Y-343927D01*
Y-343895D01*
Y-343863D01*
Y-343830D01*
Y-343798D01*
Y-343766D01*
Y-343734D01*
Y-343701D01*
Y-343669D01*
Y-343637D01*
Y-343605D01*
Y-343572D01*
Y-343540D01*
Y-343508D01*
Y-343476D01*
Y-343443D01*
Y-343411D01*
Y-343379D01*
Y-343347D01*
Y-343314D01*
Y-343282D01*
Y-343250D01*
Y-343217D01*
Y-343185D01*
Y-343153D01*
Y-343121D01*
Y-343089D01*
Y-343056D01*
Y-343024D01*
X353462D01*
Y-342992D01*
Y-342959D01*
Y-342927D01*
Y-342895D01*
Y-342863D01*
Y-342830D01*
Y-342798D01*
Y-342766D01*
Y-342734D01*
Y-342701D01*
Y-342669D01*
Y-342637D01*
Y-342604D01*
Y-342572D01*
Y-342540D01*
Y-342508D01*
Y-342476D01*
Y-342443D01*
Y-342411D01*
Y-342379D01*
Y-342346D01*
Y-342314D01*
Y-342282D01*
Y-342250D01*
X353495D01*
Y-342217D01*
X356592D01*
Y-342185D01*
Y-342153D01*
Y-342121D01*
Y-342088D01*
Y-342056D01*
Y-342024D01*
Y-341992D01*
Y-341959D01*
Y-341927D01*
Y-341895D01*
Y-341863D01*
Y-341830D01*
Y-341798D01*
Y-341766D01*
Y-341734D01*
Y-341701D01*
Y-341669D01*
Y-341637D01*
Y-341604D01*
Y-341572D01*
Y-341540D01*
Y-341508D01*
Y-341475D01*
Y-341443D01*
Y-341411D01*
Y-341379D01*
Y-341346D01*
Y-341314D01*
Y-341282D01*
Y-341249D01*
Y-341217D01*
Y-341185D01*
Y-341153D01*
Y-341121D01*
Y-341088D01*
Y-341056D01*
Y-341024D01*
Y-340991D01*
Y-340959D01*
Y-340927D01*
Y-340895D01*
Y-340862D01*
Y-340830D01*
Y-340798D01*
Y-340766D01*
Y-340733D01*
Y-340701D01*
Y-340669D01*
Y-340637D01*
Y-340604D01*
Y-340572D01*
Y-340540D01*
Y-340508D01*
Y-340475D01*
Y-340443D01*
Y-340411D01*
Y-340378D01*
Y-340346D01*
Y-340314D01*
Y-340282D01*
Y-340249D01*
Y-340217D01*
Y-340185D01*
Y-340153D01*
Y-340120D01*
Y-340088D01*
Y-340056D01*
Y-340024D01*
Y-339991D01*
Y-339959D01*
Y-339927D01*
Y-339895D01*
Y-339862D01*
Y-339830D01*
Y-339798D01*
Y-339766D01*
Y-339733D01*
Y-339701D01*
Y-339669D01*
Y-339636D01*
Y-339604D01*
Y-339572D01*
Y-339540D01*
Y-339507D01*
Y-339475D01*
Y-339443D01*
Y-339411D01*
Y-339378D01*
Y-339346D01*
Y-339314D01*
Y-339282D01*
Y-339249D01*
Y-339217D01*
Y-339185D01*
Y-339153D01*
Y-339120D01*
Y-339088D01*
Y-339056D01*
Y-339023D01*
Y-338991D01*
Y-338959D01*
Y-338927D01*
Y-338894D01*
Y-338862D01*
Y-338830D01*
Y-338798D01*
Y-338765D01*
Y-338733D01*
Y-338701D01*
Y-338669D01*
X353462D01*
Y-338636D01*
Y-338604D01*
Y-338572D01*
Y-338540D01*
Y-338507D01*
Y-338475D01*
Y-338443D01*
Y-338410D01*
Y-338378D01*
Y-338346D01*
Y-338314D01*
Y-338281D01*
Y-338249D01*
Y-338217D01*
Y-338185D01*
Y-338152D01*
Y-338120D01*
Y-338088D01*
Y-338056D01*
Y-338023D01*
Y-337991D01*
Y-337959D01*
Y-337927D01*
Y-337894D01*
Y-337862D01*
Y-337830D01*
Y-337797D01*
Y-337765D01*
Y-337733D01*
Y-337701D01*
Y-337668D01*
Y-337636D01*
Y-337604D01*
Y-337572D01*
Y-337539D01*
Y-337507D01*
Y-337475D01*
Y-337443D01*
Y-337410D01*
Y-337378D01*
Y-337346D01*
Y-337314D01*
Y-337281D01*
Y-337249D01*
Y-337217D01*
Y-337185D01*
Y-337152D01*
Y-337120D01*
Y-337088D01*
Y-337055D01*
Y-337023D01*
Y-336991D01*
Y-336959D01*
Y-336927D01*
Y-336894D01*
Y-336862D01*
Y-336830D01*
Y-336797D01*
Y-336765D01*
Y-336733D01*
Y-336701D01*
Y-336668D01*
Y-336636D01*
Y-336604D01*
Y-336572D01*
Y-336539D01*
Y-336507D01*
Y-336475D01*
Y-336442D01*
Y-336410D01*
Y-336378D01*
Y-336346D01*
Y-336314D01*
Y-336281D01*
Y-336249D01*
Y-336217D01*
Y-336184D01*
Y-336152D01*
Y-336120D01*
Y-336088D01*
Y-336055D01*
Y-336023D01*
Y-335991D01*
Y-335959D01*
Y-335926D01*
Y-335894D01*
Y-335862D01*
Y-335830D01*
Y-335797D01*
Y-335765D01*
Y-335733D01*
Y-335700D01*
Y-335668D01*
Y-335636D01*
Y-335604D01*
Y-335572D01*
Y-335539D01*
Y-335507D01*
Y-335475D01*
Y-335442D01*
Y-335410D01*
Y-335378D01*
Y-335346D01*
Y-335313D01*
Y-335281D01*
Y-335249D01*
Y-335217D01*
Y-335184D01*
Y-335152D01*
Y-335120D01*
Y-335087D01*
Y-335055D01*
Y-335023D01*
Y-334991D01*
Y-334959D01*
Y-334926D01*
Y-334894D01*
Y-334862D01*
Y-334829D01*
Y-334797D01*
Y-334765D01*
Y-334733D01*
Y-334700D01*
Y-334668D01*
Y-334636D01*
Y-334604D01*
Y-334571D01*
Y-334539D01*
Y-334507D01*
Y-334474D01*
Y-334442D01*
Y-334410D01*
Y-334378D01*
Y-334346D01*
Y-334313D01*
Y-334281D01*
Y-334249D01*
Y-334216D01*
Y-334184D01*
Y-334152D01*
Y-334120D01*
Y-334087D01*
Y-334055D01*
Y-334023D01*
Y-333991D01*
Y-333958D01*
Y-333926D01*
Y-333894D01*
Y-333862D01*
Y-333829D01*
Y-333797D01*
Y-333765D01*
Y-333733D01*
Y-333700D01*
Y-333668D01*
Y-333636D01*
Y-333604D01*
Y-333571D01*
Y-333539D01*
Y-333507D01*
Y-333474D01*
Y-333442D01*
Y-333410D01*
Y-333378D01*
Y-333345D01*
Y-333313D01*
Y-333281D01*
Y-333249D01*
Y-333216D01*
Y-333184D01*
Y-333152D01*
Y-333120D01*
Y-333087D01*
Y-333055D01*
Y-333023D01*
Y-332991D01*
Y-332958D01*
Y-332926D01*
Y-332894D01*
Y-332861D01*
Y-332829D01*
Y-332797D01*
Y-332765D01*
Y-332732D01*
Y-332700D01*
Y-332668D01*
Y-332636D01*
Y-332603D01*
Y-332571D01*
Y-332539D01*
Y-332507D01*
Y-332474D01*
Y-332442D01*
Y-332410D01*
Y-332378D01*
Y-332345D01*
Y-332313D01*
Y-332281D01*
Y-332248D01*
Y-332216D01*
Y-332184D01*
Y-332152D01*
Y-332119D01*
Y-332087D01*
Y-332055D01*
Y-332023D01*
Y-331990D01*
Y-331958D01*
Y-331926D01*
Y-331894D01*
Y-331861D01*
Y-331829D01*
Y-331797D01*
Y-331765D01*
Y-331732D01*
Y-331700D01*
Y-331668D01*
Y-331635D01*
Y-331603D01*
Y-331571D01*
Y-331539D01*
Y-331506D01*
Y-331474D01*
Y-331442D01*
Y-331410D01*
Y-331377D01*
Y-331345D01*
Y-331313D01*
Y-331281D01*
Y-331248D01*
Y-331216D01*
Y-331184D01*
Y-331152D01*
Y-331119D01*
Y-331087D01*
Y-331055D01*
Y-331023D01*
Y-330990D01*
Y-330958D01*
Y-330926D01*
Y-330893D01*
Y-330861D01*
Y-330829D01*
Y-330797D01*
Y-330764D01*
Y-330732D01*
Y-330700D01*
Y-330668D01*
Y-330635D01*
Y-330603D01*
Y-330571D01*
Y-330539D01*
Y-330506D01*
Y-330474D01*
Y-330442D01*
Y-330410D01*
Y-330377D01*
Y-330345D01*
Y-330313D01*
Y-330280D01*
Y-330248D01*
Y-330216D01*
Y-330184D01*
Y-330152D01*
Y-330119D01*
Y-330087D01*
Y-330055D01*
Y-330022D01*
Y-329990D01*
Y-329958D01*
Y-329926D01*
Y-329893D01*
Y-329861D01*
Y-329829D01*
Y-329797D01*
Y-329764D01*
Y-329732D01*
Y-329700D01*
Y-329667D01*
Y-329635D01*
Y-329603D01*
Y-329571D01*
Y-329538D01*
Y-329506D01*
Y-329474D01*
Y-329442D01*
Y-329410D01*
Y-329377D01*
Y-329345D01*
Y-329313D01*
Y-329280D01*
Y-329248D01*
Y-329216D01*
Y-329184D01*
Y-329151D01*
Y-329119D01*
Y-329087D01*
Y-329055D01*
Y-329022D01*
Y-328990D01*
Y-328958D01*
Y-328925D01*
Y-328893D01*
Y-328861D01*
Y-328829D01*
Y-328797D01*
Y-328764D01*
Y-328732D01*
Y-328700D01*
Y-328667D01*
Y-328635D01*
Y-328603D01*
Y-328571D01*
Y-328538D01*
Y-328506D01*
Y-328474D01*
Y-328442D01*
Y-328409D01*
Y-328377D01*
Y-328345D01*
Y-328313D01*
Y-328280D01*
Y-328248D01*
Y-328216D01*
Y-328184D01*
Y-328151D01*
Y-328119D01*
Y-328087D01*
Y-328054D01*
Y-328022D01*
Y-327990D01*
Y-327958D01*
Y-327925D01*
Y-327893D01*
Y-327861D01*
Y-327829D01*
Y-327796D01*
Y-327764D01*
Y-327732D01*
Y-327700D01*
Y-327667D01*
Y-327635D01*
Y-327603D01*
Y-327571D01*
Y-327538D01*
Y-327506D01*
Y-327474D01*
Y-327442D01*
Y-327409D01*
Y-327377D01*
Y-327345D01*
Y-327312D01*
Y-327280D01*
Y-327248D01*
Y-327216D01*
Y-327183D01*
Y-327151D01*
Y-327119D01*
Y-327087D01*
Y-327054D01*
Y-327022D01*
Y-326990D01*
Y-326958D01*
Y-326925D01*
Y-326893D01*
Y-326861D01*
Y-326829D01*
Y-326796D01*
Y-326764D01*
Y-326732D01*
Y-326699D01*
Y-326667D01*
Y-326635D01*
Y-326603D01*
Y-326570D01*
Y-326538D01*
Y-326506D01*
Y-326474D01*
Y-326441D01*
Y-326409D01*
Y-326377D01*
Y-326345D01*
Y-326312D01*
Y-326280D01*
Y-326248D01*
Y-326216D01*
Y-326183D01*
Y-326151D01*
Y-326119D01*
Y-326086D01*
Y-326054D01*
Y-326022D01*
Y-325990D01*
Y-325957D01*
Y-325925D01*
Y-325893D01*
Y-325861D01*
Y-325828D01*
Y-325796D01*
X353495D01*
Y-325764D01*
X394209D01*
Y-325796D01*
D02*
G37*
G36*
X354946Y-347992D02*
X355108D01*
Y-348025D01*
X355204D01*
Y-348057D01*
X355301D01*
Y-348089D01*
X355366D01*
Y-348121D01*
X355430D01*
Y-348154D01*
X355463D01*
Y-348186D01*
X355527D01*
Y-348218D01*
X355559D01*
Y-348250D01*
X355592D01*
Y-348283D01*
X355624D01*
Y-348315D01*
X355656D01*
Y-348347D01*
X355688D01*
Y-348379D01*
X355721D01*
Y-348412D01*
X355753D01*
Y-348444D01*
X355785D01*
Y-348476D01*
Y-348508D01*
X355817D01*
Y-348541D01*
X355850D01*
Y-348573D01*
Y-348605D01*
X355882D01*
Y-348638D01*
Y-348670D01*
X355914D01*
Y-348702D01*
Y-348734D01*
X355946D01*
Y-348766D01*
Y-348799D01*
Y-348831D01*
X355979D01*
Y-348863D01*
Y-348896D01*
Y-348928D01*
Y-348960D01*
X356011D01*
Y-348992D01*
Y-349025D01*
Y-349057D01*
Y-349089D01*
Y-349121D01*
Y-349154D01*
Y-349186D01*
Y-349218D01*
Y-349251D01*
Y-349283D01*
Y-349315D01*
Y-349347D01*
Y-349379D01*
X355979D01*
Y-349412D01*
Y-349444D01*
Y-349476D01*
Y-349509D01*
X355946D01*
Y-349541D01*
Y-349573D01*
Y-349605D01*
X355914D01*
Y-349638D01*
Y-349670D01*
Y-349702D01*
X355882D01*
Y-349734D01*
Y-349767D01*
X355850D01*
Y-349799D01*
X355817D01*
Y-349831D01*
Y-349863D01*
X355785D01*
Y-349896D01*
X355753D01*
Y-349928D01*
Y-349960D01*
X355721D01*
Y-349992D01*
X355688D01*
Y-350025D01*
X355656D01*
Y-350057D01*
X355624D01*
Y-350089D01*
X355592D01*
Y-350121D01*
X355527D01*
Y-350154D01*
X355495D01*
Y-350186D01*
X355430D01*
Y-350218D01*
X355398D01*
Y-350251D01*
X355333D01*
Y-350283D01*
X355237D01*
Y-350315D01*
X355172D01*
Y-350347D01*
X355043D01*
Y-350380D01*
X354559D01*
Y-350347D01*
X354462D01*
Y-350315D01*
X354366D01*
Y-350283D01*
X354269D01*
Y-350251D01*
X354237D01*
Y-350218D01*
X354172D01*
Y-350186D01*
X354107D01*
Y-350154D01*
X354075D01*
Y-350121D01*
X354043D01*
Y-350089D01*
X353978D01*
Y-350057D01*
X353946D01*
Y-350025D01*
X353914D01*
Y-349992D01*
X353882D01*
Y-349960D01*
Y-349928D01*
X353849D01*
Y-349896D01*
X353817D01*
Y-349863D01*
X353785D01*
Y-349831D01*
Y-349799D01*
X353753D01*
Y-349767D01*
Y-349734D01*
X353720D01*
Y-349702D01*
Y-349670D01*
X353688D01*
Y-349638D01*
Y-349605D01*
X353656D01*
Y-349573D01*
Y-349541D01*
Y-349509D01*
X353624D01*
Y-349476D01*
Y-349444D01*
Y-349412D01*
Y-349379D01*
Y-349347D01*
X353591D01*
Y-349315D01*
Y-349283D01*
Y-349251D01*
Y-349218D01*
Y-349186D01*
Y-349154D01*
Y-349121D01*
Y-349089D01*
Y-349057D01*
Y-349025D01*
X353624D01*
Y-348992D01*
Y-348960D01*
Y-348928D01*
Y-348896D01*
Y-348863D01*
X353656D01*
Y-348831D01*
Y-348799D01*
Y-348766D01*
X353688D01*
Y-348734D01*
Y-348702D01*
Y-348670D01*
X353720D01*
Y-348638D01*
Y-348605D01*
X353753D01*
Y-348573D01*
Y-348541D01*
X353785D01*
Y-348508D01*
X353817D01*
Y-348476D01*
Y-348444D01*
X353849D01*
Y-348412D01*
X353882D01*
Y-348379D01*
X353914D01*
Y-348347D01*
X353946D01*
Y-348315D01*
X353978D01*
Y-348283D01*
X354011D01*
Y-348250D01*
X354043D01*
Y-348218D01*
X354075D01*
Y-348186D01*
X354140D01*
Y-348154D01*
X354204D01*
Y-348121D01*
X354237D01*
Y-348089D01*
X354301D01*
Y-348057D01*
X354398D01*
Y-348025D01*
X354495D01*
Y-347992D01*
X354656D01*
Y-347960D01*
X354946D01*
Y-347992D01*
D02*
G37*
G36*
X355075Y-352380D02*
X355204D01*
Y-352412D01*
X355269D01*
Y-352444D01*
X355333D01*
Y-352477D01*
X355398D01*
Y-352509D01*
X355463D01*
Y-352541D01*
X355495D01*
Y-352573D01*
X355559D01*
Y-352606D01*
X355592D01*
Y-352638D01*
X355624D01*
Y-352670D01*
X355656D01*
Y-352702D01*
X355688D01*
Y-352735D01*
X355721D01*
Y-352767D01*
X355753D01*
Y-352799D01*
X355785D01*
Y-352832D01*
Y-352864D01*
X355817D01*
Y-352896D01*
X355850D01*
Y-352928D01*
Y-352961D01*
X355882D01*
Y-352993D01*
Y-353025D01*
X355914D01*
Y-353057D01*
Y-353090D01*
X355946D01*
Y-353122D01*
Y-353154D01*
Y-353186D01*
X355979D01*
Y-353219D01*
Y-353251D01*
Y-353283D01*
Y-353315D01*
Y-353348D01*
X356011D01*
Y-353380D01*
Y-353412D01*
Y-353445D01*
Y-353477D01*
Y-353509D01*
Y-353541D01*
Y-353573D01*
Y-353606D01*
Y-353638D01*
Y-353670D01*
Y-353703D01*
Y-353735D01*
X355979D01*
Y-353767D01*
Y-353799D01*
Y-353832D01*
Y-353864D01*
Y-353896D01*
X355946D01*
Y-353928D01*
Y-353961D01*
Y-353993D01*
X355914D01*
Y-354025D01*
Y-354058D01*
X355882D01*
Y-354090D01*
Y-354122D01*
X355850D01*
Y-354154D01*
Y-354187D01*
X355817D01*
Y-354219D01*
X355785D01*
Y-354251D01*
Y-354283D01*
X355753D01*
Y-354316D01*
X355721D01*
Y-354348D01*
X355688D01*
Y-354380D01*
X355656D01*
Y-354412D01*
X355624D01*
Y-354445D01*
X355592D01*
Y-354477D01*
X355559D01*
Y-354509D01*
X355495D01*
Y-354541D01*
X355463D01*
Y-354574D01*
X355398D01*
Y-354606D01*
X355333D01*
Y-354638D01*
X355269D01*
Y-354670D01*
X355172D01*
Y-354703D01*
X355075D01*
Y-354735D01*
X354527D01*
Y-354703D01*
X354430D01*
Y-354670D01*
X354333D01*
Y-354638D01*
X354269D01*
Y-354606D01*
X354204D01*
Y-354574D01*
X354140D01*
Y-354541D01*
X354107D01*
Y-354509D01*
X354075D01*
Y-354477D01*
X354011D01*
Y-354445D01*
X353978D01*
Y-354412D01*
X353946D01*
Y-354380D01*
X353914D01*
Y-354348D01*
X353882D01*
Y-354316D01*
X353849D01*
Y-354283D01*
Y-354251D01*
X353817D01*
Y-354219D01*
X353785D01*
Y-354187D01*
Y-354154D01*
X353753D01*
Y-354122D01*
Y-354090D01*
X353720D01*
Y-354058D01*
Y-354025D01*
X353688D01*
Y-353993D01*
Y-353961D01*
X353656D01*
Y-353928D01*
Y-353896D01*
Y-353864D01*
X353624D01*
Y-353832D01*
Y-353799D01*
Y-353767D01*
Y-353735D01*
Y-353703D01*
X353591D01*
Y-353670D01*
Y-353638D01*
Y-353606D01*
Y-353573D01*
Y-353541D01*
Y-353509D01*
Y-353477D01*
Y-353445D01*
Y-353412D01*
Y-353380D01*
X353624D01*
Y-353348D01*
Y-353315D01*
Y-353283D01*
Y-353251D01*
Y-353219D01*
X353656D01*
Y-353186D01*
Y-353154D01*
Y-353122D01*
X353688D01*
Y-353090D01*
Y-353057D01*
X353720D01*
Y-353025D01*
Y-352993D01*
X353753D01*
Y-352961D01*
Y-352928D01*
X353785D01*
Y-352896D01*
Y-352864D01*
X353817D01*
Y-352832D01*
X353849D01*
Y-352799D01*
Y-352767D01*
X353882D01*
Y-352735D01*
X353914D01*
Y-352702D01*
X353946D01*
Y-352670D01*
X353978D01*
Y-352638D01*
X354011D01*
Y-352606D01*
X354043D01*
Y-352573D01*
X354107D01*
Y-352541D01*
X354140D01*
Y-352509D01*
X354204D01*
Y-352477D01*
X354269D01*
Y-352444D01*
X354333D01*
Y-352412D01*
X354430D01*
Y-352380D01*
X354527D01*
Y-352348D01*
X355075D01*
Y-352380D01*
D02*
G37*
G36*
X350365Y-325796D02*
X350688D01*
Y-325828D01*
X350817D01*
Y-325861D01*
X350946D01*
Y-325893D01*
X351010D01*
Y-325925D01*
X351107D01*
Y-325957D01*
X351172D01*
Y-325990D01*
X351236D01*
Y-326022D01*
X351301D01*
Y-326054D01*
X351365D01*
Y-326086D01*
X351398D01*
Y-326119D01*
X351462D01*
Y-326151D01*
X351494D01*
Y-326183D01*
X351527D01*
Y-326216D01*
X351591D01*
Y-326248D01*
X351623D01*
Y-326280D01*
X351656D01*
Y-326312D01*
X351688D01*
Y-326345D01*
X351720D01*
Y-326377D01*
X351752D01*
Y-326409D01*
X351785D01*
Y-326441D01*
X351817D01*
Y-326474D01*
X351849D01*
Y-326506D01*
Y-326538D01*
X351882D01*
Y-326570D01*
X351914D01*
Y-326603D01*
X351946D01*
Y-326635D01*
Y-326667D01*
X351978D01*
Y-326699D01*
X352010D01*
Y-326732D01*
Y-326764D01*
X352043D01*
Y-326796D01*
Y-326829D01*
X352075D01*
Y-326861D01*
Y-326893D01*
X352107D01*
Y-326925D01*
Y-326958D01*
X352140D01*
Y-326990D01*
Y-327022D01*
Y-327054D01*
X352172D01*
Y-327087D01*
Y-327119D01*
X352204D01*
Y-327151D01*
Y-327183D01*
Y-327216D01*
Y-327248D01*
X352236D01*
Y-327280D01*
Y-327312D01*
Y-327345D01*
Y-327377D01*
Y-327409D01*
X352269D01*
Y-327442D01*
Y-327474D01*
Y-327506D01*
Y-327538D01*
Y-327571D01*
Y-327603D01*
Y-327635D01*
Y-327667D01*
Y-327700D01*
Y-327732D01*
Y-327764D01*
Y-327796D01*
Y-327829D01*
Y-327861D01*
Y-327893D01*
Y-327925D01*
Y-327958D01*
Y-327990D01*
Y-328022D01*
Y-328054D01*
Y-328087D01*
Y-328119D01*
Y-328151D01*
Y-328184D01*
Y-328216D01*
Y-328248D01*
Y-328280D01*
Y-328313D01*
Y-328345D01*
Y-328377D01*
Y-328409D01*
Y-328442D01*
Y-328474D01*
Y-328506D01*
Y-328538D01*
Y-328571D01*
Y-328603D01*
Y-328635D01*
Y-328667D01*
Y-328700D01*
Y-328732D01*
Y-328764D01*
Y-328797D01*
Y-328829D01*
Y-328861D01*
Y-328893D01*
Y-328925D01*
Y-328958D01*
Y-328990D01*
Y-329022D01*
Y-329055D01*
Y-329087D01*
Y-329119D01*
Y-329151D01*
Y-329184D01*
Y-329216D01*
Y-329248D01*
Y-329280D01*
Y-329313D01*
Y-329345D01*
Y-329377D01*
Y-329410D01*
Y-329442D01*
Y-329474D01*
Y-329506D01*
Y-329538D01*
Y-329571D01*
Y-329603D01*
Y-329635D01*
Y-329667D01*
Y-329700D01*
Y-329732D01*
Y-329764D01*
Y-329797D01*
Y-329829D01*
Y-329861D01*
Y-329893D01*
Y-329926D01*
Y-329958D01*
Y-329990D01*
Y-330022D01*
Y-330055D01*
Y-330087D01*
Y-330119D01*
Y-330152D01*
Y-330184D01*
Y-330216D01*
Y-330248D01*
Y-330280D01*
Y-330313D01*
Y-330345D01*
Y-330377D01*
Y-330410D01*
Y-330442D01*
Y-330474D01*
Y-330506D01*
Y-330539D01*
Y-330571D01*
Y-330603D01*
Y-330635D01*
Y-330668D01*
Y-330700D01*
Y-330732D01*
Y-330764D01*
Y-330797D01*
Y-330829D01*
Y-330861D01*
Y-330893D01*
Y-330926D01*
Y-330958D01*
Y-330990D01*
Y-331023D01*
Y-331055D01*
Y-331087D01*
Y-331119D01*
Y-331152D01*
Y-331184D01*
Y-331216D01*
Y-331248D01*
Y-331281D01*
Y-331313D01*
Y-331345D01*
Y-331377D01*
Y-331410D01*
Y-331442D01*
Y-331474D01*
Y-331506D01*
Y-331539D01*
Y-331571D01*
Y-331603D01*
Y-331635D01*
Y-331668D01*
Y-331700D01*
Y-331732D01*
Y-331765D01*
Y-331797D01*
Y-331829D01*
Y-331861D01*
Y-331894D01*
Y-331926D01*
Y-331958D01*
Y-331990D01*
Y-332023D01*
Y-332055D01*
Y-332087D01*
Y-332119D01*
Y-332152D01*
Y-332184D01*
Y-332216D01*
Y-332248D01*
Y-332281D01*
Y-332313D01*
Y-332345D01*
Y-332378D01*
Y-332410D01*
Y-332442D01*
Y-332474D01*
Y-332507D01*
Y-332539D01*
Y-332571D01*
Y-332603D01*
Y-332636D01*
Y-332668D01*
Y-332700D01*
Y-332732D01*
Y-332765D01*
Y-332797D01*
Y-332829D01*
Y-332861D01*
Y-332894D01*
Y-332926D01*
Y-332958D01*
Y-332991D01*
Y-333023D01*
Y-333055D01*
Y-333087D01*
Y-333120D01*
Y-333152D01*
Y-333184D01*
Y-333216D01*
Y-333249D01*
Y-333281D01*
Y-333313D01*
Y-333345D01*
Y-333378D01*
Y-333410D01*
Y-333442D01*
Y-333474D01*
Y-333507D01*
Y-333539D01*
Y-333571D01*
Y-333604D01*
Y-333636D01*
Y-333668D01*
Y-333700D01*
Y-333733D01*
Y-333765D01*
Y-333797D01*
Y-333829D01*
Y-333862D01*
Y-333894D01*
Y-333926D01*
Y-333958D01*
Y-333991D01*
Y-334023D01*
Y-334055D01*
Y-334087D01*
Y-334120D01*
Y-334152D01*
Y-334184D01*
Y-334216D01*
Y-334249D01*
Y-334281D01*
Y-334313D01*
Y-334346D01*
Y-334378D01*
Y-334410D01*
Y-334442D01*
Y-334474D01*
Y-334507D01*
Y-334539D01*
Y-334571D01*
Y-334604D01*
Y-334636D01*
Y-334668D01*
Y-334700D01*
Y-334733D01*
Y-334765D01*
Y-334797D01*
Y-334829D01*
Y-334862D01*
Y-334894D01*
Y-334926D01*
Y-334959D01*
Y-334991D01*
Y-335023D01*
Y-335055D01*
Y-335087D01*
Y-335120D01*
Y-335152D01*
Y-335184D01*
Y-335217D01*
Y-335249D01*
Y-335281D01*
Y-335313D01*
Y-335346D01*
Y-335378D01*
Y-335410D01*
Y-335442D01*
Y-335475D01*
Y-335507D01*
Y-335539D01*
Y-335572D01*
Y-335604D01*
Y-335636D01*
Y-335668D01*
Y-335700D01*
Y-335733D01*
Y-335765D01*
Y-335797D01*
Y-335830D01*
Y-335862D01*
Y-335894D01*
Y-335926D01*
Y-335959D01*
Y-335991D01*
Y-336023D01*
Y-336055D01*
Y-336088D01*
Y-336120D01*
Y-336152D01*
Y-336184D01*
Y-336217D01*
Y-336249D01*
Y-336281D01*
Y-336314D01*
Y-336346D01*
Y-336378D01*
Y-336410D01*
Y-336442D01*
Y-336475D01*
Y-336507D01*
Y-336539D01*
Y-336572D01*
Y-336604D01*
Y-336636D01*
Y-336668D01*
Y-336701D01*
Y-336733D01*
Y-336765D01*
Y-336797D01*
Y-336830D01*
Y-336862D01*
Y-336894D01*
Y-336927D01*
Y-336959D01*
Y-336991D01*
Y-337023D01*
Y-337055D01*
Y-337088D01*
Y-337120D01*
Y-337152D01*
Y-337185D01*
Y-337217D01*
Y-337249D01*
Y-337281D01*
Y-337314D01*
Y-337346D01*
Y-337378D01*
Y-337410D01*
Y-337443D01*
Y-337475D01*
Y-337507D01*
Y-337539D01*
Y-337572D01*
Y-337604D01*
Y-337636D01*
Y-337668D01*
Y-337701D01*
Y-337733D01*
Y-337765D01*
Y-337797D01*
Y-337830D01*
Y-337862D01*
Y-337894D01*
Y-337927D01*
Y-337959D01*
Y-337991D01*
Y-338023D01*
Y-338056D01*
Y-338088D01*
Y-338120D01*
Y-338152D01*
Y-338185D01*
Y-338217D01*
Y-338249D01*
Y-338281D01*
Y-338314D01*
Y-338346D01*
Y-338378D01*
Y-338410D01*
Y-338443D01*
Y-338475D01*
Y-338507D01*
Y-338540D01*
Y-338572D01*
Y-338604D01*
Y-338636D01*
Y-338669D01*
Y-338701D01*
Y-338733D01*
Y-338765D01*
Y-338798D01*
Y-338830D01*
Y-338862D01*
Y-338894D01*
Y-338927D01*
Y-338959D01*
Y-338991D01*
Y-339023D01*
Y-339056D01*
Y-339088D01*
Y-339120D01*
Y-339153D01*
Y-339185D01*
Y-339217D01*
Y-339249D01*
Y-339282D01*
Y-339314D01*
Y-339346D01*
Y-339378D01*
Y-339411D01*
Y-339443D01*
Y-339475D01*
Y-339507D01*
Y-339540D01*
Y-339572D01*
Y-339604D01*
Y-339636D01*
Y-339669D01*
Y-339701D01*
Y-339733D01*
Y-339766D01*
Y-339798D01*
Y-339830D01*
Y-339862D01*
Y-339895D01*
Y-339927D01*
Y-339959D01*
Y-339991D01*
Y-340024D01*
Y-340056D01*
Y-340088D01*
Y-340120D01*
Y-340153D01*
Y-340185D01*
Y-340217D01*
Y-340249D01*
Y-340282D01*
Y-340314D01*
Y-340346D01*
Y-340378D01*
Y-340411D01*
Y-340443D01*
Y-340475D01*
Y-340508D01*
Y-340540D01*
Y-340572D01*
Y-340604D01*
Y-340637D01*
Y-340669D01*
Y-340701D01*
Y-340733D01*
Y-340766D01*
Y-340798D01*
Y-340830D01*
Y-340862D01*
Y-340895D01*
Y-340927D01*
Y-340959D01*
Y-340991D01*
Y-341024D01*
Y-341056D01*
Y-341088D01*
Y-341121D01*
Y-341153D01*
Y-341185D01*
Y-341217D01*
Y-341249D01*
Y-341282D01*
Y-341314D01*
Y-341346D01*
Y-341379D01*
Y-341411D01*
Y-341443D01*
Y-341475D01*
Y-341508D01*
Y-341540D01*
Y-341572D01*
Y-341604D01*
Y-341637D01*
Y-341669D01*
Y-341701D01*
Y-341734D01*
Y-341766D01*
Y-341798D01*
Y-341830D01*
Y-341863D01*
Y-341895D01*
Y-341927D01*
Y-341959D01*
Y-341992D01*
Y-342024D01*
Y-342056D01*
Y-342088D01*
Y-342121D01*
Y-342153D01*
Y-342185D01*
Y-342217D01*
Y-342250D01*
Y-342282D01*
Y-342314D01*
Y-342346D01*
Y-342379D01*
Y-342411D01*
Y-342443D01*
Y-342476D01*
Y-342508D01*
Y-342540D01*
Y-342572D01*
Y-342604D01*
Y-342637D01*
Y-342669D01*
Y-342701D01*
Y-342734D01*
Y-342766D01*
Y-342798D01*
Y-342830D01*
Y-342863D01*
Y-342895D01*
Y-342927D01*
Y-342959D01*
Y-342992D01*
Y-343024D01*
Y-343056D01*
Y-343089D01*
Y-343121D01*
Y-343153D01*
Y-343185D01*
Y-343217D01*
Y-343250D01*
Y-343282D01*
Y-343314D01*
Y-343347D01*
Y-343379D01*
Y-343411D01*
Y-343443D01*
Y-343476D01*
Y-343508D01*
Y-343540D01*
Y-343572D01*
Y-343605D01*
Y-343637D01*
Y-343669D01*
Y-343701D01*
Y-343734D01*
Y-343766D01*
Y-343798D01*
Y-343830D01*
Y-343863D01*
Y-343895D01*
Y-343927D01*
Y-343959D01*
Y-343992D01*
Y-344024D01*
Y-344056D01*
Y-344089D01*
Y-344121D01*
Y-344153D01*
Y-344185D01*
Y-344218D01*
Y-344250D01*
Y-344282D01*
Y-344314D01*
Y-344347D01*
Y-344379D01*
Y-344411D01*
Y-344443D01*
Y-344476D01*
Y-344508D01*
Y-344540D01*
Y-344572D01*
Y-344605D01*
Y-344637D01*
Y-344669D01*
Y-344702D01*
Y-344734D01*
Y-344766D01*
Y-344798D01*
Y-344831D01*
Y-344863D01*
Y-344895D01*
Y-344927D01*
Y-344960D01*
Y-344992D01*
Y-345024D01*
Y-345056D01*
Y-345089D01*
Y-345121D01*
Y-345153D01*
Y-345185D01*
Y-345218D01*
Y-345250D01*
Y-345282D01*
Y-345315D01*
Y-345347D01*
Y-345379D01*
Y-345411D01*
Y-345444D01*
Y-345476D01*
Y-345508D01*
Y-345540D01*
Y-345573D01*
Y-345605D01*
Y-345637D01*
Y-345669D01*
Y-345702D01*
Y-345734D01*
Y-345766D01*
Y-345798D01*
Y-345831D01*
Y-345863D01*
Y-345895D01*
Y-345928D01*
Y-345960D01*
Y-345992D01*
Y-346024D01*
Y-346057D01*
Y-346089D01*
Y-346121D01*
Y-346153D01*
Y-346186D01*
Y-346218D01*
Y-346250D01*
Y-346282D01*
Y-346315D01*
Y-346347D01*
Y-346379D01*
Y-346411D01*
Y-346444D01*
Y-346476D01*
Y-346508D01*
Y-346540D01*
Y-346573D01*
Y-346605D01*
Y-346637D01*
Y-346670D01*
Y-346702D01*
Y-346734D01*
Y-346766D01*
Y-346799D01*
Y-346831D01*
Y-346863D01*
Y-346895D01*
Y-346928D01*
Y-346960D01*
Y-346992D01*
Y-347024D01*
Y-347057D01*
Y-347089D01*
Y-347121D01*
Y-347153D01*
Y-347186D01*
Y-347218D01*
Y-347250D01*
Y-347283D01*
Y-347315D01*
Y-347347D01*
Y-347379D01*
Y-347411D01*
Y-347444D01*
Y-347476D01*
Y-347508D01*
Y-347541D01*
Y-347573D01*
Y-347605D01*
Y-347637D01*
Y-347670D01*
Y-347702D01*
Y-347734D01*
Y-347766D01*
Y-347799D01*
Y-347831D01*
Y-347863D01*
Y-347896D01*
Y-347928D01*
Y-347960D01*
Y-347992D01*
Y-348025D01*
Y-348057D01*
Y-348089D01*
Y-348121D01*
Y-348154D01*
Y-348186D01*
Y-348218D01*
Y-348250D01*
Y-348283D01*
Y-348315D01*
Y-348347D01*
Y-348379D01*
Y-348412D01*
Y-348444D01*
Y-348476D01*
Y-348508D01*
Y-348541D01*
Y-348573D01*
Y-348605D01*
Y-348638D01*
Y-348670D01*
Y-348702D01*
Y-348734D01*
Y-348766D01*
Y-348799D01*
Y-348831D01*
Y-348863D01*
Y-348896D01*
Y-348928D01*
Y-348960D01*
Y-348992D01*
Y-349025D01*
Y-349057D01*
Y-349089D01*
Y-349121D01*
Y-349154D01*
Y-349186D01*
Y-349218D01*
Y-349251D01*
Y-349283D01*
Y-349315D01*
Y-349347D01*
Y-349379D01*
Y-349412D01*
Y-349444D01*
Y-349476D01*
Y-349509D01*
Y-349541D01*
Y-349573D01*
Y-349605D01*
Y-349638D01*
Y-349670D01*
Y-349702D01*
Y-349734D01*
Y-349767D01*
Y-349799D01*
Y-349831D01*
Y-349863D01*
Y-349896D01*
Y-349928D01*
Y-349960D01*
Y-349992D01*
Y-350025D01*
Y-350057D01*
Y-350089D01*
Y-350121D01*
Y-350154D01*
Y-350186D01*
Y-350218D01*
Y-350251D01*
Y-350283D01*
Y-350315D01*
Y-350347D01*
Y-350380D01*
Y-350412D01*
Y-350444D01*
Y-350476D01*
Y-350509D01*
Y-350541D01*
Y-350573D01*
Y-350606D01*
Y-350638D01*
Y-350670D01*
Y-350702D01*
Y-350734D01*
Y-350767D01*
Y-350799D01*
Y-350831D01*
Y-350864D01*
Y-350896D01*
Y-350928D01*
Y-350960D01*
Y-350993D01*
Y-351025D01*
Y-351057D01*
Y-351089D01*
Y-351122D01*
Y-351154D01*
Y-351186D01*
Y-351218D01*
Y-351251D01*
Y-351283D01*
Y-351315D01*
Y-351347D01*
Y-351380D01*
Y-351412D01*
Y-351444D01*
Y-351477D01*
Y-351509D01*
Y-351541D01*
Y-351573D01*
Y-351606D01*
Y-351638D01*
Y-351670D01*
Y-351702D01*
Y-351735D01*
Y-351767D01*
Y-351799D01*
Y-351831D01*
Y-351864D01*
Y-351896D01*
Y-351928D01*
Y-351960D01*
Y-351993D01*
Y-352025D01*
Y-352057D01*
Y-352090D01*
Y-352122D01*
Y-352154D01*
Y-352186D01*
Y-352219D01*
Y-352251D01*
Y-352283D01*
Y-352315D01*
Y-352348D01*
Y-352380D01*
Y-352412D01*
Y-352444D01*
Y-352477D01*
Y-352509D01*
Y-352541D01*
Y-352573D01*
Y-352606D01*
Y-352638D01*
Y-352670D01*
Y-352702D01*
Y-352735D01*
Y-352767D01*
Y-352799D01*
Y-352832D01*
Y-352864D01*
Y-352896D01*
Y-352928D01*
Y-352961D01*
Y-352993D01*
Y-353025D01*
Y-353057D01*
Y-353090D01*
Y-353122D01*
Y-353154D01*
Y-353186D01*
Y-353219D01*
Y-353251D01*
Y-353283D01*
Y-353315D01*
Y-353348D01*
Y-353380D01*
Y-353412D01*
Y-353445D01*
Y-353477D01*
Y-353509D01*
Y-353541D01*
Y-353573D01*
Y-353606D01*
Y-353638D01*
Y-353670D01*
Y-353703D01*
Y-353735D01*
Y-353767D01*
Y-353799D01*
Y-353832D01*
Y-353864D01*
Y-353896D01*
Y-353928D01*
Y-353961D01*
Y-353993D01*
Y-354025D01*
Y-354058D01*
Y-354090D01*
Y-354122D01*
Y-354154D01*
Y-354187D01*
Y-354219D01*
Y-354251D01*
Y-354283D01*
Y-354316D01*
Y-354348D01*
Y-354380D01*
Y-354412D01*
Y-354445D01*
Y-354477D01*
Y-354509D01*
Y-354541D01*
Y-354574D01*
Y-354606D01*
Y-354638D01*
Y-354670D01*
Y-354703D01*
Y-354735D01*
Y-354767D01*
Y-354800D01*
Y-354832D01*
Y-354864D01*
Y-354896D01*
Y-354928D01*
Y-354961D01*
Y-354993D01*
Y-355025D01*
Y-355058D01*
Y-355090D01*
Y-355122D01*
Y-355154D01*
Y-355187D01*
Y-355219D01*
Y-355251D01*
Y-355283D01*
Y-355316D01*
Y-355348D01*
Y-355380D01*
Y-355413D01*
Y-355445D01*
Y-355477D01*
Y-355509D01*
Y-355541D01*
Y-355574D01*
Y-355606D01*
Y-355638D01*
Y-355671D01*
Y-355703D01*
Y-355735D01*
Y-355767D01*
Y-355800D01*
Y-355832D01*
Y-355864D01*
Y-355896D01*
Y-355929D01*
Y-355961D01*
Y-355993D01*
Y-356025D01*
Y-356058D01*
Y-356090D01*
Y-356122D01*
Y-356154D01*
Y-356187D01*
Y-356219D01*
Y-356251D01*
Y-356283D01*
Y-356316D01*
Y-356348D01*
Y-356380D01*
Y-356413D01*
Y-356445D01*
Y-356477D01*
Y-356509D01*
Y-356542D01*
Y-356574D01*
Y-356606D01*
Y-356638D01*
Y-356671D01*
Y-356703D01*
Y-356735D01*
Y-356768D01*
Y-356800D01*
Y-356832D01*
Y-356864D01*
Y-356896D01*
Y-356929D01*
Y-356961D01*
Y-356993D01*
Y-357026D01*
Y-357058D01*
Y-357090D01*
Y-357122D01*
Y-357155D01*
Y-357187D01*
Y-357219D01*
Y-357251D01*
Y-357284D01*
Y-357316D01*
Y-357348D01*
Y-357380D01*
Y-357413D01*
Y-357445D01*
Y-357477D01*
Y-357509D01*
Y-357542D01*
Y-357574D01*
Y-357606D01*
Y-357639D01*
Y-357671D01*
Y-357703D01*
Y-357735D01*
Y-357768D01*
Y-357800D01*
Y-357832D01*
Y-357864D01*
Y-357897D01*
Y-357929D01*
Y-357961D01*
Y-357993D01*
Y-358026D01*
Y-358058D01*
Y-358090D01*
Y-358122D01*
Y-358155D01*
Y-358187D01*
Y-358219D01*
Y-358252D01*
Y-358284D01*
Y-358316D01*
Y-358348D01*
Y-358381D01*
Y-358413D01*
Y-358445D01*
Y-358477D01*
Y-358510D01*
Y-358542D01*
Y-358574D01*
Y-358606D01*
Y-358639D01*
Y-358671D01*
Y-358703D01*
Y-358735D01*
Y-358768D01*
Y-358800D01*
Y-358832D01*
Y-358864D01*
Y-358897D01*
Y-358929D01*
Y-358961D01*
Y-358994D01*
Y-359026D01*
Y-359058D01*
Y-359090D01*
Y-359123D01*
Y-359155D01*
Y-359187D01*
Y-359219D01*
Y-359252D01*
Y-359284D01*
Y-359316D01*
Y-359348D01*
Y-359381D01*
Y-359413D01*
Y-359445D01*
Y-359477D01*
Y-359510D01*
Y-359542D01*
Y-359574D01*
Y-359607D01*
Y-359639D01*
Y-359671D01*
Y-359703D01*
Y-359735D01*
Y-359768D01*
Y-359800D01*
Y-359832D01*
Y-359865D01*
Y-359897D01*
Y-359929D01*
Y-359961D01*
Y-359994D01*
Y-360026D01*
Y-360058D01*
Y-360090D01*
Y-360123D01*
Y-360155D01*
Y-360187D01*
Y-360220D01*
Y-360252D01*
Y-360284D01*
Y-360316D01*
Y-360349D01*
Y-360381D01*
Y-360413D01*
Y-360445D01*
Y-360478D01*
Y-360510D01*
Y-360542D01*
Y-360574D01*
Y-360607D01*
Y-360639D01*
Y-360671D01*
Y-360703D01*
Y-360736D01*
Y-360768D01*
Y-360800D01*
Y-360832D01*
Y-360865D01*
Y-360897D01*
Y-360929D01*
Y-360962D01*
Y-360994D01*
Y-361026D01*
Y-361058D01*
Y-361090D01*
Y-361123D01*
Y-361155D01*
Y-361187D01*
Y-361220D01*
Y-361252D01*
Y-361284D01*
Y-361316D01*
Y-361349D01*
Y-361381D01*
Y-361413D01*
Y-361445D01*
Y-361478D01*
Y-361510D01*
Y-361542D01*
Y-361575D01*
Y-361607D01*
Y-361639D01*
Y-361671D01*
Y-361703D01*
Y-361736D01*
Y-361768D01*
Y-361800D01*
Y-361832D01*
Y-361865D01*
Y-361897D01*
Y-361929D01*
Y-361962D01*
Y-361994D01*
Y-362026D01*
Y-362058D01*
Y-362091D01*
Y-362123D01*
Y-362155D01*
Y-362187D01*
Y-362220D01*
Y-362252D01*
Y-362284D01*
Y-362316D01*
Y-362349D01*
Y-362381D01*
Y-362413D01*
Y-362445D01*
Y-362478D01*
Y-362510D01*
Y-362542D01*
Y-362575D01*
Y-362607D01*
Y-362639D01*
X351075D01*
Y-362607D01*
Y-362575D01*
Y-362542D01*
Y-362510D01*
Y-362478D01*
Y-362445D01*
Y-362413D01*
Y-362381D01*
Y-362349D01*
Y-362316D01*
Y-362284D01*
Y-362252D01*
Y-362220D01*
Y-362187D01*
Y-362155D01*
Y-362123D01*
Y-362091D01*
Y-362058D01*
Y-362026D01*
Y-361994D01*
Y-361962D01*
Y-361929D01*
Y-361897D01*
Y-361865D01*
Y-361832D01*
Y-361800D01*
Y-361768D01*
Y-361736D01*
Y-361703D01*
Y-361671D01*
Y-361639D01*
Y-361607D01*
Y-361575D01*
Y-361542D01*
Y-361510D01*
Y-361478D01*
Y-361445D01*
Y-361413D01*
Y-361381D01*
Y-361349D01*
Y-361316D01*
Y-361284D01*
Y-361252D01*
Y-361220D01*
Y-361187D01*
Y-361155D01*
Y-361123D01*
Y-361090D01*
Y-361058D01*
Y-361026D01*
Y-360994D01*
Y-360962D01*
Y-360929D01*
Y-360897D01*
Y-360865D01*
Y-360832D01*
Y-360800D01*
Y-360768D01*
Y-360736D01*
Y-360703D01*
Y-360671D01*
Y-360639D01*
Y-360607D01*
Y-360574D01*
Y-360542D01*
Y-360510D01*
Y-360478D01*
Y-360445D01*
Y-360413D01*
Y-360381D01*
Y-360349D01*
Y-360316D01*
Y-360284D01*
Y-360252D01*
Y-360220D01*
Y-360187D01*
Y-360155D01*
Y-360123D01*
Y-360090D01*
Y-360058D01*
Y-360026D01*
Y-359994D01*
Y-359961D01*
Y-359929D01*
Y-359897D01*
Y-359865D01*
Y-359832D01*
Y-359800D01*
Y-359768D01*
Y-359735D01*
Y-359703D01*
Y-359671D01*
Y-359639D01*
Y-359607D01*
Y-359574D01*
Y-359542D01*
Y-359510D01*
Y-359477D01*
Y-359445D01*
Y-359413D01*
Y-359381D01*
Y-359348D01*
Y-359316D01*
Y-359284D01*
Y-359252D01*
Y-359219D01*
Y-359187D01*
Y-359155D01*
Y-359123D01*
Y-359090D01*
Y-359058D01*
Y-359026D01*
Y-358994D01*
Y-358961D01*
Y-358929D01*
Y-358897D01*
Y-358864D01*
Y-358832D01*
Y-358800D01*
Y-358768D01*
Y-358735D01*
Y-358703D01*
Y-358671D01*
Y-358639D01*
Y-358606D01*
Y-358574D01*
Y-358542D01*
Y-358510D01*
Y-358477D01*
Y-358445D01*
Y-358413D01*
Y-358381D01*
Y-358348D01*
Y-358316D01*
Y-358284D01*
Y-358252D01*
Y-358219D01*
Y-358187D01*
Y-358155D01*
Y-358122D01*
Y-358090D01*
Y-358058D01*
Y-358026D01*
Y-357993D01*
Y-357961D01*
Y-357929D01*
Y-357897D01*
Y-357864D01*
Y-357832D01*
Y-357800D01*
Y-357768D01*
Y-357735D01*
Y-357703D01*
Y-357671D01*
Y-357639D01*
Y-357606D01*
Y-357574D01*
Y-357542D01*
Y-357509D01*
Y-357477D01*
Y-357445D01*
Y-357413D01*
Y-357380D01*
Y-357348D01*
Y-357316D01*
Y-357284D01*
Y-357251D01*
Y-357219D01*
Y-357187D01*
Y-357155D01*
Y-357122D01*
Y-357090D01*
Y-357058D01*
Y-357026D01*
Y-356993D01*
Y-356961D01*
Y-356929D01*
Y-356896D01*
Y-356864D01*
Y-356832D01*
Y-356800D01*
Y-356768D01*
Y-356735D01*
Y-356703D01*
Y-356671D01*
Y-356638D01*
Y-356606D01*
Y-356574D01*
Y-356542D01*
Y-356509D01*
Y-356477D01*
Y-356445D01*
Y-356413D01*
Y-356380D01*
Y-356348D01*
Y-356316D01*
Y-356283D01*
Y-356251D01*
Y-356219D01*
Y-356187D01*
Y-356154D01*
Y-356122D01*
Y-356090D01*
Y-356058D01*
Y-356025D01*
Y-355993D01*
Y-355961D01*
Y-355929D01*
Y-355896D01*
Y-355864D01*
Y-355832D01*
Y-355800D01*
Y-355767D01*
Y-355735D01*
Y-355703D01*
Y-355671D01*
Y-355638D01*
Y-355606D01*
Y-355574D01*
Y-355541D01*
Y-355509D01*
Y-355477D01*
Y-355445D01*
Y-355413D01*
Y-355380D01*
Y-355348D01*
Y-355316D01*
Y-355283D01*
Y-355251D01*
Y-355219D01*
Y-355187D01*
Y-355154D01*
Y-355122D01*
Y-355090D01*
Y-355058D01*
Y-355025D01*
Y-354993D01*
Y-354961D01*
Y-354928D01*
Y-354896D01*
Y-354864D01*
Y-354832D01*
Y-354800D01*
Y-354767D01*
Y-354735D01*
Y-354703D01*
Y-354670D01*
Y-354638D01*
Y-354606D01*
Y-354574D01*
Y-354541D01*
Y-354509D01*
Y-354477D01*
Y-354445D01*
Y-354412D01*
Y-354380D01*
Y-354348D01*
Y-354316D01*
Y-354283D01*
Y-354251D01*
Y-354219D01*
Y-354187D01*
Y-354154D01*
Y-354122D01*
Y-354090D01*
Y-354058D01*
Y-354025D01*
Y-353993D01*
Y-353961D01*
Y-353928D01*
Y-353896D01*
Y-353864D01*
Y-353832D01*
Y-353799D01*
Y-353767D01*
Y-353735D01*
Y-353703D01*
Y-353670D01*
Y-353638D01*
Y-353606D01*
Y-353573D01*
Y-353541D01*
Y-353509D01*
Y-353477D01*
Y-353445D01*
Y-353412D01*
Y-353380D01*
Y-353348D01*
Y-353315D01*
Y-353283D01*
Y-353251D01*
Y-353219D01*
Y-353186D01*
Y-353154D01*
Y-353122D01*
Y-353090D01*
Y-353057D01*
Y-353025D01*
Y-352993D01*
Y-352961D01*
Y-352928D01*
Y-352896D01*
Y-352864D01*
Y-352832D01*
Y-352799D01*
Y-352767D01*
Y-352735D01*
Y-352702D01*
Y-352670D01*
Y-352638D01*
Y-352606D01*
Y-352573D01*
Y-352541D01*
Y-352509D01*
Y-352477D01*
Y-352444D01*
Y-352412D01*
Y-352380D01*
Y-352348D01*
Y-352315D01*
Y-352283D01*
Y-352251D01*
Y-352219D01*
Y-352186D01*
Y-352154D01*
Y-352122D01*
Y-352090D01*
Y-352057D01*
Y-352025D01*
Y-351993D01*
Y-351960D01*
Y-351928D01*
Y-351896D01*
Y-351864D01*
Y-351831D01*
Y-351799D01*
Y-351767D01*
Y-351735D01*
Y-351702D01*
Y-351670D01*
Y-351638D01*
Y-351606D01*
Y-351573D01*
Y-351541D01*
Y-351509D01*
Y-351477D01*
Y-351444D01*
Y-351412D01*
Y-351380D01*
Y-351347D01*
Y-351315D01*
Y-351283D01*
Y-351251D01*
Y-351218D01*
Y-351186D01*
Y-351154D01*
Y-351122D01*
Y-351089D01*
Y-351057D01*
Y-351025D01*
Y-350993D01*
Y-350960D01*
Y-350928D01*
Y-350896D01*
Y-350864D01*
Y-350831D01*
Y-350799D01*
Y-350767D01*
Y-350734D01*
Y-350702D01*
Y-350670D01*
Y-350638D01*
Y-350606D01*
Y-350573D01*
Y-350541D01*
Y-350509D01*
Y-350476D01*
Y-350444D01*
Y-350412D01*
Y-350380D01*
Y-350347D01*
Y-350315D01*
Y-350283D01*
Y-350251D01*
Y-350218D01*
Y-350186D01*
Y-350154D01*
Y-350121D01*
Y-350089D01*
Y-350057D01*
Y-350025D01*
Y-349992D01*
Y-349960D01*
Y-349928D01*
Y-349896D01*
Y-349863D01*
Y-349831D01*
Y-349799D01*
Y-349767D01*
Y-349734D01*
Y-349702D01*
Y-349670D01*
Y-349638D01*
Y-349605D01*
Y-349573D01*
Y-349541D01*
Y-349509D01*
Y-349476D01*
Y-349444D01*
Y-349412D01*
Y-349379D01*
Y-349347D01*
Y-349315D01*
Y-349283D01*
Y-349251D01*
Y-349218D01*
Y-349186D01*
Y-349154D01*
Y-349121D01*
Y-349089D01*
Y-349057D01*
Y-349025D01*
Y-348992D01*
Y-348960D01*
Y-348928D01*
Y-348896D01*
Y-348863D01*
Y-348831D01*
Y-348799D01*
Y-348766D01*
Y-348734D01*
Y-348702D01*
Y-348670D01*
Y-348638D01*
Y-348605D01*
Y-348573D01*
Y-348541D01*
Y-348508D01*
Y-348476D01*
Y-348444D01*
Y-348412D01*
Y-348379D01*
Y-348347D01*
Y-348315D01*
Y-348283D01*
Y-348250D01*
Y-348218D01*
Y-348186D01*
Y-348154D01*
Y-348121D01*
Y-348089D01*
Y-348057D01*
Y-348025D01*
Y-347992D01*
Y-347960D01*
Y-347928D01*
Y-347896D01*
Y-347863D01*
Y-347831D01*
Y-347799D01*
Y-347766D01*
Y-347734D01*
Y-347702D01*
Y-347670D01*
Y-347637D01*
Y-347605D01*
Y-347573D01*
Y-347541D01*
Y-347508D01*
Y-347476D01*
Y-347444D01*
Y-347411D01*
Y-347379D01*
Y-347347D01*
Y-347315D01*
Y-347283D01*
Y-347250D01*
Y-347218D01*
Y-347186D01*
Y-347153D01*
Y-347121D01*
Y-347089D01*
Y-347057D01*
Y-347024D01*
Y-346992D01*
Y-346960D01*
Y-346928D01*
Y-346895D01*
Y-346863D01*
Y-346831D01*
Y-346799D01*
Y-346766D01*
Y-346734D01*
Y-346702D01*
Y-346670D01*
Y-346637D01*
Y-346605D01*
Y-346573D01*
Y-346540D01*
Y-346508D01*
Y-346476D01*
Y-346444D01*
Y-346411D01*
Y-346379D01*
Y-346347D01*
Y-346315D01*
Y-346282D01*
Y-346250D01*
Y-346218D01*
Y-346186D01*
Y-346153D01*
Y-346121D01*
Y-346089D01*
Y-346057D01*
Y-346024D01*
Y-345992D01*
Y-345960D01*
Y-345928D01*
Y-345895D01*
Y-345863D01*
Y-345831D01*
Y-345798D01*
Y-345766D01*
Y-345734D01*
Y-345702D01*
Y-345669D01*
Y-345637D01*
Y-345605D01*
Y-345573D01*
Y-345540D01*
Y-345508D01*
Y-345476D01*
Y-345444D01*
Y-345411D01*
Y-345379D01*
Y-345347D01*
Y-345315D01*
Y-345282D01*
Y-345250D01*
Y-345218D01*
Y-345185D01*
Y-345153D01*
Y-345121D01*
Y-345089D01*
Y-345056D01*
Y-345024D01*
Y-344992D01*
Y-344960D01*
Y-344927D01*
Y-344895D01*
Y-344863D01*
Y-344831D01*
Y-344798D01*
Y-344766D01*
Y-344734D01*
Y-344702D01*
Y-344669D01*
Y-344637D01*
Y-344605D01*
Y-344572D01*
Y-344540D01*
Y-344508D01*
Y-344476D01*
Y-344443D01*
Y-344411D01*
Y-344379D01*
Y-344347D01*
Y-344314D01*
Y-344282D01*
Y-344250D01*
Y-344218D01*
Y-344185D01*
Y-344153D01*
Y-344121D01*
Y-344089D01*
Y-344056D01*
Y-344024D01*
Y-343992D01*
Y-343959D01*
Y-343927D01*
Y-343895D01*
Y-343863D01*
Y-343830D01*
Y-343798D01*
Y-343766D01*
Y-343734D01*
Y-343701D01*
Y-343669D01*
Y-343637D01*
Y-343605D01*
Y-343572D01*
Y-343540D01*
Y-343508D01*
Y-343476D01*
Y-343443D01*
Y-343411D01*
Y-343379D01*
Y-343347D01*
Y-343314D01*
Y-343282D01*
Y-343250D01*
Y-343217D01*
Y-343185D01*
Y-343153D01*
Y-343121D01*
Y-343089D01*
Y-343056D01*
Y-343024D01*
Y-342992D01*
Y-342959D01*
Y-342927D01*
Y-342895D01*
Y-342863D01*
Y-342830D01*
Y-342798D01*
Y-342766D01*
Y-342734D01*
Y-342701D01*
Y-342669D01*
Y-342637D01*
Y-342604D01*
Y-342572D01*
Y-342540D01*
Y-342508D01*
Y-342476D01*
Y-342443D01*
Y-342411D01*
Y-342379D01*
Y-342346D01*
Y-342314D01*
Y-342282D01*
Y-342250D01*
Y-342217D01*
Y-342185D01*
Y-342153D01*
Y-342121D01*
Y-342088D01*
Y-342056D01*
Y-342024D01*
Y-341992D01*
Y-341959D01*
Y-341927D01*
Y-341895D01*
Y-341863D01*
Y-341830D01*
Y-341798D01*
Y-341766D01*
Y-341734D01*
Y-341701D01*
Y-341669D01*
Y-341637D01*
Y-341604D01*
Y-341572D01*
Y-341540D01*
Y-341508D01*
Y-341475D01*
Y-341443D01*
Y-341411D01*
Y-341379D01*
Y-341346D01*
Y-341314D01*
Y-341282D01*
Y-341249D01*
Y-341217D01*
Y-341185D01*
Y-341153D01*
Y-341121D01*
Y-341088D01*
Y-341056D01*
Y-341024D01*
Y-340991D01*
Y-340959D01*
Y-340927D01*
Y-340895D01*
Y-340862D01*
Y-340830D01*
Y-340798D01*
Y-340766D01*
Y-340733D01*
Y-340701D01*
Y-340669D01*
Y-340637D01*
Y-340604D01*
Y-340572D01*
Y-340540D01*
Y-340508D01*
Y-340475D01*
Y-340443D01*
Y-340411D01*
Y-340378D01*
Y-340346D01*
Y-340314D01*
Y-340282D01*
Y-340249D01*
Y-340217D01*
Y-340185D01*
Y-340153D01*
Y-340120D01*
Y-340088D01*
Y-340056D01*
Y-340024D01*
Y-339991D01*
Y-339959D01*
Y-339927D01*
Y-339895D01*
Y-339862D01*
Y-339830D01*
Y-339798D01*
Y-339766D01*
Y-339733D01*
Y-339701D01*
Y-339669D01*
Y-339636D01*
Y-339604D01*
Y-339572D01*
Y-339540D01*
Y-339507D01*
Y-339475D01*
Y-339443D01*
Y-339411D01*
Y-339378D01*
Y-339346D01*
Y-339314D01*
Y-339282D01*
Y-339249D01*
Y-339217D01*
Y-339185D01*
Y-339153D01*
Y-339120D01*
Y-339088D01*
Y-339056D01*
Y-339023D01*
Y-338991D01*
Y-338959D01*
Y-338927D01*
Y-338894D01*
Y-338862D01*
Y-338830D01*
Y-338798D01*
Y-338765D01*
Y-338733D01*
Y-338701D01*
Y-338669D01*
Y-338636D01*
Y-338604D01*
Y-338572D01*
Y-338540D01*
Y-338507D01*
Y-338475D01*
Y-338443D01*
Y-338410D01*
Y-338378D01*
Y-338346D01*
Y-338314D01*
Y-338281D01*
Y-338249D01*
Y-338217D01*
Y-338185D01*
Y-338152D01*
Y-338120D01*
Y-338088D01*
Y-338056D01*
Y-338023D01*
Y-337991D01*
Y-337959D01*
Y-337927D01*
Y-337894D01*
Y-337862D01*
Y-337830D01*
Y-337797D01*
Y-337765D01*
Y-337733D01*
Y-337701D01*
Y-337668D01*
Y-337636D01*
Y-337604D01*
Y-337572D01*
Y-337539D01*
Y-337507D01*
Y-337475D01*
Y-337443D01*
Y-337410D01*
Y-337378D01*
Y-337346D01*
Y-337314D01*
Y-337281D01*
Y-337249D01*
Y-337217D01*
Y-337185D01*
Y-337152D01*
Y-337120D01*
Y-337088D01*
Y-337055D01*
Y-337023D01*
Y-336991D01*
Y-336959D01*
Y-336927D01*
Y-336894D01*
Y-336862D01*
Y-336830D01*
Y-336797D01*
Y-336765D01*
Y-336733D01*
Y-336701D01*
Y-336668D01*
Y-336636D01*
Y-336604D01*
Y-336572D01*
Y-336539D01*
Y-336507D01*
Y-336475D01*
Y-336442D01*
Y-336410D01*
Y-336378D01*
Y-336346D01*
Y-336314D01*
Y-336281D01*
Y-336249D01*
Y-336217D01*
Y-336184D01*
Y-336152D01*
Y-336120D01*
Y-336088D01*
Y-336055D01*
Y-336023D01*
Y-335991D01*
Y-335959D01*
Y-335926D01*
Y-335894D01*
Y-335862D01*
Y-335830D01*
Y-335797D01*
Y-335765D01*
Y-335733D01*
Y-335700D01*
Y-335668D01*
Y-335636D01*
Y-335604D01*
Y-335572D01*
Y-335539D01*
Y-335507D01*
Y-335475D01*
Y-335442D01*
Y-335410D01*
Y-335378D01*
Y-335346D01*
Y-335313D01*
Y-335281D01*
Y-335249D01*
Y-335217D01*
Y-335184D01*
Y-335152D01*
Y-335120D01*
Y-335087D01*
Y-335055D01*
Y-335023D01*
Y-334991D01*
Y-334959D01*
Y-334926D01*
Y-334894D01*
Y-334862D01*
Y-334829D01*
Y-334797D01*
Y-334765D01*
Y-334733D01*
Y-334700D01*
Y-334668D01*
Y-334636D01*
Y-334604D01*
Y-334571D01*
Y-334539D01*
Y-334507D01*
Y-334474D01*
Y-334442D01*
Y-334410D01*
Y-334378D01*
Y-334346D01*
Y-334313D01*
Y-334281D01*
Y-334249D01*
Y-334216D01*
Y-334184D01*
Y-334152D01*
Y-334120D01*
Y-334087D01*
Y-334055D01*
Y-334023D01*
Y-333991D01*
Y-333958D01*
Y-333926D01*
Y-333894D01*
Y-333862D01*
Y-333829D01*
Y-333797D01*
Y-333765D01*
Y-333733D01*
Y-333700D01*
Y-333668D01*
Y-333636D01*
Y-333604D01*
Y-333571D01*
Y-333539D01*
Y-333507D01*
Y-333474D01*
Y-333442D01*
Y-333410D01*
Y-333378D01*
Y-333345D01*
Y-333313D01*
Y-333281D01*
Y-333249D01*
Y-333216D01*
Y-333184D01*
Y-333152D01*
Y-333120D01*
Y-333087D01*
Y-333055D01*
Y-333023D01*
Y-332991D01*
Y-332958D01*
Y-332926D01*
Y-332894D01*
Y-332861D01*
Y-332829D01*
Y-332797D01*
Y-332765D01*
Y-332732D01*
Y-332700D01*
Y-332668D01*
Y-332636D01*
Y-332603D01*
Y-332571D01*
Y-332539D01*
Y-332507D01*
Y-332474D01*
Y-332442D01*
Y-332410D01*
Y-332378D01*
Y-332345D01*
Y-332313D01*
Y-332281D01*
Y-332248D01*
Y-332216D01*
Y-332184D01*
Y-332152D01*
Y-332119D01*
Y-332087D01*
Y-332055D01*
Y-332023D01*
Y-331990D01*
Y-331958D01*
Y-331926D01*
Y-331894D01*
Y-331861D01*
Y-331829D01*
Y-331797D01*
Y-331765D01*
Y-331732D01*
Y-331700D01*
Y-331668D01*
Y-331635D01*
Y-331603D01*
Y-331571D01*
Y-331539D01*
Y-331506D01*
Y-331474D01*
Y-331442D01*
Y-331410D01*
Y-331377D01*
Y-331345D01*
Y-331313D01*
Y-331281D01*
Y-331248D01*
Y-331216D01*
Y-331184D01*
Y-331152D01*
Y-331119D01*
Y-331087D01*
Y-331055D01*
Y-331023D01*
Y-330990D01*
Y-330958D01*
Y-330926D01*
Y-330893D01*
Y-330861D01*
Y-330829D01*
Y-330797D01*
Y-330764D01*
Y-330732D01*
Y-330700D01*
Y-330668D01*
Y-330635D01*
Y-330603D01*
Y-330571D01*
Y-330539D01*
Y-330506D01*
Y-330474D01*
Y-330442D01*
Y-330410D01*
Y-330377D01*
Y-330345D01*
Y-330313D01*
Y-330280D01*
Y-330248D01*
Y-330216D01*
Y-330184D01*
Y-330152D01*
Y-330119D01*
Y-330087D01*
Y-330055D01*
Y-330022D01*
Y-329990D01*
Y-329958D01*
Y-329926D01*
Y-329893D01*
Y-329861D01*
Y-329829D01*
Y-329797D01*
Y-329764D01*
Y-329732D01*
Y-329700D01*
Y-329667D01*
Y-329635D01*
Y-329603D01*
Y-329571D01*
Y-329538D01*
Y-329506D01*
Y-329474D01*
Y-329442D01*
Y-329410D01*
Y-329377D01*
Y-329345D01*
Y-329313D01*
Y-329280D01*
Y-329248D01*
Y-329216D01*
Y-329184D01*
Y-329151D01*
Y-329119D01*
Y-329087D01*
Y-329055D01*
Y-329022D01*
Y-328990D01*
Y-328958D01*
Y-328925D01*
Y-328893D01*
Y-328861D01*
Y-328829D01*
Y-328797D01*
Y-328764D01*
Y-328732D01*
Y-328700D01*
Y-328667D01*
Y-328635D01*
Y-328603D01*
Y-328571D01*
Y-328538D01*
Y-328506D01*
Y-328474D01*
Y-328442D01*
Y-328409D01*
Y-328377D01*
Y-328345D01*
Y-328313D01*
Y-328280D01*
Y-328248D01*
Y-328216D01*
Y-328184D01*
Y-328151D01*
Y-328119D01*
Y-328087D01*
Y-328054D01*
Y-328022D01*
Y-327990D01*
Y-327958D01*
Y-327925D01*
Y-327893D01*
Y-327861D01*
Y-327829D01*
Y-327796D01*
Y-327764D01*
Y-327732D01*
X351043D01*
Y-327700D01*
Y-327667D01*
Y-327635D01*
Y-327603D01*
Y-327571D01*
X351010D01*
Y-327538D01*
Y-327506D01*
X350978D01*
Y-327474D01*
Y-327442D01*
X350946D01*
Y-327409D01*
Y-327377D01*
X350914D01*
Y-327345D01*
X350881D01*
Y-327312D01*
Y-327280D01*
X350849D01*
Y-327248D01*
X350817D01*
Y-327216D01*
X350785D01*
Y-327183D01*
X350720D01*
Y-327151D01*
X350688D01*
Y-327119D01*
X350623D01*
Y-327087D01*
X350559D01*
Y-327054D01*
X350494D01*
Y-327022D01*
X350365D01*
Y-326990D01*
X346268D01*
Y-326958D01*
Y-326925D01*
Y-326893D01*
Y-326861D01*
Y-326829D01*
Y-326796D01*
Y-326764D01*
Y-326732D01*
Y-326699D01*
Y-326667D01*
Y-326635D01*
Y-326603D01*
Y-326570D01*
Y-326538D01*
Y-326506D01*
Y-326474D01*
Y-326441D01*
Y-326409D01*
Y-326377D01*
Y-326345D01*
Y-326312D01*
Y-326280D01*
Y-326248D01*
Y-326216D01*
Y-326183D01*
Y-326151D01*
Y-326119D01*
Y-326086D01*
Y-326054D01*
Y-326022D01*
Y-325990D01*
Y-325957D01*
Y-325925D01*
Y-325893D01*
Y-325861D01*
Y-325828D01*
Y-325796D01*
Y-325764D01*
X350365D01*
Y-325796D01*
D02*
G37*
%LPC*%
G36*
X76272Y-136327D02*
X73902D01*
Y-138697D01*
X76272D01*
Y-136327D01*
D02*
G37*
G36*
X41941Y-137859D02*
X41421Y-138074D01*
X40915Y-138580D01*
X40703Y-139092D01*
X40179D01*
X39967Y-138580D01*
X39461Y-138074D01*
X38941Y-137859D01*
Y-139600D01*
Y-141341D01*
X39461Y-141126D01*
X39967Y-140620D01*
X40179Y-140108D01*
X40703D01*
X40915Y-140620D01*
X41421Y-141126D01*
X41941Y-141341D01*
Y-139600D01*
Y-137859D01*
D02*
G37*
G36*
X37941D02*
X37421Y-138074D01*
X36915Y-138580D01*
X36703Y-139092D01*
X36179D01*
X35967Y-138580D01*
X35461Y-138074D01*
X34941Y-137859D01*
Y-139600D01*
Y-141341D01*
X35461Y-141126D01*
X35967Y-140620D01*
X36179Y-140108D01*
X36703D01*
X36915Y-140620D01*
X37421Y-141126D01*
X37941Y-141341D01*
Y-139600D01*
Y-137859D01*
D02*
G37*
G36*
X33941D02*
X33421Y-138074D01*
X32915Y-138580D01*
X32703Y-139092D01*
X32179D01*
X31967Y-138580D01*
X31461Y-138074D01*
X30941Y-137859D01*
Y-139600D01*
Y-141341D01*
X31461Y-141126D01*
X31967Y-140620D01*
X32179Y-140108D01*
X32703D01*
X32915Y-140620D01*
X33421Y-141126D01*
X33941Y-141341D01*
Y-139600D01*
Y-137859D01*
D02*
G37*
G36*
X29941D02*
X29421Y-138074D01*
X28915Y-138580D01*
X28703Y-139092D01*
X28179D01*
X27967Y-138580D01*
X27461Y-138074D01*
X26941Y-137859D01*
Y-139600D01*
Y-141341D01*
X27461Y-141126D01*
X27967Y-140620D01*
X28179Y-140108D01*
X28703D01*
X28915Y-140620D01*
X29421Y-141126D01*
X29941Y-141341D01*
Y-139600D01*
Y-137859D01*
D02*
G37*
G36*
X25941D02*
X25421Y-138074D01*
X24915Y-138580D01*
X24703Y-139092D01*
X24179D01*
X23967Y-138580D01*
X23461Y-138074D01*
X22941Y-137859D01*
Y-139600D01*
Y-141341D01*
X23461Y-141126D01*
X23967Y-140620D01*
X24179Y-140108D01*
X24703D01*
X24915Y-140620D01*
X25421Y-141126D01*
X25941Y-141341D01*
Y-139600D01*
Y-137859D01*
D02*
G37*
G36*
X21941D02*
X21421Y-138074D01*
X20915Y-138580D01*
X20703Y-139092D01*
X20179D01*
X19967Y-138580D01*
X19461Y-138074D01*
X18941Y-137859D01*
Y-139600D01*
Y-141341D01*
X19461Y-141126D01*
X19967Y-140620D01*
X20179Y-140108D01*
X20703D01*
X20915Y-140620D01*
X21421Y-141126D01*
X21941Y-141341D01*
Y-139600D01*
Y-137859D01*
D02*
G37*
G36*
X17941D02*
X17421Y-138074D01*
X16915Y-138580D01*
X16703Y-139092D01*
X16179D01*
X15967Y-138580D01*
X15461Y-138074D01*
X14941Y-137859D01*
Y-139600D01*
Y-141341D01*
X15461Y-141126D01*
X15967Y-140620D01*
X16179Y-140108D01*
X16703D01*
X16915Y-140620D01*
X17421Y-141126D01*
X17941Y-141341D01*
Y-139600D01*
Y-137859D01*
D02*
G37*
G36*
X13941D02*
X13421Y-138074D01*
X12915Y-138580D01*
X12703Y-139092D01*
X12179D01*
X11967Y-138580D01*
X11461Y-138074D01*
X10941Y-137859D01*
Y-139600D01*
Y-141341D01*
X11461Y-141126D01*
X11967Y-140620D01*
X12179Y-140108D01*
X12703D01*
X12915Y-140620D01*
X13421Y-141126D01*
X13941Y-141341D01*
Y-139600D01*
Y-137859D01*
D02*
G37*
G36*
X9941D02*
X9421Y-138074D01*
X8915Y-138580D01*
X8703Y-139092D01*
X8179D01*
X7967Y-138580D01*
X7461Y-138074D01*
X6941Y-137859D01*
Y-139600D01*
Y-141341D01*
X7461Y-141126D01*
X7967Y-140620D01*
X8179Y-140108D01*
X8703D01*
X8915Y-140620D01*
X9421Y-141126D01*
X9941Y-141341D01*
Y-139600D01*
Y-137859D01*
D02*
G37*
G36*
X-6059D02*
X-6579Y-138074D01*
X-7085Y-138580D01*
X-7297Y-139092D01*
X-7821D01*
X-8033Y-138580D01*
X-8539Y-138074D01*
X-9059Y-137859D01*
Y-139600D01*
Y-141341D01*
X-8539Y-141126D01*
X-8033Y-140620D01*
X-7821Y-140108D01*
X-7297D01*
X-7085Y-140620D01*
X-6579Y-141126D01*
X-6059Y-141341D01*
Y-139600D01*
Y-137859D01*
D02*
G37*
G36*
X-10059D02*
X-10579Y-138074D01*
X-11085Y-138580D01*
X-11297Y-139092D01*
X-11821D01*
X-12033Y-138580D01*
X-12539Y-138074D01*
X-13059Y-137859D01*
Y-139600D01*
Y-141341D01*
X-12539Y-141126D01*
X-12033Y-140620D01*
X-11821Y-140108D01*
X-11297D01*
X-11085Y-140620D01*
X-10579Y-141126D01*
X-10059Y-141341D01*
Y-139600D01*
Y-137859D01*
D02*
G37*
G36*
X53941D02*
X53421Y-138074D01*
X52915Y-138580D01*
X52703Y-139092D01*
X52179D01*
X51967Y-138580D01*
X51461Y-138074D01*
X50941Y-137859D01*
Y-139600D01*
Y-141341D01*
X51461Y-141126D01*
X51967Y-140620D01*
X52179Y-140108D01*
X52703D01*
X52915Y-140620D01*
X53421Y-141126D01*
X53941Y-141341D01*
Y-139600D01*
Y-137859D01*
D02*
G37*
G36*
X49941D02*
X49421Y-138074D01*
X48915Y-138580D01*
X48703Y-139092D01*
X48179D01*
X47967Y-138580D01*
X47461Y-138074D01*
X46941Y-137859D01*
Y-139600D01*
Y-141341D01*
X47461Y-141126D01*
X47967Y-140620D01*
X48179Y-140108D01*
X48703D01*
X48915Y-140620D01*
X49421Y-141126D01*
X49941Y-141341D01*
Y-139600D01*
Y-137859D01*
D02*
G37*
G36*
X45941D02*
X45421Y-138074D01*
X44915Y-138580D01*
X44703Y-139092D01*
X44179D01*
X43967Y-138580D01*
X43461Y-138074D01*
X42941Y-137859D01*
Y-139600D01*
Y-141341D01*
X43461Y-141126D01*
X43967Y-140620D01*
X44179Y-140108D01*
X44703D01*
X44915Y-140620D01*
X45421Y-141126D01*
X45941Y-141341D01*
Y-139600D01*
Y-137859D01*
D02*
G37*
G36*
X54941D02*
Y-139100D01*
X56182D01*
X55967Y-138580D01*
X55461Y-138074D01*
X54941Y-137859D01*
D02*
G37*
G36*
X5941D02*
X5421Y-138074D01*
X4915Y-138580D01*
X4700Y-139100D01*
X5941D01*
Y-137859D01*
D02*
G37*
G36*
X-5059D02*
Y-139100D01*
X-3818D01*
X-4033Y-138580D01*
X-4539Y-138074D01*
X-5059Y-137859D01*
D02*
G37*
G36*
X-14059D02*
X-14579Y-138074D01*
X-15085Y-138580D01*
X-15300Y-139100D01*
X-14059D01*
Y-137859D01*
D02*
G37*
G36*
X-25059D02*
Y-139100D01*
X-23818D01*
X-24033Y-138580D01*
X-24539Y-138074D01*
X-25059Y-137859D01*
D02*
G37*
G36*
X56182Y-140100D02*
X54941D01*
Y-141341D01*
X55461Y-141126D01*
X55967Y-140620D01*
X56182Y-140100D01*
D02*
G37*
G36*
X5941D02*
X4700D01*
X4915Y-140620D01*
X5421Y-141126D01*
X5941Y-141341D01*
Y-140100D01*
D02*
G37*
G36*
X-3818D02*
X-5059D01*
Y-141341D01*
X-4539Y-141126D01*
X-4033Y-140620D01*
X-3818Y-140100D01*
D02*
G37*
G36*
X-14059D02*
X-15300D01*
X-15085Y-140620D01*
X-14579Y-141126D01*
X-14059Y-141341D01*
Y-140100D01*
D02*
G37*
G36*
X-23818D02*
X-25059D01*
Y-141341D01*
X-24539Y-141126D01*
X-24033Y-140620D01*
X-23818Y-140100D01*
D02*
G37*
G36*
X39941Y-141859D02*
X39421Y-142074D01*
X38915Y-142580D01*
X38703Y-143092D01*
X38179D01*
X37967Y-142580D01*
X37461Y-142074D01*
X36941Y-141859D01*
Y-143600D01*
Y-145341D01*
X37461Y-145126D01*
X37967Y-144620D01*
X38179Y-144108D01*
X38703D01*
X38915Y-144620D01*
X39421Y-145126D01*
X39941Y-145341D01*
Y-143600D01*
Y-141859D01*
D02*
G37*
G36*
X35941D02*
X35421Y-142074D01*
X34915Y-142580D01*
X34703Y-143092D01*
X34179D01*
X33967Y-142580D01*
X33461Y-142074D01*
X32941Y-141859D01*
Y-143600D01*
Y-145341D01*
X33461Y-145126D01*
X33967Y-144620D01*
X34179Y-144108D01*
X34703D01*
X34915Y-144620D01*
X35421Y-145126D01*
X35941Y-145341D01*
Y-143600D01*
Y-141859D01*
D02*
G37*
G36*
X31941D02*
X31421Y-142074D01*
X30915Y-142580D01*
X30703Y-143092D01*
X30179D01*
X29967Y-142580D01*
X29461Y-142074D01*
X28941Y-141859D01*
Y-143600D01*
Y-145341D01*
X29461Y-145126D01*
X29967Y-144620D01*
X30179Y-144108D01*
X30703D01*
X30915Y-144620D01*
X31421Y-145126D01*
X31941Y-145341D01*
Y-143600D01*
Y-141859D01*
D02*
G37*
G36*
X27941D02*
X27421Y-142074D01*
X26915Y-142580D01*
X26703Y-143092D01*
X26179D01*
X25967Y-142580D01*
X25461Y-142074D01*
X24941Y-141859D01*
Y-143600D01*
Y-145341D01*
X25461Y-145126D01*
X25967Y-144620D01*
X26179Y-144108D01*
X26703D01*
X26915Y-144620D01*
X27421Y-145126D01*
X27941Y-145341D01*
Y-143600D01*
Y-141859D01*
D02*
G37*
G36*
X23941D02*
X23421Y-142074D01*
X22915Y-142580D01*
X22703Y-143092D01*
X22179D01*
X21967Y-142580D01*
X21461Y-142074D01*
X20941Y-141859D01*
Y-143600D01*
Y-145341D01*
X21461Y-145126D01*
X21967Y-144620D01*
X22179Y-144108D01*
X22703D01*
X22915Y-144620D01*
X23421Y-145126D01*
X23941Y-145341D01*
Y-143600D01*
Y-141859D01*
D02*
G37*
G36*
X19941D02*
X19421Y-142074D01*
X18915Y-142580D01*
X18703Y-143092D01*
X18179D01*
X17967Y-142580D01*
X17461Y-142074D01*
X16941Y-141859D01*
Y-143600D01*
Y-145341D01*
X17461Y-145126D01*
X17967Y-144620D01*
X18179Y-144108D01*
X18703D01*
X18915Y-144620D01*
X19421Y-145126D01*
X19941Y-145341D01*
Y-143600D01*
Y-141859D01*
D02*
G37*
G36*
X15941D02*
X15421Y-142074D01*
X14915Y-142580D01*
X14703Y-143092D01*
X14179D01*
X13967Y-142580D01*
X13461Y-142074D01*
X12941Y-141859D01*
Y-143600D01*
Y-145341D01*
X13461Y-145126D01*
X13967Y-144620D01*
X14179Y-144108D01*
X14703D01*
X14915Y-144620D01*
X15421Y-145126D01*
X15941Y-145341D01*
Y-143600D01*
Y-141859D01*
D02*
G37*
G36*
X55941D02*
X55421Y-142074D01*
X54915Y-142580D01*
X54703Y-143092D01*
X54179D01*
X53967Y-142580D01*
X53461Y-142074D01*
X52941Y-141859D01*
Y-143600D01*
Y-145341D01*
X53461Y-145126D01*
X53967Y-144620D01*
X54179Y-144108D01*
X54703D01*
X54915Y-144620D01*
X55421Y-145126D01*
X55941Y-145341D01*
Y-143600D01*
Y-141859D01*
D02*
G37*
G36*
X51941D02*
X51421Y-142074D01*
X50915Y-142580D01*
X50703Y-143092D01*
X50179D01*
X49967Y-142580D01*
X49461Y-142074D01*
X48941Y-141859D01*
Y-143600D01*
Y-145341D01*
X49461Y-145126D01*
X49967Y-144620D01*
X50179Y-144108D01*
X50703D01*
X50915Y-144620D01*
X51421Y-145126D01*
X51941Y-145341D01*
Y-143600D01*
Y-141859D01*
D02*
G37*
G36*
X47941D02*
X47421Y-142074D01*
X46915Y-142580D01*
X46703Y-143092D01*
X46179D01*
X45967Y-142580D01*
X45461Y-142074D01*
X44941Y-141859D01*
Y-143600D01*
X43941D01*
Y-141859D01*
X43421Y-142074D01*
X42915Y-142580D01*
X42703Y-143092D01*
X42179D01*
X41967Y-142580D01*
X41461Y-142074D01*
X40941Y-141859D01*
Y-143600D01*
Y-145341D01*
X41461Y-145126D01*
X41967Y-144620D01*
X42179Y-144108D01*
X42703D01*
X42915Y-144620D01*
X43421Y-145126D01*
X43933Y-145338D01*
X43933Y-145688D01*
X43883Y-145859D01*
X43272Y-146112D01*
X42765Y-146618D01*
X42550Y-147138D01*
X46033D01*
X45817Y-146618D01*
X45311Y-146112D01*
X44799Y-145900D01*
X44799Y-145550D01*
X44849Y-145379D01*
X45461Y-145126D01*
X45967Y-144620D01*
X46179Y-144108D01*
X46703D01*
X46915Y-144620D01*
X47421Y-145126D01*
X47941Y-145341D01*
Y-143600D01*
Y-141859D01*
D02*
G37*
G36*
X56941D02*
Y-143100D01*
X58182D01*
X57967Y-142580D01*
X57461Y-142074D01*
X56941Y-141859D01*
D02*
G37*
G36*
X11941D02*
X11421Y-142074D01*
X10915Y-142580D01*
X10700Y-143100D01*
X11941D01*
Y-141859D01*
D02*
G37*
G36*
X-7059D02*
Y-143100D01*
X-5818D01*
X-6033Y-142580D01*
X-6539Y-142074D01*
X-7059Y-141859D01*
D02*
G37*
G36*
X-8059D02*
X-8579Y-142074D01*
X-9085Y-142580D01*
X-9300Y-143100D01*
X-8059D01*
Y-141859D01*
D02*
G37*
G36*
X58182Y-144100D02*
X56941D01*
Y-145341D01*
X57461Y-145126D01*
X57967Y-144620D01*
X58182Y-144100D01*
D02*
G37*
G36*
X11941D02*
X10700D01*
X10915Y-144620D01*
X11421Y-145126D01*
X11941Y-145341D01*
Y-144100D01*
D02*
G37*
G36*
X-5818D02*
X-7059D01*
Y-145341D01*
X-6539Y-145126D01*
X-6033Y-144620D01*
X-5818Y-144100D01*
D02*
G37*
G36*
X-8059D02*
X-9300D01*
X-9085Y-144620D01*
X-8579Y-145126D01*
X-8059Y-145341D01*
Y-144100D01*
D02*
G37*
G36*
X2237Y-142002D02*
X2035D01*
Y-146832D01*
X6866D01*
Y-146631D01*
X6503Y-145275D01*
X5801Y-144059D01*
X4809Y-143067D01*
X3593Y-142365D01*
X2237Y-142002D01*
D02*
G37*
G36*
X-17763D02*
X-17965D01*
Y-146832D01*
X-13134D01*
Y-146631D01*
X-13497Y-145275D01*
X-14199Y-144059D01*
X-15191Y-143067D01*
X-16407Y-142365D01*
X-17763Y-142002D01*
D02*
G37*
G36*
X1035D02*
X834D01*
X-522Y-142365D01*
X-1738Y-143067D01*
X-2730Y-144059D01*
X-3432Y-145275D01*
X-3795Y-146631D01*
Y-146832D01*
X1035D01*
Y-142002D01*
D02*
G37*
G36*
X-18965D02*
X-19166D01*
X-20522Y-142365D01*
X-21738Y-143067D01*
X-22730Y-144059D01*
X-23432Y-145275D01*
X-23795Y-146631D01*
Y-146832D01*
X-18965D01*
Y-142002D01*
D02*
G37*
G36*
X33941Y-145859D02*
X33421Y-146074D01*
X32915Y-146580D01*
X32703Y-147092D01*
X32179D01*
X31967Y-146580D01*
X31461Y-146074D01*
X30941Y-145859D01*
Y-147600D01*
Y-149341D01*
X31461Y-149126D01*
X31967Y-148620D01*
X32179Y-148108D01*
X32703D01*
X32915Y-148620D01*
X33421Y-149126D01*
X33941Y-149341D01*
Y-147600D01*
Y-145859D01*
D02*
G37*
G36*
X29941D02*
X29421Y-146074D01*
X28915Y-146580D01*
X28703Y-147092D01*
X28179D01*
X27967Y-146580D01*
X27461Y-146074D01*
X26941Y-145859D01*
Y-147600D01*
Y-149341D01*
X27461Y-149126D01*
X27967Y-148620D01*
X28179Y-148108D01*
X28703D01*
X28915Y-148620D01*
X29421Y-149126D01*
X29941Y-149341D01*
Y-147600D01*
Y-145859D01*
D02*
G37*
G36*
X25941D02*
X25421Y-146074D01*
X24915Y-146580D01*
X24703Y-147092D01*
X24179D01*
X23967Y-146580D01*
X23461Y-146074D01*
X22941Y-145859D01*
Y-147600D01*
Y-149341D01*
X23461Y-149126D01*
X23967Y-148620D01*
X24179Y-148108D01*
X24703D01*
X24915Y-148620D01*
X25421Y-149126D01*
X25941Y-149341D01*
Y-147600D01*
Y-145859D01*
D02*
G37*
G36*
X21941D02*
X21421Y-146074D01*
X20915Y-146580D01*
X20703Y-147092D01*
X20179D01*
X19967Y-146580D01*
X19461Y-146074D01*
X18941Y-145859D01*
Y-147600D01*
Y-149341D01*
X19461Y-149126D01*
X19967Y-148620D01*
X20179Y-148108D01*
X20703D01*
X20915Y-148620D01*
X21421Y-149126D01*
X21941Y-149341D01*
Y-147600D01*
Y-145859D01*
D02*
G37*
G36*
X17941D02*
X17421Y-146074D01*
X16915Y-146580D01*
X16703Y-147092D01*
X16179D01*
X15967Y-146580D01*
X15461Y-146074D01*
X14941Y-145859D01*
Y-147600D01*
Y-149341D01*
X15461Y-149126D01*
X15967Y-148620D01*
X16179Y-148108D01*
X16703D01*
X16915Y-148620D01*
X17421Y-149126D01*
X17941Y-149341D01*
Y-147600D01*
Y-145859D01*
D02*
G37*
G36*
X54941D02*
Y-147100D01*
X56182D01*
X55967Y-146580D01*
X55461Y-146074D01*
X54941Y-145859D01*
D02*
G37*
G36*
X53941D02*
X53421Y-146074D01*
X52915Y-146580D01*
X52700Y-147100D01*
X53941D01*
Y-145859D01*
D02*
G37*
G36*
X34941D02*
Y-147100D01*
X36182D01*
X35967Y-146580D01*
X35461Y-146074D01*
X34941Y-145859D01*
D02*
G37*
G36*
X13941D02*
X13421Y-146074D01*
X12915Y-146580D01*
X12700Y-147100D01*
X13941D01*
Y-145859D01*
D02*
G37*
G36*
X72350Y-145897D02*
Y-147138D01*
X73592D01*
X73376Y-146618D01*
X72870Y-146112D01*
X72350Y-145897D01*
D02*
G37*
G36*
X71350D02*
X70831Y-146112D01*
X70324Y-146618D01*
X70109Y-147138D01*
X71350D01*
Y-145897D01*
D02*
G37*
G36*
X56182Y-148100D02*
X54941D01*
Y-149341D01*
X55461Y-149126D01*
X55967Y-148620D01*
X56182Y-148100D01*
D02*
G37*
G36*
X53941D02*
X52700D01*
X52915Y-148620D01*
X53421Y-149126D01*
X53941Y-149341D01*
Y-148100D01*
D02*
G37*
G36*
X36182D02*
X34941D01*
Y-149341D01*
X35461Y-149126D01*
X35967Y-148620D01*
X36182Y-148100D01*
D02*
G37*
G36*
X13941D02*
X12700D01*
X12915Y-148620D01*
X13421Y-149126D01*
X13941Y-149341D01*
Y-148100D01*
D02*
G37*
G36*
X35941Y-149859D02*
X35421Y-150074D01*
X34915Y-150580D01*
X34703Y-151092D01*
X34179D01*
X33967Y-150580D01*
X33461Y-150074D01*
X32941Y-149859D01*
Y-151600D01*
Y-153341D01*
X33461Y-153126D01*
X33967Y-152620D01*
X34179Y-152108D01*
X34703D01*
X34915Y-152620D01*
X35421Y-153126D01*
X35941Y-153341D01*
Y-151600D01*
Y-149859D01*
D02*
G37*
G36*
X31941D02*
X31421Y-150074D01*
X30915Y-150580D01*
X30703Y-151092D01*
X30179D01*
X29967Y-150580D01*
X29461Y-150074D01*
X28941Y-149859D01*
Y-151600D01*
Y-153341D01*
X29461Y-153126D01*
X29967Y-152620D01*
X30179Y-152108D01*
X30703D01*
X30915Y-152620D01*
X31421Y-153126D01*
X31941Y-153341D01*
Y-151600D01*
Y-149859D01*
D02*
G37*
G36*
X27941D02*
X27421Y-150074D01*
X26915Y-150580D01*
X26703Y-151092D01*
X26179D01*
X25967Y-150580D01*
X25461Y-150074D01*
X24941Y-149859D01*
Y-151600D01*
Y-153341D01*
X25461Y-153126D01*
X25967Y-152620D01*
X26179Y-152108D01*
X26703D01*
X26915Y-152620D01*
X27421Y-153126D01*
X27941Y-153341D01*
Y-151600D01*
Y-149859D01*
D02*
G37*
G36*
X23941D02*
X23421Y-150074D01*
X22915Y-150580D01*
X22703Y-151092D01*
X22179D01*
X21967Y-150580D01*
X21461Y-150074D01*
X20941Y-149859D01*
Y-151600D01*
Y-153341D01*
X21461Y-153126D01*
X21967Y-152620D01*
X22179Y-152108D01*
X22703D01*
X22915Y-152620D01*
X23421Y-153126D01*
X23941Y-153341D01*
Y-151600D01*
Y-149859D01*
D02*
G37*
G36*
X19941D02*
X19421Y-150074D01*
X18915Y-150580D01*
X18703Y-151092D01*
X18179D01*
X17967Y-150580D01*
X17461Y-150074D01*
X16941Y-149859D01*
Y-151600D01*
Y-153341D01*
X17461Y-153126D01*
X17967Y-152620D01*
X18179Y-152108D01*
X18703D01*
X18915Y-152620D01*
X19421Y-153126D01*
X19941Y-153341D01*
Y-151600D01*
Y-149859D01*
D02*
G37*
G36*
X15941D02*
X15421Y-150074D01*
X14915Y-150580D01*
X14703Y-151092D01*
X14179D01*
X13967Y-150580D01*
X13461Y-150074D01*
X12941Y-149859D01*
Y-151600D01*
Y-153341D01*
X13461Y-153126D01*
X13967Y-152620D01*
X14179Y-152108D01*
X14703D01*
X14915Y-152620D01*
X15421Y-153126D01*
X15941Y-153341D01*
Y-151600D01*
Y-149859D01*
D02*
G37*
G36*
X55941D02*
X55421Y-150074D01*
X54915Y-150580D01*
X54703Y-151092D01*
X54179D01*
X53967Y-150580D01*
X53461Y-150074D01*
X52941Y-149859D01*
Y-151600D01*
Y-153341D01*
X53461Y-153126D01*
X53967Y-152620D01*
X54179Y-152108D01*
X54703D01*
X54915Y-152620D01*
X55421Y-153126D01*
X55941Y-153341D01*
Y-151600D01*
Y-149859D01*
D02*
G37*
G36*
X56941D02*
Y-151100D01*
X58182D01*
X57967Y-150580D01*
X57461Y-150074D01*
X56941Y-149859D01*
D02*
G37*
G36*
X51941D02*
X51421Y-150074D01*
X50915Y-150580D01*
X50700Y-151100D01*
X51941D01*
Y-149859D01*
D02*
G37*
G36*
X36941D02*
Y-151100D01*
X38182D01*
X37967Y-150580D01*
X37461Y-150074D01*
X36941Y-149859D01*
D02*
G37*
G36*
X11941D02*
X11421Y-150074D01*
X10915Y-150580D01*
X10700Y-151100D01*
X11941D01*
Y-149859D01*
D02*
G37*
G36*
X46033Y-148138D02*
X42550D01*
X42572Y-148191D01*
X42294Y-148606D01*
X38961D01*
Y-151173D01*
X44291D01*
X49622D01*
Y-148606D01*
X46288D01*
X46011Y-148191D01*
X46033Y-148138D01*
D02*
G37*
G36*
X6866Y-147832D02*
X2035D01*
Y-152663D01*
X2237D01*
X3593Y-152300D01*
X4809Y-151598D01*
X5801Y-150605D01*
X6503Y-149390D01*
X6866Y-148034D01*
Y-147832D01*
D02*
G37*
G36*
X1035D02*
X-3795D01*
Y-148034D01*
X-3432Y-149390D01*
X-2730Y-150605D01*
X-1738Y-151598D01*
X-522Y-152300D01*
X834Y-152663D01*
X1035D01*
Y-147832D01*
D02*
G37*
G36*
X-13134D02*
X-17965D01*
Y-152663D01*
X-17763D01*
X-16407Y-152300D01*
X-15191Y-151598D01*
X-14199Y-150605D01*
X-13497Y-149390D01*
X-13134Y-148034D01*
Y-147832D01*
D02*
G37*
G36*
X-18965D02*
X-23795D01*
Y-148034D01*
X-23432Y-149390D01*
X-22730Y-150605D01*
X-21738Y-151598D01*
X-20522Y-152300D01*
X-19166Y-152663D01*
X-18965D01*
Y-147832D01*
D02*
G37*
G36*
X58182Y-152100D02*
X56941D01*
Y-153341D01*
X57461Y-153126D01*
X57967Y-152620D01*
X58182Y-152100D01*
D02*
G37*
G36*
X51941D02*
X50700D01*
X50915Y-152620D01*
X51421Y-153126D01*
X51941Y-153341D01*
Y-152100D01*
D02*
G37*
G36*
X38182D02*
X36941D01*
Y-153341D01*
X37461Y-153126D01*
X37967Y-152620D01*
X38182Y-152100D01*
D02*
G37*
G36*
X11941D02*
X10700D01*
X10915Y-152620D01*
X11421Y-153126D01*
X11941Y-153341D01*
Y-152100D01*
D02*
G37*
G36*
X49622Y-152173D02*
X44791D01*
Y-154740D01*
X49622D01*
Y-152173D01*
D02*
G37*
G36*
X-25059Y-153859D02*
Y-155100D01*
X-23818D01*
X-24033Y-154580D01*
X-24539Y-154074D01*
X-25059Y-153859D01*
D02*
G37*
G36*
X43791Y-152173D02*
X38961D01*
Y-154512D01*
X35221D01*
Y-155905D01*
X-3528D01*
Y-152395D01*
X-13402D01*
Y-162269D01*
X-3528D01*
Y-158760D01*
X35221D01*
Y-160449D01*
X36860D01*
Y-171638D01*
X35221D01*
Y-179150D01*
X41157D01*
Y-171638D01*
X39715D01*
Y-166354D01*
X42294D01*
X42572Y-166770D01*
X42550Y-166823D01*
X46033D01*
X46011Y-166770D01*
X46288Y-166354D01*
X49622D01*
Y-163787D01*
X44291D01*
Y-163287D01*
X43791D01*
Y-160221D01*
X41354D01*
Y-158908D01*
X51953D01*
Y-160252D01*
X56709D01*
Y-154709D01*
X51953D01*
Y-156053D01*
X41354D01*
Y-154740D01*
X43791D01*
Y-152173D01*
D02*
G37*
G36*
X83677Y-154905D02*
X81504D01*
Y-155996D01*
X83677D01*
Y-154905D01*
D02*
G37*
G36*
X-23818Y-156100D02*
X-25059D01*
Y-157341D01*
X-24539Y-157126D01*
X-24033Y-156620D01*
X-23818Y-156100D01*
D02*
G37*
G36*
X-23059Y-157859D02*
Y-159100D01*
X-21818D01*
X-22033Y-158580D01*
X-22539Y-158074D01*
X-23059Y-157859D01*
D02*
G37*
G36*
X-24059D02*
X-24579Y-158074D01*
X-25085Y-158580D01*
X-25300Y-159100D01*
X-24059D01*
Y-157859D01*
D02*
G37*
G36*
X-21818Y-160100D02*
X-23059D01*
Y-161341D01*
X-22539Y-161126D01*
X-22033Y-160620D01*
X-21818Y-160100D01*
D02*
G37*
G36*
X-24059D02*
X-25300D01*
X-25085Y-160620D01*
X-24579Y-161126D01*
X-24059Y-161341D01*
Y-160100D01*
D02*
G37*
G36*
X49622Y-160221D02*
X44791D01*
Y-162787D01*
X49622D01*
Y-160221D01*
D02*
G37*
G36*
X33941Y-161859D02*
X33421Y-162074D01*
X32915Y-162580D01*
X32703Y-163092D01*
X32179D01*
X31967Y-162580D01*
X31461Y-162074D01*
X30941Y-161859D01*
Y-163600D01*
Y-165341D01*
X31461Y-165126D01*
X31967Y-164620D01*
X32179Y-164108D01*
X32703D01*
X32915Y-164620D01*
X33421Y-165126D01*
X33941Y-165341D01*
Y-163600D01*
Y-161859D01*
D02*
G37*
G36*
X29941D02*
X29421Y-162074D01*
X28915Y-162580D01*
X28703Y-163092D01*
X28179D01*
X27967Y-162580D01*
X27461Y-162074D01*
X26941Y-161859D01*
Y-163600D01*
Y-165341D01*
X27461Y-165126D01*
X27967Y-164620D01*
X28179Y-164108D01*
X28703D01*
X28915Y-164620D01*
X29421Y-165126D01*
X29941Y-165341D01*
Y-163600D01*
Y-161859D01*
D02*
G37*
G36*
X25941D02*
X25421Y-162074D01*
X24915Y-162580D01*
X24703Y-163092D01*
X24179D01*
X23967Y-162580D01*
X23461Y-162074D01*
X22941Y-161859D01*
Y-163600D01*
Y-165341D01*
X23461Y-165126D01*
X23967Y-164620D01*
X24179Y-164108D01*
X24703D01*
X24915Y-164620D01*
X25421Y-165126D01*
X25941Y-165341D01*
Y-163600D01*
Y-161859D01*
D02*
G37*
G36*
X21941D02*
X21421Y-162074D01*
X20915Y-162580D01*
X20703Y-163092D01*
X20179D01*
X19967Y-162580D01*
X19461Y-162074D01*
X18941Y-161859D01*
Y-163600D01*
Y-165341D01*
X19461Y-165126D01*
X19967Y-164620D01*
X20179Y-164108D01*
X20703D01*
X20915Y-164620D01*
X21421Y-165126D01*
X21941Y-165341D01*
Y-163600D01*
Y-161859D01*
D02*
G37*
G36*
X17941D02*
X17421Y-162074D01*
X16915Y-162580D01*
X16703Y-163092D01*
X16179D01*
X15967Y-162580D01*
X15461Y-162074D01*
X14941Y-161859D01*
Y-163600D01*
Y-165341D01*
X15461Y-165126D01*
X15967Y-164620D01*
X16179Y-164108D01*
X16703D01*
X16915Y-164620D01*
X17421Y-165126D01*
X17941Y-165341D01*
Y-163600D01*
Y-161859D01*
D02*
G37*
G36*
X13941D02*
X13421Y-162074D01*
X12915Y-162580D01*
X12703Y-163092D01*
X12179D01*
X11967Y-162580D01*
X11461Y-162074D01*
X10941Y-161859D01*
Y-163600D01*
Y-165341D01*
X11461Y-165126D01*
X11967Y-164620D01*
X12179Y-164108D01*
X12703D01*
X12915Y-164620D01*
X13421Y-165126D01*
X13941Y-165341D01*
Y-163600D01*
Y-161859D01*
D02*
G37*
G36*
X34941D02*
Y-163100D01*
X36182D01*
X35967Y-162580D01*
X35461Y-162074D01*
X34941Y-161859D01*
D02*
G37*
G36*
X9941D02*
X9421Y-162074D01*
X8915Y-162580D01*
X8700Y-163100D01*
X9941D01*
Y-161859D01*
D02*
G37*
G36*
X36182Y-164100D02*
X34941D01*
Y-165341D01*
X35461Y-165126D01*
X35967Y-164620D01*
X36182Y-164100D01*
D02*
G37*
G36*
X9941D02*
X8700D01*
X8915Y-164620D01*
X9421Y-165126D01*
X9941Y-165341D01*
Y-164100D01*
D02*
G37*
G36*
X2237Y-162002D02*
X2035D01*
Y-166832D01*
X6866D01*
Y-166630D01*
X6503Y-165275D01*
X5801Y-164059D01*
X4809Y-163067D01*
X3593Y-162365D01*
X2237Y-162002D01*
D02*
G37*
G36*
X-17763D02*
X-17965D01*
Y-166832D01*
X-13134D01*
Y-166630D01*
X-13497Y-165275D01*
X-14199Y-164059D01*
X-15191Y-163067D01*
X-16407Y-162365D01*
X-17763Y-162002D01*
D02*
G37*
G36*
X1035D02*
X834D01*
X-522Y-162365D01*
X-1738Y-163067D01*
X-2730Y-164059D01*
X-3432Y-165275D01*
X-3795Y-166630D01*
Y-166832D01*
X1035D01*
Y-162002D01*
D02*
G37*
G36*
X-18965D02*
X-19166D01*
X-20522Y-162365D01*
X-21738Y-163067D01*
X-22730Y-164059D01*
X-23432Y-165275D01*
X-23795Y-166630D01*
Y-166832D01*
X-18965D01*
Y-162002D01*
D02*
G37*
G36*
X27941Y-165859D02*
X27421Y-166074D01*
X26915Y-166580D01*
X26703Y-167092D01*
X26179D01*
X25967Y-166580D01*
X25461Y-166074D01*
X24941Y-165859D01*
Y-167600D01*
Y-169341D01*
X25461Y-169126D01*
X25967Y-168620D01*
X26179Y-168108D01*
X26703D01*
X26915Y-168620D01*
X27421Y-169126D01*
X28083Y-169400D01*
X28385D01*
X28719Y-169900D01*
X28712Y-169918D01*
Y-170634D01*
X28921Y-171138D01*
X28717Y-171552D01*
X28628Y-171638D01*
X27740D01*
Y-179150D01*
X33677D01*
Y-171638D01*
X32238D01*
Y-170812D01*
X32312Y-170634D01*
Y-169918D01*
X32038Y-169256D01*
X31531Y-168750D01*
X30870Y-168476D01*
X30568D01*
X30317Y-168100D01*
X28441D01*
Y-167600D01*
X27941D01*
Y-165859D01*
D02*
G37*
G36*
X23941D02*
X23421Y-166074D01*
X22915Y-166580D01*
X22703Y-167092D01*
X22179D01*
X21967Y-166580D01*
X21461Y-166074D01*
X20941Y-165859D01*
Y-167600D01*
Y-169341D01*
X21461Y-169126D01*
X21967Y-168620D01*
X22179Y-168108D01*
X22703D01*
X22915Y-168620D01*
X23421Y-169126D01*
X23941Y-169341D01*
Y-167600D01*
Y-165859D01*
D02*
G37*
G36*
X19941D02*
X19421Y-166074D01*
X18915Y-166580D01*
X18703Y-167092D01*
X18179D01*
X17967Y-166580D01*
X17461Y-166074D01*
X16941Y-165859D01*
Y-167600D01*
Y-169341D01*
X17461Y-169126D01*
X17967Y-168620D01*
X18179Y-168108D01*
X18703D01*
X18915Y-168620D01*
X19421Y-169126D01*
X19941Y-169341D01*
Y-167600D01*
Y-165859D01*
D02*
G37*
G36*
X15941D02*
X15421Y-166074D01*
X14915Y-166580D01*
X14703Y-167092D01*
X14179D01*
X13967Y-166580D01*
X13461Y-166074D01*
X12941Y-165859D01*
Y-167600D01*
Y-169341D01*
X13461Y-169126D01*
X13967Y-168620D01*
X14179Y-168108D01*
X14703D01*
X14915Y-168620D01*
X15421Y-169126D01*
X15941Y-169341D01*
Y-167600D01*
Y-165859D01*
D02*
G37*
G36*
X28941D02*
Y-167100D01*
X30182D01*
X29967Y-166580D01*
X29461Y-166074D01*
X28941Y-165859D01*
D02*
G37*
G36*
X11941D02*
X11421Y-166074D01*
X10915Y-166580D01*
X10700Y-167100D01*
X11941D01*
Y-165859D01*
D02*
G37*
G36*
X-7059D02*
Y-167100D01*
X-5818D01*
X-6033Y-166580D01*
X-6539Y-166074D01*
X-7059Y-165859D01*
D02*
G37*
G36*
X-8059D02*
X-8579Y-166074D01*
X-9085Y-166580D01*
X-9300Y-167100D01*
X-8059D01*
Y-165859D01*
D02*
G37*
G36*
X46033Y-167823D02*
X44791D01*
Y-169064D01*
X45311Y-168849D01*
X45817Y-168342D01*
X46033Y-167823D01*
D02*
G37*
G36*
X43791D02*
X42550D01*
X42765Y-168342D01*
X43272Y-168849D01*
X43791Y-169064D01*
Y-167823D01*
D02*
G37*
G36*
X11941Y-168100D02*
X10700D01*
X10915Y-168620D01*
X11421Y-169126D01*
X11941Y-169341D01*
Y-168100D01*
D02*
G37*
G36*
X-5818D02*
X-7059D01*
Y-169341D01*
X-6539Y-169126D01*
X-6033Y-168620D01*
X-5818Y-168100D01*
D02*
G37*
G36*
X-8059D02*
X-9300D01*
X-9085Y-168620D01*
X-8579Y-169126D01*
X-8059Y-169341D01*
Y-168100D01*
D02*
G37*
G36*
X21941Y-169859D02*
X21421Y-170074D01*
X20915Y-170580D01*
X20703Y-171092D01*
X20179D01*
X19967Y-170580D01*
X19461Y-170074D01*
X18941Y-169859D01*
Y-171600D01*
Y-173341D01*
X19461Y-173126D01*
X19967Y-172620D01*
X20179Y-172108D01*
X20703D01*
X20915Y-172620D01*
X21421Y-173126D01*
X21941Y-173341D01*
Y-171600D01*
Y-169859D01*
D02*
G37*
G36*
X17941D02*
X17421Y-170074D01*
X16915Y-170580D01*
X16703Y-171092D01*
X16179D01*
X15967Y-170580D01*
X15461Y-170074D01*
X14941Y-169859D01*
Y-171600D01*
Y-173341D01*
X15461Y-173126D01*
X15967Y-172620D01*
X16179Y-172108D01*
X16703D01*
X16915Y-172620D01*
X17421Y-173126D01*
X17941Y-173341D01*
Y-171600D01*
Y-169859D01*
D02*
G37*
G36*
X13941D02*
X13421Y-170074D01*
X12915Y-170580D01*
X12703Y-171092D01*
X12179D01*
X11967Y-170580D01*
X11461Y-170074D01*
X10941Y-169859D01*
Y-171600D01*
Y-173341D01*
X11461Y-173126D01*
X11967Y-172620D01*
X12179Y-172108D01*
X12703D01*
X12915Y-172620D01*
X13421Y-173126D01*
X13941Y-173341D01*
Y-171600D01*
Y-169859D01*
D02*
G37*
G36*
X22941D02*
Y-171100D01*
X24182D01*
X23967Y-170580D01*
X23461Y-170074D01*
X22941Y-169859D01*
D02*
G37*
G36*
X9941D02*
X9421Y-170074D01*
X8915Y-170580D01*
X8700Y-171100D01*
X9941D01*
Y-169859D01*
D02*
G37*
G36*
X-9059D02*
Y-171100D01*
X-7818D01*
X-8033Y-170580D01*
X-8539Y-170074D01*
X-9059Y-169859D01*
D02*
G37*
G36*
X-10059D02*
X-10579Y-170074D01*
X-11085Y-170580D01*
X-11300Y-171100D01*
X-10059D01*
Y-169859D01*
D02*
G37*
G36*
X6866Y-167832D02*
X2035D01*
Y-172663D01*
X2237D01*
X3593Y-172300D01*
X4809Y-171598D01*
X5801Y-170605D01*
X6503Y-169390D01*
X6866Y-168034D01*
Y-167832D01*
D02*
G37*
G36*
X1035D02*
X-3795D01*
Y-168034D01*
X-3432Y-169390D01*
X-2730Y-170605D01*
X-1738Y-171598D01*
X-522Y-172300D01*
X834Y-172663D01*
X1035D01*
Y-167832D01*
D02*
G37*
G36*
X-13134D02*
X-17965D01*
Y-172663D01*
X-17763D01*
X-16407Y-172300D01*
X-15191Y-171598D01*
X-14199Y-170605D01*
X-13497Y-169390D01*
X-13134Y-168034D01*
Y-167832D01*
D02*
G37*
G36*
X-18965D02*
X-23795D01*
Y-168034D01*
X-23432Y-169390D01*
X-22730Y-170605D01*
X-21738Y-171598D01*
X-20522Y-172300D01*
X-19166Y-172663D01*
X-18965D01*
Y-167832D01*
D02*
G37*
G36*
X24182Y-172100D02*
X22941D01*
Y-173341D01*
X23461Y-173126D01*
X23967Y-172620D01*
X24182Y-172100D01*
D02*
G37*
G36*
X9941D02*
X8700D01*
X8915Y-172620D01*
X9421Y-173126D01*
X9941Y-173341D01*
Y-172100D01*
D02*
G37*
G36*
X-7818D02*
X-9059D01*
Y-173341D01*
X-8539Y-173126D01*
X-8033Y-172620D01*
X-7818Y-172100D01*
D02*
G37*
G36*
X-10059D02*
X-11300D01*
X-11085Y-172620D01*
X-10579Y-173126D01*
X-10059Y-173341D01*
Y-172100D01*
D02*
G37*
G36*
X-15634Y-174591D02*
X-21177D01*
Y-175585D01*
X-22734D01*
X-23264Y-175365D01*
X-23980D01*
X-24642Y-175639D01*
X-25148Y-176146D01*
X-25422Y-176807D01*
Y-177523D01*
X-25148Y-178185D01*
X-24642Y-178691D01*
X-24227Y-178863D01*
Y-179404D01*
X-24642Y-179576D01*
X-25148Y-180083D01*
X-25422Y-180744D01*
Y-181460D01*
X-25148Y-182122D01*
X-24691Y-182579D01*
X-25148Y-183036D01*
X-25422Y-183697D01*
Y-184413D01*
X-25148Y-185075D01*
X-24642Y-185581D01*
X-24227Y-185753D01*
Y-186294D01*
X-24642Y-186466D01*
X-25148Y-186972D01*
X-25422Y-187634D01*
Y-188350D01*
X-25148Y-189012D01*
X-24642Y-189518D01*
X-24592Y-189539D01*
X-24579Y-190074D01*
X-25085Y-190580D01*
X-25300Y-191100D01*
X-21818D01*
X-22033Y-190580D01*
X-22539Y-190074D01*
X-22336Y-189624D01*
X-22139Y-189423D01*
X-21177D01*
Y-189976D01*
X-17188D01*
X-16981Y-190476D01*
X-17085Y-190580D01*
X-17300Y-191100D01*
X-15559D01*
Y-191600D01*
X-15059D01*
Y-193341D01*
X-14539Y-193126D01*
X-14033Y-192620D01*
X-13821Y-192108D01*
X-13297D01*
X-13085Y-192620D01*
X-12579Y-193126D01*
X-12059Y-193341D01*
Y-191600D01*
Y-189859D01*
X-12579Y-190074D01*
X-13085Y-190580D01*
X-13297Y-191092D01*
X-13821D01*
X-14033Y-190580D01*
X-14539Y-190074D01*
X-15201Y-189800D01*
X-15634D01*
Y-185614D01*
X-17602D01*
Y-182693D01*
Y-178953D01*
X-15634D01*
Y-174591D01*
D02*
G37*
G36*
X70315Y-179821D02*
X69073D01*
Y-181062D01*
X69593Y-180847D01*
X70099Y-180340D01*
X70315Y-179821D01*
D02*
G37*
G36*
X68073D02*
X66832D01*
X67048Y-180340D01*
X67554Y-180847D01*
X68073Y-181062D01*
Y-179821D01*
D02*
G37*
G36*
X30996Y-180299D02*
X27740D01*
Y-183555D01*
X30996D01*
Y-180299D01*
D02*
G37*
G36*
X23941Y-189859D02*
X23421Y-190074D01*
X22915Y-190580D01*
X22703Y-191092D01*
X22179D01*
X21967Y-190580D01*
X21461Y-190074D01*
X20941Y-189859D01*
Y-191600D01*
Y-193341D01*
X21461Y-193126D01*
X21967Y-192620D01*
X22179Y-192108D01*
X22703D01*
X22915Y-192620D01*
X23421Y-193126D01*
X23941Y-193341D01*
Y-191600D01*
Y-189859D01*
D02*
G37*
G36*
X19941D02*
X19421Y-190074D01*
X18915Y-190580D01*
X18703Y-191092D01*
X18179D01*
X17967Y-190580D01*
X17461Y-190074D01*
X16941Y-189859D01*
Y-191600D01*
Y-193341D01*
X17461Y-193126D01*
X17967Y-192620D01*
X18179Y-192108D01*
X18703D01*
X18915Y-192620D01*
X19421Y-193126D01*
X19941Y-193341D01*
Y-191600D01*
Y-189859D01*
D02*
G37*
G36*
X15941D02*
X15421Y-190074D01*
X14915Y-190580D01*
X14703Y-191092D01*
X14179D01*
X13967Y-190580D01*
X13461Y-190074D01*
X12941Y-189859D01*
Y-191600D01*
Y-193341D01*
X13461Y-193126D01*
X13967Y-192620D01*
X14179Y-192108D01*
X14703D01*
X14915Y-192620D01*
X15421Y-193126D01*
X15941Y-193341D01*
Y-191600D01*
Y-189859D01*
D02*
G37*
G36*
X11941D02*
X11421Y-190074D01*
X10915Y-190580D01*
X10703Y-191092D01*
X10179D01*
X9967Y-190580D01*
X9461Y-190074D01*
X8941Y-189859D01*
Y-191600D01*
Y-193341D01*
X9461Y-193126D01*
X9967Y-192620D01*
X10179Y-192108D01*
X10703D01*
X10915Y-192620D01*
X11421Y-193126D01*
X11941Y-193341D01*
Y-191600D01*
Y-189859D01*
D02*
G37*
G36*
X7941D02*
X7421Y-190074D01*
X6915Y-190580D01*
X6703Y-191092D01*
X6179D01*
X5967Y-190580D01*
X5461Y-190074D01*
X4941Y-189859D01*
Y-191600D01*
Y-193341D01*
X5461Y-193126D01*
X5967Y-192620D01*
X6179Y-192108D01*
X6703D01*
X6915Y-192620D01*
X7421Y-193126D01*
X7941Y-193341D01*
Y-191600D01*
Y-189859D01*
D02*
G37*
G36*
X-4059D02*
X-4579Y-190074D01*
X-5085Y-190580D01*
X-5297Y-191092D01*
X-5821D01*
X-6033Y-190580D01*
X-6539Y-190074D01*
X-7059Y-189859D01*
Y-191600D01*
Y-193341D01*
X-6539Y-193126D01*
X-6033Y-192620D01*
X-5821Y-192108D01*
X-5297D01*
X-5085Y-192620D01*
X-4579Y-193126D01*
X-4059Y-193341D01*
Y-191600D01*
Y-189859D01*
D02*
G37*
G36*
X-8059D02*
X-8579Y-190074D01*
X-9085Y-190580D01*
X-9297Y-191092D01*
X-9821D01*
X-10033Y-190580D01*
X-10539Y-190074D01*
X-11059Y-189859D01*
Y-191600D01*
Y-193341D01*
X-10539Y-193126D01*
X-10033Y-192620D01*
X-9821Y-192108D01*
X-9297D01*
X-9085Y-192620D01*
X-8579Y-193126D01*
X-8059Y-193341D01*
Y-191600D01*
Y-189859D01*
D02*
G37*
G36*
X55941D02*
X55421Y-190074D01*
X54915Y-190580D01*
X54703Y-191092D01*
X54179D01*
X53967Y-190580D01*
X53461Y-190074D01*
X52941Y-189859D01*
Y-191600D01*
Y-193341D01*
X53461Y-193126D01*
X53967Y-192620D01*
X54179Y-192108D01*
X54703D01*
X54915Y-192620D01*
X55421Y-193126D01*
X55941Y-193341D01*
Y-191600D01*
Y-189859D01*
D02*
G37*
G36*
X56941D02*
Y-191100D01*
X58182D01*
X57967Y-190580D01*
X57461Y-190074D01*
X56941Y-189859D01*
D02*
G37*
G36*
X51941D02*
X51421Y-190074D01*
X50915Y-190580D01*
X50700Y-191100D01*
X51941D01*
Y-189859D01*
D02*
G37*
G36*
X24941D02*
Y-191100D01*
X26182D01*
X25967Y-190580D01*
X25461Y-190074D01*
X24941Y-189859D01*
D02*
G37*
G36*
X3941D02*
X3421Y-190074D01*
X2915Y-190580D01*
X2700Y-191100D01*
X3941D01*
Y-189859D01*
D02*
G37*
G36*
X-3059D02*
Y-191100D01*
X-1818D01*
X-2033Y-190580D01*
X-2539Y-190074D01*
X-3059Y-189859D01*
D02*
G37*
G36*
X33237Y-190461D02*
X31996D01*
Y-191702D01*
X32516Y-191487D01*
X33022Y-190980D01*
X33237Y-190461D01*
D02*
G37*
G36*
X30996D02*
X29755D01*
X29970Y-190980D01*
X30476Y-191487D01*
X30996Y-191702D01*
Y-190461D01*
D02*
G37*
G36*
X58182Y-192100D02*
X56941D01*
Y-193341D01*
X57461Y-193126D01*
X57967Y-192620D01*
X58182Y-192100D01*
D02*
G37*
G36*
X51941D02*
X50700D01*
X50915Y-192620D01*
X51421Y-193126D01*
X51941Y-193341D01*
Y-192100D01*
D02*
G37*
G36*
X26182D02*
X24941D01*
Y-193341D01*
X25461Y-193126D01*
X25967Y-192620D01*
X26182Y-192100D01*
D02*
G37*
G36*
X3941D02*
X2700D01*
X2915Y-192620D01*
X3421Y-193126D01*
X3941Y-193341D01*
Y-192100D01*
D02*
G37*
G36*
X-1818D02*
X-3059D01*
Y-193341D01*
X-2539Y-193126D01*
X-2033Y-192620D01*
X-1818Y-192100D01*
D02*
G37*
G36*
X-16059D02*
X-17300D01*
X-17085Y-192620D01*
X-16579Y-193126D01*
X-16059Y-193341D01*
Y-192100D01*
D02*
G37*
G36*
X-21818D02*
X-23059D01*
Y-193341D01*
X-22539Y-193126D01*
X-22033Y-192620D01*
X-21818Y-192100D01*
D02*
G37*
G36*
X-24059D02*
X-25300D01*
X-25085Y-192620D01*
X-24579Y-193126D01*
X-24059Y-193341D01*
Y-192100D01*
D02*
G37*
G36*
X25941Y-193859D02*
X25421Y-194074D01*
X24915Y-194580D01*
X24703Y-195092D01*
X24179D01*
X23967Y-194580D01*
X23461Y-194074D01*
X22941Y-193859D01*
Y-195600D01*
Y-197341D01*
X23461Y-197126D01*
X23967Y-196620D01*
X24179Y-196108D01*
X24703D01*
X24915Y-196620D01*
X25421Y-197126D01*
X25941Y-197341D01*
Y-195600D01*
Y-193859D01*
D02*
G37*
G36*
X21941D02*
X21421Y-194074D01*
X20915Y-194580D01*
X20703Y-195092D01*
X20179D01*
X19967Y-194580D01*
X19461Y-194074D01*
X18941Y-193859D01*
Y-195600D01*
Y-197341D01*
X19461Y-197126D01*
X19967Y-196620D01*
X20179Y-196108D01*
X20703D01*
X20915Y-196620D01*
X21421Y-197126D01*
X21941Y-197341D01*
Y-195600D01*
Y-193859D01*
D02*
G37*
G36*
X17941D02*
X17421Y-194074D01*
X16915Y-194580D01*
X16703Y-195092D01*
X16179D01*
X15967Y-194580D01*
X15461Y-194074D01*
X14941Y-193859D01*
Y-195600D01*
Y-197341D01*
X15461Y-197126D01*
X15967Y-196620D01*
X16179Y-196108D01*
X16703D01*
X16915Y-196620D01*
X17421Y-197126D01*
X17941Y-197341D01*
Y-195600D01*
Y-193859D01*
D02*
G37*
G36*
X13941D02*
X13421Y-194074D01*
X12915Y-194580D01*
X12703Y-195092D01*
X12179D01*
X11967Y-194580D01*
X11461Y-194074D01*
X10941Y-193859D01*
Y-195600D01*
Y-197341D01*
X11461Y-197126D01*
X11967Y-196620D01*
X12179Y-196108D01*
X12703D01*
X12915Y-196620D01*
X13421Y-197126D01*
X13941Y-197341D01*
Y-195600D01*
Y-193859D01*
D02*
G37*
G36*
X53941D02*
X53421Y-194074D01*
X52915Y-194580D01*
X52703Y-195092D01*
X52179D01*
X51967Y-194580D01*
X51461Y-194074D01*
X50941Y-193859D01*
Y-195600D01*
Y-197341D01*
X51461Y-197126D01*
X51967Y-196620D01*
X52179Y-196108D01*
X52703D01*
X52915Y-196620D01*
X53421Y-197126D01*
X53941Y-197341D01*
Y-195600D01*
Y-193859D01*
D02*
G37*
G36*
X54941D02*
Y-195100D01*
X56182D01*
X55967Y-194580D01*
X55461Y-194074D01*
X54941Y-193859D01*
D02*
G37*
G36*
X49941D02*
X49421Y-194074D01*
X48915Y-194580D01*
X48700Y-195100D01*
X49941D01*
Y-193859D01*
D02*
G37*
G36*
X26941D02*
Y-195100D01*
X28182D01*
X27967Y-194580D01*
X27461Y-194074D01*
X26941Y-193859D01*
D02*
G37*
G36*
X9941D02*
X9421Y-194074D01*
X8915Y-194580D01*
X8700Y-195100D01*
X9941D01*
Y-193859D01*
D02*
G37*
G36*
X-9059D02*
Y-195100D01*
X-7818D01*
X-8033Y-194580D01*
X-8539Y-194074D01*
X-9059Y-193859D01*
D02*
G37*
G36*
X-10059D02*
X-10579Y-194074D01*
X-11085Y-194580D01*
X-11300Y-195100D01*
X-10059D01*
Y-193859D01*
D02*
G37*
G36*
X56182Y-196100D02*
X54941D01*
Y-197341D01*
X55461Y-197126D01*
X55967Y-196620D01*
X56182Y-196100D01*
D02*
G37*
G36*
X49941D02*
X48700D01*
X48915Y-196620D01*
X49421Y-197126D01*
X49941Y-197341D01*
Y-196100D01*
D02*
G37*
G36*
X28182D02*
X26941D01*
Y-197341D01*
X27461Y-197126D01*
X27967Y-196620D01*
X28182Y-196100D01*
D02*
G37*
G36*
X9941D02*
X8700D01*
X8915Y-196620D01*
X9421Y-197126D01*
X9941Y-197341D01*
Y-196100D01*
D02*
G37*
G36*
X-7818D02*
X-9059D01*
Y-197341D01*
X-8539Y-197126D01*
X-8033Y-196620D01*
X-7818Y-196100D01*
D02*
G37*
G36*
X-10059D02*
X-11300D01*
X-11085Y-196620D01*
X-10579Y-197126D01*
X-10059Y-197341D01*
Y-196100D01*
D02*
G37*
G36*
X19941Y-197859D02*
X19421Y-198074D01*
X18915Y-198580D01*
X18703Y-199092D01*
X18179D01*
X17967Y-198580D01*
X17461Y-198074D01*
X16941Y-197859D01*
Y-199600D01*
Y-201341D01*
X17461Y-201126D01*
X17967Y-200620D01*
X18179Y-200108D01*
X18703D01*
X18915Y-200620D01*
X19421Y-201126D01*
X19941Y-201341D01*
Y-199600D01*
Y-197859D01*
D02*
G37*
G36*
X15941D02*
X15421Y-198074D01*
X14915Y-198580D01*
X14703Y-199092D01*
X14179D01*
X13967Y-198580D01*
X13461Y-198074D01*
X12941Y-197859D01*
Y-199600D01*
Y-201341D01*
X13461Y-201126D01*
X13967Y-200620D01*
X14179Y-200108D01*
X14703D01*
X14915Y-200620D01*
X15421Y-201126D01*
X15941Y-201341D01*
Y-199600D01*
Y-197859D01*
D02*
G37*
G36*
X55941D02*
X55421Y-198074D01*
X54915Y-198580D01*
X54703Y-199092D01*
X54179D01*
X53967Y-198580D01*
X53461Y-198074D01*
X52941Y-197859D01*
Y-199600D01*
Y-201341D01*
X53461Y-201126D01*
X53967Y-200620D01*
X54179Y-200108D01*
X54703D01*
X54915Y-200620D01*
X55421Y-201126D01*
X55941Y-201341D01*
Y-199600D01*
Y-197859D01*
D02*
G37*
G36*
X56941D02*
Y-199100D01*
X58182D01*
X57967Y-198580D01*
X57461Y-198074D01*
X56941Y-197859D01*
D02*
G37*
G36*
X47941D02*
X47421Y-198074D01*
X46915Y-198580D01*
X46700Y-199100D01*
X47941D01*
Y-197859D01*
D02*
G37*
G36*
X20941D02*
Y-199100D01*
X22182D01*
X21967Y-198580D01*
X21461Y-198074D01*
X20941Y-197859D01*
D02*
G37*
G36*
X11941D02*
X11421Y-198074D01*
X10915Y-198580D01*
X10700Y-199100D01*
X11941D01*
Y-197859D01*
D02*
G37*
G36*
X-7059D02*
Y-199100D01*
X-5818D01*
X-6033Y-198580D01*
X-6539Y-198074D01*
X-7059Y-197859D01*
D02*
G37*
G36*
X-8059D02*
X-8579Y-198074D01*
X-9085Y-198580D01*
X-9300Y-199100D01*
X-8059D01*
Y-197859D01*
D02*
G37*
G36*
X-17763Y-195150D02*
X-17965D01*
Y-199980D01*
X-13134D01*
Y-199778D01*
X-13497Y-198423D01*
X-14199Y-197207D01*
X-15191Y-196215D01*
X-16407Y-195513D01*
X-17763Y-195150D01*
D02*
G37*
G36*
X2237D02*
X2035D01*
Y-199980D01*
X6866D01*
Y-199778D01*
X6503Y-198423D01*
X5801Y-197207D01*
X4809Y-196215D01*
X3593Y-195513D01*
X2237Y-195150D01*
D02*
G37*
G36*
X-18965D02*
X-19166D01*
X-20522Y-195513D01*
X-21738Y-196215D01*
X-22730Y-197207D01*
X-23432Y-198423D01*
X-23795Y-199778D01*
Y-199980D01*
X-18965D01*
Y-195150D01*
D02*
G37*
G36*
X1035D02*
X834D01*
X-522Y-195513D01*
X-1738Y-196215D01*
X-2730Y-197207D01*
X-3432Y-198423D01*
X-3795Y-199778D01*
Y-199980D01*
X1035D01*
Y-195150D01*
D02*
G37*
G36*
X44791Y-199046D02*
Y-200287D01*
X46033D01*
X45817Y-199768D01*
X45311Y-199261D01*
X44791Y-199046D01*
D02*
G37*
G36*
X43791D02*
X43272Y-199261D01*
X42765Y-199768D01*
X42550Y-200287D01*
X43791D01*
Y-199046D01*
D02*
G37*
G36*
X58182Y-200100D02*
X56941D01*
Y-201341D01*
X57461Y-201126D01*
X57967Y-200620D01*
X58182Y-200100D01*
D02*
G37*
G36*
X41157Y-180299D02*
X31996D01*
Y-184055D01*
X31496D01*
Y-184555D01*
X27740D01*
Y-187811D01*
X30069D01*
Y-188842D01*
X29970Y-188941D01*
X29755Y-189461D01*
X33237D01*
X33022Y-188941D01*
X32923Y-188842D01*
Y-187811D01*
X36762D01*
Y-207661D01*
X35221D01*
Y-209053D01*
X-3528D01*
Y-205543D01*
X-13402D01*
Y-215417D01*
X-3528D01*
Y-211908D01*
X35221D01*
Y-213598D01*
X35263D01*
X35388Y-213975D01*
X35397Y-214098D01*
X34915Y-214580D01*
X34700Y-215100D01*
X38182D01*
X37967Y-214580D01*
X37485Y-214098D01*
X37494Y-213975D01*
X37619Y-213598D01*
X38961D01*
Y-215937D01*
X43791D01*
Y-213370D01*
X41354D01*
Y-212057D01*
X52583D01*
X52937Y-212411D01*
X52937Y-213338D01*
X52900Y-213461D01*
X52696Y-213793D01*
X52608Y-213800D01*
X52083D01*
X51421Y-214074D01*
X50915Y-214580D01*
X50700Y-215100D01*
X52441D01*
Y-215600D01*
X52941D01*
Y-217341D01*
X53461Y-217126D01*
X53967Y-216620D01*
X54179Y-216108D01*
X54703D01*
X54915Y-216620D01*
X55421Y-217126D01*
X55941Y-217341D01*
Y-215600D01*
X56441D01*
Y-215100D01*
X58182D01*
X57967Y-214580D01*
X57461Y-214074D01*
X57044Y-213902D01*
X57144Y-213402D01*
X57693D01*
Y-207858D01*
X52937D01*
Y-209203D01*
X41354D01*
Y-207890D01*
X43791D01*
Y-204823D01*
X44291D01*
Y-204323D01*
X49622D01*
Y-201756D01*
X49246D01*
X49147Y-201256D01*
X49461Y-201126D01*
X49967Y-200620D01*
X50179Y-200108D01*
X50703D01*
X50915Y-200620D01*
X51421Y-201126D01*
X51941Y-201341D01*
Y-199600D01*
Y-197859D01*
X51421Y-198074D01*
X50915Y-198580D01*
X50703Y-199092D01*
X50179D01*
X49967Y-198580D01*
X49461Y-198074D01*
X48941Y-197859D01*
Y-199600D01*
X48441D01*
Y-200100D01*
X46700D01*
X46915Y-200620D01*
X47421Y-201126D01*
X47735Y-201256D01*
X47636Y-201756D01*
X46288D01*
X46011Y-201340D01*
X46033Y-201287D01*
X42550D01*
X42572Y-201340D01*
X42294Y-201756D01*
X39616D01*
Y-187811D01*
X41157D01*
Y-180299D01*
D02*
G37*
G36*
X22182Y-200100D02*
X20941D01*
Y-201341D01*
X21461Y-201126D01*
X21967Y-200620D01*
X22182Y-200100D01*
D02*
G37*
G36*
X11941D02*
X10700D01*
X10915Y-200620D01*
X11421Y-201126D01*
X11941Y-201341D01*
Y-200100D01*
D02*
G37*
G36*
X-5818D02*
X-7059D01*
Y-201341D01*
X-6539Y-201126D01*
X-6033Y-200620D01*
X-5818Y-200100D01*
D02*
G37*
G36*
X-8059D02*
X-9300D01*
X-9085Y-200620D01*
X-8579Y-201126D01*
X-8059Y-201341D01*
Y-200100D01*
D02*
G37*
G36*
X17941Y-201859D02*
X17421Y-202074D01*
X16915Y-202580D01*
X16703Y-203092D01*
X16179D01*
X15967Y-202580D01*
X15461Y-202074D01*
X14941Y-201859D01*
Y-203600D01*
Y-205341D01*
X15461Y-205126D01*
X15967Y-204620D01*
X16179Y-204108D01*
X16703D01*
X16915Y-204620D01*
X17421Y-205126D01*
X17941Y-205341D01*
Y-203600D01*
Y-201859D01*
D02*
G37*
G36*
X13941D02*
X13421Y-202074D01*
X12915Y-202580D01*
X12703Y-203092D01*
X12179D01*
X11967Y-202580D01*
X11461Y-202074D01*
X10941Y-201859D01*
Y-203600D01*
Y-205341D01*
X11461Y-205126D01*
X11967Y-204620D01*
X12179Y-204108D01*
X12703D01*
X12915Y-204620D01*
X13421Y-205126D01*
X13941Y-205341D01*
Y-203600D01*
Y-201859D01*
D02*
G37*
G36*
X54941D02*
Y-203100D01*
X56182D01*
X55967Y-202580D01*
X55461Y-202074D01*
X54941Y-201859D01*
D02*
G37*
G36*
X53941D02*
X53421Y-202074D01*
X52915Y-202580D01*
X52700Y-203100D01*
X53941D01*
Y-201859D01*
D02*
G37*
G36*
X18941D02*
Y-203100D01*
X20182D01*
X19967Y-202580D01*
X19461Y-202074D01*
X18941Y-201859D01*
D02*
G37*
G36*
X9941D02*
X9421Y-202074D01*
X8915Y-202580D01*
X8700Y-203100D01*
X9941D01*
Y-201859D01*
D02*
G37*
G36*
X81193Y-203967D02*
X80673Y-204183D01*
X80167Y-204689D01*
X79952Y-205209D01*
X81193D01*
Y-203967D01*
D02*
G37*
G36*
X56182Y-204100D02*
X54941D01*
Y-205341D01*
X55461Y-205126D01*
X55967Y-204620D01*
X56182Y-204100D01*
D02*
G37*
G36*
X53941D02*
X52700D01*
X52915Y-204620D01*
X53421Y-205126D01*
X53941Y-205341D01*
Y-204100D01*
D02*
G37*
G36*
X20182D02*
X18941D01*
Y-205341D01*
X19461Y-205126D01*
X19967Y-204620D01*
X20182Y-204100D01*
D02*
G37*
G36*
X9941D02*
X8700D01*
X8915Y-204620D01*
X9421Y-205126D01*
X9941Y-205341D01*
Y-204100D01*
D02*
G37*
G36*
X6866Y-200980D02*
X2035D01*
Y-205811D01*
X2237D01*
X3593Y-205448D01*
X4809Y-204746D01*
X5801Y-203753D01*
X6503Y-202538D01*
X6866Y-201182D01*
Y-200980D01*
D02*
G37*
G36*
X1035D02*
X-3795D01*
Y-201182D01*
X-3432Y-202538D01*
X-2730Y-203753D01*
X-1738Y-204746D01*
X-522Y-205448D01*
X834Y-205811D01*
X1035D01*
Y-200980D01*
D02*
G37*
G36*
X-13134D02*
X-17965D01*
Y-205811D01*
X-17763D01*
X-16407Y-205448D01*
X-15191Y-204746D01*
X-14199Y-203753D01*
X-13497Y-202538D01*
X-13134Y-201182D01*
Y-200980D01*
D02*
G37*
G36*
X-18965D02*
X-23795D01*
Y-201182D01*
X-23432Y-202538D01*
X-22730Y-203753D01*
X-21738Y-204746D01*
X-20522Y-205448D01*
X-19166Y-205811D01*
X-18965D01*
Y-200980D01*
D02*
G37*
G36*
X81193Y-206209D02*
X79952D01*
X80167Y-206728D01*
X80673Y-207235D01*
X81193Y-207450D01*
Y-206209D01*
D02*
G37*
G36*
X49622Y-205323D02*
X44791D01*
Y-207890D01*
X49622D01*
Y-205323D01*
D02*
G37*
G36*
X81488Y-208055D02*
X79315D01*
Y-209146D01*
X81488D01*
Y-208055D01*
D02*
G37*
G36*
X-22059Y-209859D02*
X-22579Y-210074D01*
X-23085Y-210580D01*
X-23297Y-211092D01*
X-23821D01*
X-24033Y-210580D01*
X-24539Y-210074D01*
X-25059Y-209859D01*
Y-211600D01*
Y-213341D01*
X-24539Y-213126D01*
X-24033Y-212620D01*
X-23821Y-212108D01*
X-23297D01*
X-23085Y-212620D01*
X-22579Y-213126D01*
X-22059Y-213341D01*
Y-211600D01*
Y-209859D01*
D02*
G37*
G36*
X-21059D02*
Y-211100D01*
X-19818D01*
X-20033Y-210580D01*
X-20539Y-210074D01*
X-21059Y-209859D01*
D02*
G37*
G36*
X-19818Y-212100D02*
X-21059D01*
Y-213341D01*
X-20539Y-213126D01*
X-20033Y-212620D01*
X-19818Y-212100D01*
D02*
G37*
G36*
X15941Y-213859D02*
X15421Y-214074D01*
X14915Y-214580D01*
X14703Y-215092D01*
X14179D01*
X13967Y-214580D01*
X13461Y-214074D01*
X12941Y-213859D01*
Y-215600D01*
Y-217341D01*
X13461Y-217126D01*
X13967Y-216620D01*
X14179Y-216108D01*
X14703D01*
X14915Y-216620D01*
X15421Y-217126D01*
X15941Y-217341D01*
Y-215600D01*
Y-213859D01*
D02*
G37*
G36*
X16941D02*
Y-215100D01*
X18182D01*
X17967Y-214580D01*
X17461Y-214074D01*
X16941Y-213859D01*
D02*
G37*
G36*
X11941D02*
X11421Y-214074D01*
X10915Y-214580D01*
X10700Y-215100D01*
X11941D01*
Y-213859D01*
D02*
G37*
G36*
X82193Y-203967D02*
Y-205709D01*
Y-207450D01*
X82713Y-207235D01*
X82811Y-207136D01*
X84054D01*
X84202Y-207284D01*
Y-208055D01*
X82488D01*
Y-209646D01*
X81988D01*
Y-210023D01*
X79315D01*
Y-211236D01*
Y-214124D01*
X79209D01*
X78663Y-214232D01*
X78199Y-214542D01*
X78199Y-214542D01*
X77731Y-215010D01*
X77643Y-215142D01*
X77112Y-215036D01*
X77106Y-215005D01*
X76797Y-214542D01*
X76797Y-214542D01*
X74828Y-212573D01*
X74365Y-212264D01*
X73819Y-212155D01*
X73819Y-212155D01*
X72260D01*
Y-208055D01*
X66913D01*
Y-208221D01*
X66383Y-208327D01*
X65920Y-208636D01*
X65920Y-208636D01*
X65354Y-209203D01*
X63205D01*
Y-207858D01*
X58449D01*
Y-213402D01*
X63205D01*
Y-212057D01*
X65354D01*
X65920Y-212624D01*
X66383Y-212933D01*
X66913Y-213038D01*
Y-217142D01*
X70692D01*
X70883Y-217604D01*
X69900Y-218587D01*
X65732D01*
Y-220124D01*
X65189D01*
X64996Y-219931D01*
X64334Y-219657D01*
X63618D01*
X62957Y-219931D01*
X62450Y-220437D01*
X62176Y-221099D01*
Y-221815D01*
X62450Y-222476D01*
X62957Y-222983D01*
X63618Y-223257D01*
X64334D01*
X64512Y-223183D01*
X65732D01*
Y-225935D01*
X65095D01*
X64996Y-225836D01*
X64476Y-225621D01*
Y-227362D01*
Y-229103D01*
X64996Y-228888D01*
X65095Y-228790D01*
X65732D01*
Y-230232D01*
X68398D01*
Y-227165D01*
X68898D01*
Y-226665D01*
X72063D01*
Y-224721D01*
Y-220749D01*
X72455Y-220357D01*
X72917Y-220549D01*
Y-224327D01*
X72917D01*
Y-224492D01*
X72917D01*
Y-230232D01*
X74258D01*
Y-231272D01*
X73987Y-231925D01*
Y-232642D01*
X74261Y-233303D01*
X74768Y-233809D01*
X75429Y-234084D01*
X76145D01*
X76807Y-233809D01*
X77313Y-233303D01*
X77587Y-232642D01*
Y-231925D01*
X77375Y-231413D01*
X77402Y-231346D01*
X77795Y-231352D01*
X77929Y-231377D01*
X78223Y-231816D01*
X79699Y-233293D01*
X79699Y-233293D01*
X80162Y-233602D01*
X80709Y-233711D01*
X81559D01*
X81658Y-233809D01*
X82319Y-234084D01*
X83035D01*
X83697Y-233809D01*
X84203Y-233303D01*
X84477Y-232642D01*
Y-231925D01*
X84203Y-231264D01*
X83697Y-230757D01*
X83636Y-230732D01*
X83735Y-230232D01*
X85547D01*
Y-229410D01*
X86047Y-229076D01*
X86256Y-229162D01*
X86972D01*
X87634Y-228888D01*
X88140Y-228382D01*
X88414Y-227720D01*
Y-227004D01*
X88140Y-226343D01*
X87634Y-225836D01*
X86972Y-225562D01*
X86256D01*
X86047Y-225649D01*
X85547Y-225315D01*
Y-224492D01*
X85547D01*
Y-224327D01*
X85547D01*
Y-223504D01*
X86047Y-223170D01*
X86256Y-223257D01*
X86972D01*
X87634Y-222983D01*
X88140Y-222476D01*
X88414Y-221815D01*
Y-221099D01*
X88140Y-220437D01*
X87634Y-219931D01*
X86972Y-219657D01*
X86256D01*
X86047Y-219743D01*
X85547Y-219409D01*
Y-218587D01*
X80841D01*
X80168Y-217913D01*
Y-217142D01*
X84661D01*
Y-215671D01*
X85161Y-215337D01*
X85272Y-215383D01*
X85988D01*
X86650Y-215109D01*
X87156Y-214602D01*
X87430Y-213941D01*
Y-213225D01*
X87270Y-212838D01*
X87582Y-212709D01*
X88088Y-212202D01*
X88362Y-211541D01*
Y-210825D01*
X88088Y-210163D01*
X87582Y-209657D01*
X87322Y-209549D01*
X86952Y-209211D01*
X87006Y-208918D01*
X87057Y-208661D01*
X87057Y-208661D01*
Y-206693D01*
X87057Y-206693D01*
X86949Y-206147D01*
X86639Y-205684D01*
X85655Y-204699D01*
X85192Y-204390D01*
X84646Y-204281D01*
X84646Y-204281D01*
X82811D01*
X82713Y-204183D01*
X82193Y-203967D01*
D02*
G37*
G36*
X49622Y-213370D02*
X44791D01*
Y-215937D01*
X49622D01*
Y-213370D01*
D02*
G37*
G36*
X58182Y-216100D02*
X56941D01*
Y-217341D01*
X57461Y-217126D01*
X57967Y-216620D01*
X58182Y-216100D01*
D02*
G37*
G36*
X51941D02*
X50700D01*
X50915Y-216620D01*
X51421Y-217126D01*
X51941Y-217341D01*
Y-216100D01*
D02*
G37*
G36*
X38182D02*
X36941D01*
Y-217341D01*
X37461Y-217126D01*
X37967Y-216620D01*
X38182Y-216100D01*
D02*
G37*
G36*
X35941D02*
X34700D01*
X34915Y-216620D01*
X35421Y-217126D01*
X35941Y-217341D01*
Y-216100D01*
D02*
G37*
G36*
X18182D02*
X16941D01*
Y-217341D01*
X17461Y-217126D01*
X17967Y-216620D01*
X18182Y-216100D01*
D02*
G37*
G36*
X11941D02*
X10700D01*
X10915Y-216620D01*
X11421Y-217126D01*
X11941Y-217341D01*
Y-216100D01*
D02*
G37*
G36*
X17941Y-217859D02*
X17421Y-218074D01*
X16915Y-218580D01*
X16703Y-219092D01*
X16179D01*
X15967Y-218580D01*
X15461Y-218074D01*
X14941Y-217859D01*
Y-219600D01*
Y-221341D01*
X15461Y-221126D01*
X15967Y-220620D01*
X16179Y-220108D01*
X16703D01*
X16915Y-220620D01*
X17421Y-221126D01*
X17941Y-221341D01*
Y-219600D01*
Y-217859D01*
D02*
G37*
G36*
X54941D02*
Y-219100D01*
X56182D01*
X55967Y-218580D01*
X55461Y-218074D01*
X54941Y-217859D01*
D02*
G37*
G36*
X53941D02*
X53421Y-218074D01*
X52915Y-218580D01*
X52700Y-219100D01*
X53941D01*
Y-217859D01*
D02*
G37*
G36*
X34941D02*
Y-219100D01*
X36182D01*
X35967Y-218580D01*
X35461Y-218074D01*
X34941Y-217859D01*
D02*
G37*
G36*
X33941D02*
X33421Y-218074D01*
X32915Y-218580D01*
X32700Y-219100D01*
X33941D01*
Y-217859D01*
D02*
G37*
G36*
X18941D02*
Y-219100D01*
X20182D01*
X19967Y-218580D01*
X19461Y-218074D01*
X18941Y-217859D01*
D02*
G37*
G36*
X13941D02*
X13421Y-218074D01*
X12915Y-218580D01*
X12700Y-219100D01*
X13941D01*
Y-217859D01*
D02*
G37*
G36*
X49622Y-216937D02*
X44291D01*
X38961D01*
Y-219504D01*
X42294D01*
X42572Y-219920D01*
X42550Y-219972D01*
X46033D01*
X46011Y-219920D01*
X46288Y-219504D01*
X49622D01*
Y-216937D01*
D02*
G37*
G36*
X-17763Y-215150D02*
X-17965D01*
Y-219980D01*
X-13134D01*
Y-219778D01*
X-13497Y-218423D01*
X-14199Y-217207D01*
X-15191Y-216215D01*
X-16407Y-215513D01*
X-17763Y-215150D01*
D02*
G37*
G36*
X2237D02*
X2035D01*
Y-219980D01*
X6866D01*
Y-219778D01*
X6503Y-218423D01*
X5801Y-217207D01*
X4809Y-216215D01*
X3593Y-215513D01*
X2237Y-215150D01*
D02*
G37*
G36*
X-18965D02*
X-19166D01*
X-20522Y-215513D01*
X-21738Y-216215D01*
X-22730Y-217207D01*
X-23432Y-218423D01*
X-23795Y-219778D01*
Y-219980D01*
X-18965D01*
Y-215150D01*
D02*
G37*
G36*
X1035D02*
X834D01*
X-522Y-215513D01*
X-1738Y-216215D01*
X-2730Y-217207D01*
X-3432Y-218423D01*
X-3795Y-219778D01*
Y-219980D01*
X1035D01*
Y-215150D01*
D02*
G37*
G36*
X56182Y-220100D02*
X54941D01*
Y-221341D01*
X55461Y-221126D01*
X55967Y-220620D01*
X56182Y-220100D01*
D02*
G37*
G36*
X53941D02*
X52700D01*
X52915Y-220620D01*
X53421Y-221126D01*
X53941Y-221341D01*
Y-220100D01*
D02*
G37*
G36*
X36182D02*
X34941D01*
Y-221341D01*
X35461Y-221126D01*
X35967Y-220620D01*
X36182Y-220100D01*
D02*
G37*
G36*
X33941D02*
X32700D01*
X32915Y-220620D01*
X33421Y-221126D01*
X33941Y-221341D01*
Y-220100D01*
D02*
G37*
G36*
X20182D02*
X18941D01*
Y-221341D01*
X19461Y-221126D01*
X19967Y-220620D01*
X20182Y-220100D01*
D02*
G37*
G36*
X13941D02*
X12700D01*
X12915Y-220620D01*
X13421Y-221126D01*
X13941Y-221341D01*
Y-220100D01*
D02*
G37*
G36*
X46033Y-220972D02*
X44791D01*
Y-222214D01*
X45311Y-221998D01*
X45817Y-221492D01*
X46033Y-220972D01*
D02*
G37*
G36*
X43791D02*
X42550D01*
X42765Y-221492D01*
X43272Y-221998D01*
X43791Y-222214D01*
Y-220972D01*
D02*
G37*
G36*
X39941Y-221859D02*
X39421Y-222074D01*
X38915Y-222580D01*
X38703Y-223092D01*
X38179D01*
X37967Y-222580D01*
X37461Y-222074D01*
X36941Y-221859D01*
Y-223600D01*
Y-225341D01*
X37461Y-225126D01*
X37967Y-224620D01*
X38179Y-224108D01*
X38703D01*
X38915Y-224620D01*
X39421Y-225126D01*
X39941Y-225341D01*
Y-223600D01*
Y-221859D01*
D02*
G37*
G36*
X15941D02*
X15421Y-222074D01*
X14915Y-222580D01*
X14703Y-223092D01*
X14179D01*
X13967Y-222580D01*
X13461Y-222074D01*
X12941Y-221859D01*
Y-223600D01*
Y-225341D01*
X13461Y-225126D01*
X13967Y-224620D01*
X14179Y-224108D01*
X14703D01*
X14915Y-224620D01*
X15421Y-225126D01*
X15941Y-225341D01*
Y-223600D01*
Y-221859D01*
D02*
G37*
G36*
X55941D02*
X55421Y-222074D01*
X54915Y-222580D01*
X54703Y-223092D01*
X54179D01*
X53967Y-222580D01*
X53461Y-222074D01*
X52941Y-221859D01*
Y-223600D01*
Y-225341D01*
X53461Y-225126D01*
X53967Y-224620D01*
X54179Y-224108D01*
X54703D01*
X54915Y-224620D01*
X55421Y-225126D01*
X55941Y-225341D01*
Y-223600D01*
Y-221859D01*
D02*
G37*
G36*
X51941D02*
X51421Y-222074D01*
X50915Y-222580D01*
X50703Y-223092D01*
X50179D01*
X49967Y-222580D01*
X49461Y-222074D01*
X48941Y-221859D01*
Y-223600D01*
Y-225341D01*
X49461Y-225126D01*
X49967Y-224620D01*
X50179Y-224108D01*
X50703D01*
X50915Y-224620D01*
X51421Y-225126D01*
X51941Y-225341D01*
Y-223600D01*
Y-221859D01*
D02*
G37*
G36*
X56941D02*
Y-223100D01*
X58182D01*
X57967Y-222580D01*
X57461Y-222074D01*
X56941Y-221859D01*
D02*
G37*
G36*
X47941D02*
X47421Y-222074D01*
X46915Y-222580D01*
X46700Y-223100D01*
X47941D01*
Y-221859D01*
D02*
G37*
G36*
X40941D02*
Y-223100D01*
X42182D01*
X41967Y-222580D01*
X41461Y-222074D01*
X40941Y-221859D01*
D02*
G37*
G36*
X35941D02*
X35421Y-222074D01*
X34915Y-222580D01*
X34700Y-223100D01*
X35941D01*
Y-221859D01*
D02*
G37*
G36*
X16941D02*
Y-223100D01*
X18182D01*
X17967Y-222580D01*
X17461Y-222074D01*
X16941Y-221859D01*
D02*
G37*
G36*
X11941D02*
X11421Y-222074D01*
X10915Y-222580D01*
X10700Y-223100D01*
X11941D01*
Y-221859D01*
D02*
G37*
G36*
X-7059D02*
Y-223100D01*
X-5818D01*
X-6033Y-222580D01*
X-6539Y-222074D01*
X-7059Y-221859D01*
D02*
G37*
G36*
X-8059D02*
X-8579Y-222074D01*
X-9085Y-222580D01*
X-9300Y-223100D01*
X-8059D01*
Y-221859D01*
D02*
G37*
G36*
X58182Y-224100D02*
X56941D01*
Y-225341D01*
X57461Y-225126D01*
X57967Y-224620D01*
X58182Y-224100D01*
D02*
G37*
G36*
X47941D02*
X46700D01*
X46915Y-224620D01*
X47421Y-225126D01*
X47941Y-225341D01*
Y-224100D01*
D02*
G37*
G36*
X42182D02*
X40941D01*
Y-225341D01*
X41461Y-225126D01*
X41967Y-224620D01*
X42182Y-224100D01*
D02*
G37*
G36*
X35941D02*
X34700D01*
X34915Y-224620D01*
X35421Y-225126D01*
X35941Y-225341D01*
Y-224100D01*
D02*
G37*
G36*
X18182D02*
X16941D01*
Y-225341D01*
X17461Y-225126D01*
X17967Y-224620D01*
X18182Y-224100D01*
D02*
G37*
G36*
X11941D02*
X10700D01*
X10915Y-224620D01*
X11421Y-225126D01*
X11941Y-225341D01*
Y-224100D01*
D02*
G37*
G36*
X-5818D02*
X-7059D01*
Y-225341D01*
X-6539Y-225126D01*
X-6033Y-224620D01*
X-5818Y-224100D01*
D02*
G37*
G36*
X-8059D02*
X-9300D01*
X-9085Y-224620D01*
X-8579Y-225126D01*
X-8059Y-225341D01*
Y-224100D01*
D02*
G37*
G36*
X6866Y-220980D02*
X2035D01*
Y-225811D01*
X2237D01*
X3593Y-225448D01*
X4809Y-224746D01*
X5801Y-223753D01*
X6503Y-222538D01*
X6866Y-221182D01*
Y-220980D01*
D02*
G37*
G36*
X1035D02*
X-3795D01*
Y-221182D01*
X-3432Y-222538D01*
X-2730Y-223753D01*
X-1738Y-224746D01*
X-522Y-225448D01*
X834Y-225811D01*
X1035D01*
Y-220980D01*
D02*
G37*
G36*
X-13134D02*
X-17965D01*
Y-225811D01*
X-17763D01*
X-16407Y-225448D01*
X-15191Y-224746D01*
X-14199Y-223753D01*
X-13497Y-222538D01*
X-13134Y-221182D01*
Y-220980D01*
D02*
G37*
G36*
X-18965D02*
X-23795D01*
Y-221182D01*
X-23432Y-222538D01*
X-22730Y-223753D01*
X-21738Y-224746D01*
X-20522Y-225448D01*
X-19166Y-225811D01*
X-18965D01*
Y-220980D01*
D02*
G37*
G36*
X63476Y-225621D02*
X62957Y-225836D01*
X62450Y-226343D01*
X62235Y-226862D01*
X63476D01*
Y-225621D01*
D02*
G37*
G36*
X41941Y-225859D02*
X41421Y-226074D01*
X40915Y-226580D01*
X40703Y-227092D01*
X40179D01*
X39967Y-226580D01*
X39461Y-226074D01*
X38941Y-225859D01*
Y-227600D01*
Y-229341D01*
X39461Y-229126D01*
X39967Y-228620D01*
X40179Y-228108D01*
X40703D01*
X40915Y-228620D01*
X41421Y-229126D01*
X41941Y-229341D01*
Y-227600D01*
Y-225859D01*
D02*
G37*
G36*
X37941D02*
X37421Y-226074D01*
X36915Y-226580D01*
X36703Y-227092D01*
X36179D01*
X35967Y-226580D01*
X35461Y-226074D01*
X34941Y-225859D01*
Y-227600D01*
Y-229341D01*
X35461Y-229126D01*
X35967Y-228620D01*
X36179Y-228108D01*
X36703D01*
X36915Y-228620D01*
X37421Y-229126D01*
X37941Y-229341D01*
Y-227600D01*
Y-225859D01*
D02*
G37*
G36*
X-6059D02*
X-6579Y-226074D01*
X-7085Y-226580D01*
X-7297Y-227092D01*
X-7821D01*
X-8033Y-226580D01*
X-8539Y-226074D01*
X-9059Y-225859D01*
Y-227600D01*
Y-229341D01*
X-8539Y-229126D01*
X-8033Y-228620D01*
X-7821Y-228108D01*
X-7297D01*
X-7085Y-228620D01*
X-6579Y-229126D01*
X-6059Y-229341D01*
Y-227600D01*
Y-225859D01*
D02*
G37*
G36*
X53941D02*
X53421Y-226074D01*
X52915Y-226580D01*
X52703Y-227092D01*
X52179D01*
X51967Y-226580D01*
X51461Y-226074D01*
X50941Y-225859D01*
Y-227600D01*
Y-229341D01*
X51461Y-229126D01*
X51967Y-228620D01*
X52179Y-228108D01*
X52703D01*
X52915Y-228620D01*
X53421Y-229126D01*
X53941Y-229341D01*
Y-227600D01*
Y-225859D01*
D02*
G37*
G36*
X49941D02*
X49421Y-226074D01*
X48915Y-226580D01*
X48703Y-227092D01*
X48179D01*
X47967Y-226580D01*
X47461Y-226074D01*
X46941Y-225859D01*
Y-227600D01*
Y-229341D01*
X47461Y-229126D01*
X47967Y-228620D01*
X48179Y-228108D01*
X48703D01*
X48915Y-228620D01*
X49421Y-229126D01*
X49941Y-229341D01*
Y-227600D01*
Y-225859D01*
D02*
G37*
G36*
X45941D02*
X45421Y-226074D01*
X44915Y-226580D01*
X44703Y-227092D01*
X44179D01*
X43967Y-226580D01*
X43461Y-226074D01*
X42941Y-225859D01*
Y-227600D01*
Y-229341D01*
X43461Y-229126D01*
X43967Y-228620D01*
X44179Y-228108D01*
X44703D01*
X44915Y-228620D01*
X45421Y-229126D01*
X45941Y-229341D01*
Y-227600D01*
Y-225859D01*
D02*
G37*
G36*
X54941D02*
Y-227100D01*
X56182D01*
X55967Y-226580D01*
X55461Y-226074D01*
X54941Y-225859D01*
D02*
G37*
G36*
X33941D02*
X33421Y-226074D01*
X32915Y-226580D01*
X32700Y-227100D01*
X33941D01*
Y-225859D01*
D02*
G37*
G36*
X10941D02*
Y-227100D01*
X12182D01*
X11967Y-226580D01*
X11461Y-226074D01*
X10941Y-225859D01*
D02*
G37*
G36*
X9941D02*
X9421Y-226074D01*
X8915Y-226580D01*
X8700Y-227100D01*
X9941D01*
Y-225859D01*
D02*
G37*
G36*
X-5059D02*
Y-227100D01*
X-3818D01*
X-4033Y-226580D01*
X-4539Y-226074D01*
X-5059Y-225859D01*
D02*
G37*
G36*
X-10059D02*
X-10579Y-226074D01*
X-11085Y-226580D01*
X-11300Y-227100D01*
X-10059D01*
Y-225859D01*
D02*
G37*
G36*
X-15634Y-227346D02*
X-21177D01*
Y-228002D01*
X-22406D01*
X-22602Y-227805D01*
X-23264Y-227531D01*
X-23980D01*
X-24642Y-227805D01*
X-25148Y-228311D01*
X-25422Y-228973D01*
Y-229689D01*
X-25148Y-230350D01*
X-24642Y-230857D01*
X-24227Y-231029D01*
Y-231570D01*
X-24642Y-231742D01*
X-25148Y-232248D01*
X-25422Y-232910D01*
Y-233626D01*
X-25148Y-234287D01*
X-24642Y-234794D01*
X-24227Y-234966D01*
Y-235507D01*
X-24642Y-235679D01*
X-25148Y-236185D01*
X-25422Y-236847D01*
Y-237563D01*
X-25148Y-238224D01*
X-24642Y-238731D01*
X-24227Y-238903D01*
Y-239444D01*
X-24642Y-239616D01*
X-25148Y-240122D01*
X-25422Y-240784D01*
Y-241500D01*
X-25148Y-242161D01*
X-24642Y-242668D01*
X-23980Y-242942D01*
X-23264D01*
X-22602Y-242668D01*
X-22491Y-242556D01*
X-21177D01*
Y-242732D01*
X-16079D01*
X-16078Y-242732D01*
X-16078D01*
X-15689Y-242732D01*
X-15297Y-243093D01*
X-15300Y-243100D01*
X-14059D01*
Y-241859D01*
X-14579Y-242074D01*
X-15085Y-242580D01*
X-15134Y-242698D01*
X-15634Y-242599D01*
X-15634Y-242261D01*
X-15634Y-242261D01*
X-15634Y-242255D01*
Y-238370D01*
X-17602D01*
Y-235449D01*
Y-231709D01*
X-15634D01*
Y-227346D01*
D02*
G37*
G36*
X63476Y-227862D02*
X62235D01*
X62450Y-228382D01*
X62957Y-228888D01*
X63476Y-229103D01*
Y-227862D01*
D02*
G37*
G36*
X56182Y-228100D02*
X54941D01*
Y-229341D01*
X55461Y-229126D01*
X55967Y-228620D01*
X56182Y-228100D01*
D02*
G37*
G36*
X33941D02*
X32700D01*
X32915Y-228620D01*
X33421Y-229126D01*
X33941Y-229341D01*
Y-228100D01*
D02*
G37*
G36*
X12182D02*
X10941D01*
Y-229341D01*
X11461Y-229126D01*
X11967Y-228620D01*
X12182Y-228100D01*
D02*
G37*
G36*
X9941D02*
X8700D01*
X8915Y-228620D01*
X9421Y-229126D01*
X9941Y-229341D01*
Y-228100D01*
D02*
G37*
G36*
X-3818D02*
X-5059D01*
Y-229341D01*
X-4539Y-229126D01*
X-4033Y-228620D01*
X-3818Y-228100D01*
D02*
G37*
G36*
X-10059D02*
X-11300D01*
X-11085Y-228620D01*
X-10579Y-229126D01*
X-10059Y-229341D01*
Y-228100D01*
D02*
G37*
G36*
X72063Y-227665D02*
X69398D01*
Y-230232D01*
X72063D01*
Y-227665D01*
D02*
G37*
G36*
X43941Y-229859D02*
X43421Y-230074D01*
X42915Y-230580D01*
X42703Y-231092D01*
X42179D01*
X41967Y-230580D01*
X41461Y-230074D01*
X40941Y-229859D01*
Y-231600D01*
Y-233341D01*
X41461Y-233126D01*
X41967Y-232620D01*
X42179Y-232108D01*
X42703D01*
X42915Y-232620D01*
X43421Y-233126D01*
X43941Y-233341D01*
Y-231600D01*
Y-229859D01*
D02*
G37*
G36*
X39941D02*
X39421Y-230074D01*
X38915Y-230580D01*
X38703Y-231092D01*
X38179D01*
X37967Y-230580D01*
X37461Y-230074D01*
X36941Y-229859D01*
Y-231600D01*
Y-233341D01*
X37461Y-233126D01*
X37967Y-232620D01*
X38179Y-232108D01*
X38703D01*
X38915Y-232620D01*
X39421Y-233126D01*
X39941Y-233341D01*
Y-231600D01*
Y-229859D01*
D02*
G37*
G36*
X55941D02*
X55421Y-230074D01*
X54915Y-230580D01*
X54703Y-231092D01*
X54179D01*
X53967Y-230580D01*
X53461Y-230074D01*
X52941Y-229859D01*
Y-231600D01*
Y-233341D01*
X53461Y-233126D01*
X53967Y-232620D01*
X54179Y-232108D01*
X54703D01*
X54915Y-232620D01*
X55421Y-233126D01*
X55941Y-233341D01*
Y-231600D01*
Y-229859D01*
D02*
G37*
G36*
X51941D02*
X51421Y-230074D01*
X50915Y-230580D01*
X50703Y-231092D01*
X50179D01*
X49967Y-230580D01*
X49461Y-230074D01*
X48941Y-229859D01*
Y-231600D01*
Y-233341D01*
X49461Y-233126D01*
X49967Y-232620D01*
X50179Y-232108D01*
X50703D01*
X50915Y-232620D01*
X51421Y-233126D01*
X51941Y-233341D01*
Y-231600D01*
Y-229859D01*
D02*
G37*
G36*
X47941D02*
X47421Y-230074D01*
X46915Y-230580D01*
X46703Y-231092D01*
X46179D01*
X45967Y-230580D01*
X45461Y-230074D01*
X44941Y-229859D01*
Y-231600D01*
Y-233341D01*
X45461Y-233126D01*
X45967Y-232620D01*
X46179Y-232108D01*
X46703D01*
X46915Y-232620D01*
X47421Y-233126D01*
X47941Y-233341D01*
Y-231600D01*
Y-229859D01*
D02*
G37*
G36*
X56941D02*
Y-231100D01*
X58182D01*
X57967Y-230580D01*
X57461Y-230074D01*
X56941Y-229859D01*
D02*
G37*
G36*
X35941D02*
X35421Y-230074D01*
X34915Y-230580D01*
X34700Y-231100D01*
X35941D01*
Y-229859D01*
D02*
G37*
G36*
X20941D02*
Y-231100D01*
X22182D01*
X21967Y-230580D01*
X21461Y-230074D01*
X20941Y-229859D01*
D02*
G37*
G36*
X19941D02*
X19421Y-230074D01*
X18915Y-230580D01*
X18700Y-231100D01*
X19941D01*
Y-229859D01*
D02*
G37*
G36*
X58182Y-232100D02*
X56941D01*
Y-233341D01*
X57461Y-233126D01*
X57967Y-232620D01*
X58182Y-232100D01*
D02*
G37*
G36*
X35941D02*
X34700D01*
X34915Y-232620D01*
X35421Y-233126D01*
X35941Y-233341D01*
Y-232100D01*
D02*
G37*
G36*
X22182D02*
X20941D01*
Y-233341D01*
X21461Y-233126D01*
X21967Y-232620D01*
X22182Y-232100D01*
D02*
G37*
G36*
X19941D02*
X18700D01*
X18915Y-232620D01*
X19421Y-233126D01*
X19941Y-233341D01*
Y-232100D01*
D02*
G37*
G36*
X41941Y-233859D02*
X41421Y-234074D01*
X40915Y-234580D01*
X40703Y-235092D01*
X40179D01*
X39967Y-234580D01*
X39461Y-234074D01*
X38941Y-233859D01*
Y-235600D01*
Y-237341D01*
X39461Y-237126D01*
X39967Y-236620D01*
X40179Y-236108D01*
X40703D01*
X40915Y-236620D01*
X41421Y-237126D01*
X41941Y-237341D01*
Y-235600D01*
Y-233859D01*
D02*
G37*
G36*
X37941D02*
X37421Y-234074D01*
X36915Y-234580D01*
X36703Y-235092D01*
X36179D01*
X35967Y-234580D01*
X35461Y-234074D01*
X34941Y-233859D01*
Y-235600D01*
Y-237341D01*
X35461Y-237126D01*
X35967Y-236620D01*
X36179Y-236108D01*
X36703D01*
X36915Y-236620D01*
X37421Y-237126D01*
X37941Y-237341D01*
Y-235600D01*
Y-233859D01*
D02*
G37*
G36*
X21941D02*
X21421Y-234074D01*
X20915Y-234580D01*
X20703Y-235092D01*
X20179D01*
X19967Y-234580D01*
X19461Y-234074D01*
X18941Y-233859D01*
Y-235600D01*
Y-237341D01*
X19461Y-237126D01*
X19967Y-236620D01*
X20179Y-236108D01*
X20703D01*
X20915Y-236620D01*
X21421Y-237126D01*
X21941Y-237341D01*
Y-235600D01*
Y-233859D01*
D02*
G37*
G36*
X53941D02*
X53421Y-234074D01*
X52915Y-234580D01*
X52703Y-235092D01*
X52179D01*
X51967Y-234580D01*
X51461Y-234074D01*
X50941Y-233859D01*
Y-235600D01*
Y-237341D01*
X51461Y-237126D01*
X51967Y-236620D01*
X52179Y-236108D01*
X52703D01*
X52915Y-236620D01*
X53421Y-237126D01*
X53941Y-237341D01*
Y-235600D01*
Y-233859D01*
D02*
G37*
G36*
X49941D02*
X49421Y-234074D01*
X48915Y-234580D01*
X48703Y-235092D01*
X48179D01*
X47967Y-234580D01*
X47461Y-234074D01*
X46941Y-233859D01*
Y-235600D01*
Y-237341D01*
X47461Y-237126D01*
X47967Y-236620D01*
X48179Y-236108D01*
X48703D01*
X48915Y-236620D01*
X49421Y-237126D01*
X49941Y-237341D01*
Y-235600D01*
Y-233859D01*
D02*
G37*
G36*
X45941D02*
X45421Y-234074D01*
X44915Y-234580D01*
X44703Y-235092D01*
X44179D01*
X43967Y-234580D01*
X43461Y-234074D01*
X42941Y-233859D01*
Y-235600D01*
Y-237341D01*
X43461Y-237126D01*
X43967Y-236620D01*
X44179Y-236108D01*
X44703D01*
X44915Y-236620D01*
X45421Y-237126D01*
X45941Y-237341D01*
Y-235600D01*
Y-233859D01*
D02*
G37*
G36*
X54941D02*
Y-235100D01*
X56182D01*
X55967Y-234580D01*
X55461Y-234074D01*
X54941Y-233859D01*
D02*
G37*
G36*
X33941D02*
X33421Y-234074D01*
X32915Y-234580D01*
X32700Y-235100D01*
X33941D01*
Y-233859D01*
D02*
G37*
G36*
X22941D02*
Y-235100D01*
X24182D01*
X23967Y-234580D01*
X23461Y-234074D01*
X22941Y-233859D01*
D02*
G37*
G36*
X17941D02*
X17421Y-234074D01*
X16915Y-234580D01*
X16700Y-235100D01*
X17941D01*
Y-233859D01*
D02*
G37*
G36*
X56182Y-236100D02*
X54941D01*
Y-237341D01*
X55461Y-237126D01*
X55967Y-236620D01*
X56182Y-236100D01*
D02*
G37*
G36*
X33941D02*
X32700D01*
X32915Y-236620D01*
X33421Y-237126D01*
X33941Y-237341D01*
Y-236100D01*
D02*
G37*
G36*
X24182D02*
X22941D01*
Y-237341D01*
X23461Y-237126D01*
X23967Y-236620D01*
X24182Y-236100D01*
D02*
G37*
G36*
X17941D02*
X16700D01*
X16915Y-236620D01*
X17421Y-237126D01*
X17941Y-237341D01*
Y-236100D01*
D02*
G37*
G36*
X41941Y-241859D02*
X41421Y-242074D01*
X40915Y-242580D01*
X40703Y-243092D01*
X40179D01*
X39967Y-242580D01*
X39461Y-242074D01*
X38941Y-241859D01*
Y-243600D01*
Y-245341D01*
X39461Y-245126D01*
X39967Y-244620D01*
X40179Y-244108D01*
X40703D01*
X40915Y-244620D01*
X41421Y-245126D01*
X41941Y-245341D01*
Y-243600D01*
Y-241859D01*
D02*
G37*
G36*
X37941D02*
X37421Y-242074D01*
X36915Y-242580D01*
X36703Y-243092D01*
X36179D01*
X35967Y-242580D01*
X35461Y-242074D01*
X34941Y-241859D01*
Y-243600D01*
Y-245341D01*
X35461Y-245126D01*
X35967Y-244620D01*
X36179Y-244108D01*
X36703D01*
X36915Y-244620D01*
X37421Y-245126D01*
X37941Y-245341D01*
Y-243600D01*
Y-241859D01*
D02*
G37*
G36*
X21941D02*
X21421Y-242074D01*
X20915Y-242580D01*
X20703Y-243092D01*
X20179D01*
X19967Y-242580D01*
X19461Y-242074D01*
X18941Y-241859D01*
Y-243600D01*
Y-245341D01*
X19461Y-245126D01*
X19967Y-244620D01*
X20179Y-244108D01*
X20703D01*
X20915Y-244620D01*
X21421Y-245126D01*
X21941Y-245341D01*
Y-243600D01*
Y-241859D01*
D02*
G37*
G36*
X17941D02*
X17421Y-242074D01*
X16915Y-242580D01*
X16703Y-243092D01*
X16179D01*
X15967Y-242580D01*
X15461Y-242074D01*
X14941Y-241859D01*
Y-243600D01*
Y-245341D01*
X15461Y-245126D01*
X15967Y-244620D01*
X16179Y-244108D01*
X16703D01*
X16915Y-244620D01*
X17421Y-245126D01*
X17941Y-245341D01*
Y-243600D01*
Y-241859D01*
D02*
G37*
G36*
X13941D02*
X13421Y-242074D01*
X12915Y-242580D01*
X12703Y-243092D01*
X12179D01*
X11967Y-242580D01*
X11461Y-242074D01*
X10941Y-241859D01*
Y-243600D01*
Y-245341D01*
X11461Y-245126D01*
X11967Y-244620D01*
X12179Y-244108D01*
X12703D01*
X12915Y-244620D01*
X13421Y-245126D01*
X13941Y-245341D01*
Y-243600D01*
Y-241859D01*
D02*
G37*
G36*
X9941D02*
X9421Y-242074D01*
X8915Y-242580D01*
X8703Y-243092D01*
X8179D01*
X7967Y-242580D01*
X7461Y-242074D01*
X6941Y-241859D01*
Y-243600D01*
Y-245341D01*
X7461Y-245126D01*
X7967Y-244620D01*
X8179Y-244108D01*
X8703D01*
X8915Y-244620D01*
X9421Y-245126D01*
X9941Y-245341D01*
Y-243600D01*
Y-241859D01*
D02*
G37*
G36*
X5941D02*
X5421Y-242074D01*
X4915Y-242580D01*
X4703Y-243092D01*
X4179D01*
X3967Y-242580D01*
X3461Y-242074D01*
X2941Y-241859D01*
Y-243600D01*
Y-245341D01*
X3461Y-245126D01*
X3967Y-244620D01*
X4179Y-244108D01*
X4703D01*
X4915Y-244620D01*
X5421Y-245126D01*
X5941Y-245341D01*
Y-243600D01*
Y-241859D01*
D02*
G37*
G36*
X1941D02*
X1421Y-242074D01*
X915Y-242580D01*
X703Y-243092D01*
X179D01*
X-33Y-242580D01*
X-539Y-242074D01*
X-1059Y-241859D01*
Y-243600D01*
Y-245341D01*
X-539Y-245126D01*
X-33Y-244620D01*
X179Y-244108D01*
X703D01*
X915Y-244620D01*
X1421Y-245126D01*
X1941Y-245341D01*
Y-243600D01*
Y-241859D01*
D02*
G37*
G36*
X-2059D02*
X-2579Y-242074D01*
X-3085Y-242580D01*
X-3297Y-243092D01*
X-3821D01*
X-4033Y-242580D01*
X-4539Y-242074D01*
X-5059Y-241859D01*
Y-243600D01*
Y-245341D01*
X-4539Y-245126D01*
X-4033Y-244620D01*
X-3821Y-244108D01*
X-3297D01*
X-3085Y-244620D01*
X-2579Y-245126D01*
X-2059Y-245341D01*
Y-243600D01*
Y-241859D01*
D02*
G37*
G36*
X-6059D02*
X-6579Y-242074D01*
X-7085Y-242580D01*
X-7297Y-243092D01*
X-7821D01*
X-8033Y-242580D01*
X-8539Y-242074D01*
X-9059Y-241859D01*
Y-243600D01*
Y-245341D01*
X-8539Y-245126D01*
X-8033Y-244620D01*
X-7821Y-244108D01*
X-7297D01*
X-7085Y-244620D01*
X-6579Y-245126D01*
X-6059Y-245341D01*
Y-243600D01*
Y-241859D01*
D02*
G37*
G36*
X-10059D02*
X-10579Y-242074D01*
X-11085Y-242580D01*
X-11297Y-243092D01*
X-11821D01*
X-12033Y-242580D01*
X-12539Y-242074D01*
X-13059Y-241859D01*
Y-243600D01*
Y-245341D01*
X-12539Y-245126D01*
X-12033Y-244620D01*
X-11821Y-244108D01*
X-11297D01*
X-11085Y-244620D01*
X-10579Y-245126D01*
X-10059Y-245341D01*
Y-243600D01*
Y-241859D01*
D02*
G37*
G36*
X53941D02*
X53421Y-242074D01*
X52915Y-242580D01*
X52703Y-243092D01*
X52179D01*
X51967Y-242580D01*
X51461Y-242074D01*
X50941Y-241859D01*
Y-243600D01*
Y-245341D01*
X51461Y-245126D01*
X51967Y-244620D01*
X52179Y-244108D01*
X52703D01*
X52915Y-244620D01*
X53421Y-245126D01*
X53941Y-245341D01*
Y-243600D01*
Y-241859D01*
D02*
G37*
G36*
X49941D02*
X49421Y-242074D01*
X48915Y-242580D01*
X48703Y-243092D01*
X48179D01*
X47967Y-242580D01*
X47461Y-242074D01*
X46941Y-241859D01*
Y-243600D01*
Y-245341D01*
X47461Y-245126D01*
X47967Y-244620D01*
X48179Y-244108D01*
X48703D01*
X48915Y-244620D01*
X49421Y-245126D01*
X49941Y-245341D01*
Y-243600D01*
Y-241859D01*
D02*
G37*
G36*
X45941D02*
X45421Y-242074D01*
X44915Y-242580D01*
X44703Y-243092D01*
X44179D01*
X43967Y-242580D01*
X43461Y-242074D01*
X42941Y-241859D01*
Y-243600D01*
Y-245341D01*
X43461Y-245126D01*
X43967Y-244620D01*
X44179Y-244108D01*
X44703D01*
X44915Y-244620D01*
X45421Y-245126D01*
X45941Y-245341D01*
Y-243600D01*
Y-241859D01*
D02*
G37*
G36*
X54941D02*
Y-243100D01*
X56182D01*
X55967Y-242580D01*
X55461Y-242074D01*
X54941Y-241859D01*
D02*
G37*
G36*
X33941D02*
X33421Y-242074D01*
X32915Y-242580D01*
X32700Y-243100D01*
X33941D01*
Y-241859D01*
D02*
G37*
G36*
X22941D02*
Y-243100D01*
X24182D01*
X23967Y-242580D01*
X23461Y-242074D01*
X22941Y-241859D01*
D02*
G37*
G36*
X33941Y-244100D02*
X32700D01*
X32915Y-244620D01*
X33421Y-245126D01*
X33941Y-245341D01*
Y-244100D01*
D02*
G37*
G36*
X24182D02*
X22941D01*
Y-245341D01*
X23461Y-245126D01*
X23967Y-244620D01*
X24182Y-244100D01*
D02*
G37*
G36*
X-14059D02*
X-15300D01*
X-15085Y-244620D01*
X-14579Y-245126D01*
X-14059Y-245341D01*
Y-244100D01*
D02*
G37*
G36*
X56182D02*
X54941D01*
Y-245341D01*
X55461Y-245126D01*
X55967Y-244620D01*
X56182Y-244100D01*
D02*
G37*
G36*
X43941Y-245859D02*
X43421Y-246074D01*
X42915Y-246580D01*
X42703Y-247092D01*
X42179D01*
X41967Y-246580D01*
X41461Y-246074D01*
X40941Y-245859D01*
Y-247600D01*
Y-249341D01*
X41461Y-249126D01*
X41967Y-248620D01*
X42179Y-248108D01*
X42703D01*
X42915Y-248620D01*
X43421Y-249126D01*
X43941Y-249341D01*
Y-247600D01*
Y-245859D01*
D02*
G37*
G36*
X39941D02*
X39421Y-246074D01*
X38915Y-246580D01*
X38703Y-247092D01*
X38179D01*
X37967Y-246580D01*
X37461Y-246074D01*
X36941Y-245859D01*
Y-247600D01*
Y-249341D01*
X37461Y-249126D01*
X37967Y-248620D01*
X38179Y-248108D01*
X38703D01*
X38915Y-248620D01*
X39421Y-249126D01*
X39941Y-249341D01*
Y-247600D01*
Y-245859D01*
D02*
G37*
G36*
X19941D02*
X19421Y-246074D01*
X18915Y-246580D01*
X18703Y-247092D01*
X18179D01*
X17967Y-246580D01*
X17461Y-246074D01*
X16941Y-245859D01*
Y-247600D01*
Y-249341D01*
X17461Y-249126D01*
X17967Y-248620D01*
X18179Y-248108D01*
X18703D01*
X18915Y-248620D01*
X19421Y-249126D01*
X19941Y-249341D01*
Y-247600D01*
Y-245859D01*
D02*
G37*
G36*
X15941D02*
X15421Y-246074D01*
X14915Y-246580D01*
X14703Y-247092D01*
X14179D01*
X13967Y-246580D01*
X13461Y-246074D01*
X12941Y-245859D01*
Y-247600D01*
Y-249341D01*
X13461Y-249126D01*
X13967Y-248620D01*
X14179Y-248108D01*
X14703D01*
X14915Y-248620D01*
X15421Y-249126D01*
X15941Y-249341D01*
Y-247600D01*
Y-245859D01*
D02*
G37*
G36*
X11941D02*
X11421Y-246074D01*
X10915Y-246580D01*
X10703Y-247092D01*
X10179D01*
X9967Y-246580D01*
X9461Y-246074D01*
X8941Y-245859D01*
Y-247600D01*
Y-249341D01*
X9461Y-249126D01*
X9967Y-248620D01*
X10179Y-248108D01*
X10703D01*
X10915Y-248620D01*
X11421Y-249126D01*
X11941Y-249341D01*
Y-247600D01*
Y-245859D01*
D02*
G37*
G36*
X-8059D02*
X-8579Y-246074D01*
X-9085Y-246580D01*
X-9297Y-247092D01*
X-9821D01*
X-10033Y-246580D01*
X-10539Y-246074D01*
X-11059Y-245859D01*
Y-247600D01*
Y-249341D01*
X-10539Y-249126D01*
X-10033Y-248620D01*
X-9821Y-248108D01*
X-9297D01*
X-9085Y-248620D01*
X-8579Y-249126D01*
X-8059Y-249341D01*
Y-247600D01*
Y-245859D01*
D02*
G37*
G36*
X55941D02*
X55421Y-246074D01*
X54915Y-246580D01*
X54703Y-247092D01*
X54179D01*
X53967Y-246580D01*
X53461Y-246074D01*
X52941Y-245859D01*
Y-247600D01*
Y-249341D01*
X53461Y-249126D01*
X53967Y-248620D01*
X54179Y-248108D01*
X54703D01*
X54915Y-248620D01*
X55421Y-249126D01*
X55941Y-249341D01*
Y-247600D01*
Y-245859D01*
D02*
G37*
G36*
X51941D02*
X51421Y-246074D01*
X50915Y-246580D01*
X50703Y-247092D01*
X50179D01*
X49967Y-246580D01*
X49461Y-246074D01*
X48941Y-245859D01*
Y-247600D01*
Y-249341D01*
X49461Y-249126D01*
X49967Y-248620D01*
X50179Y-248108D01*
X50703D01*
X50915Y-248620D01*
X51421Y-249126D01*
X51941Y-249341D01*
Y-247600D01*
Y-245859D01*
D02*
G37*
G36*
X47941D02*
X47421Y-246074D01*
X46915Y-246580D01*
X46703Y-247092D01*
X46179D01*
X45967Y-246580D01*
X45461Y-246074D01*
X44941Y-245859D01*
Y-247600D01*
Y-249341D01*
X45461Y-249126D01*
X45967Y-248620D01*
X46179Y-248108D01*
X46703D01*
X46915Y-248620D01*
X47421Y-249126D01*
X47941Y-249341D01*
Y-247600D01*
Y-245859D01*
D02*
G37*
G36*
X56941D02*
Y-247100D01*
X58182D01*
X57967Y-246580D01*
X57461Y-246074D01*
X56941Y-245859D01*
D02*
G37*
G36*
X35941D02*
X35421Y-246074D01*
X34915Y-246580D01*
X34700Y-247100D01*
X35941D01*
Y-245859D01*
D02*
G37*
G36*
X20941D02*
Y-247100D01*
X22182D01*
X21967Y-246580D01*
X21461Y-246074D01*
X20941Y-245859D01*
D02*
G37*
G36*
X7941D02*
X7421Y-246074D01*
X6915Y-246580D01*
X6700Y-247100D01*
X7941D01*
Y-245859D01*
D02*
G37*
G36*
X-7059D02*
Y-247100D01*
X-5818D01*
X-6033Y-246580D01*
X-6539Y-246074D01*
X-7059Y-245859D01*
D02*
G37*
G36*
X-12059D02*
X-12579Y-246074D01*
X-13085Y-246580D01*
X-13300Y-247100D01*
X-12059D01*
Y-245859D01*
D02*
G37*
G36*
X58182Y-248100D02*
X56941D01*
Y-249341D01*
X57461Y-249126D01*
X57967Y-248620D01*
X58182Y-248100D01*
D02*
G37*
G36*
X35941D02*
X34700D01*
X34915Y-248620D01*
X35421Y-249126D01*
X35941Y-249341D01*
Y-248100D01*
D02*
G37*
G36*
X22182D02*
X20941D01*
Y-249341D01*
X21461Y-249126D01*
X21967Y-248620D01*
X22182Y-248100D01*
D02*
G37*
G36*
X7941D02*
X6700D01*
X6915Y-248620D01*
X7421Y-249126D01*
X7941Y-249341D01*
Y-248100D01*
D02*
G37*
G36*
X-5818D02*
X-7059D01*
Y-249341D01*
X-6539Y-249126D01*
X-6033Y-248620D01*
X-5818Y-248100D01*
D02*
G37*
G36*
X-12059D02*
X-13300D01*
X-13085Y-248620D01*
X-12579Y-249126D01*
X-12059Y-249341D01*
Y-248100D01*
D02*
G37*
G36*
X37941Y-249859D02*
X37421Y-250074D01*
X36915Y-250580D01*
X36703Y-251092D01*
X36179D01*
X35967Y-250580D01*
X35461Y-250074D01*
X34941Y-249859D01*
Y-251600D01*
Y-253341D01*
X35461Y-253126D01*
X35967Y-252620D01*
X36179Y-252108D01*
X36703D01*
X36915Y-252620D01*
X37421Y-253126D01*
X37941Y-253341D01*
Y-251600D01*
Y-249859D01*
D02*
G37*
G36*
X21941D02*
X21421Y-250074D01*
X20915Y-250580D01*
X20703Y-251092D01*
X20179D01*
X19967Y-250580D01*
X19461Y-250074D01*
X18941Y-249859D01*
Y-251600D01*
Y-253341D01*
X19461Y-253126D01*
X19967Y-252620D01*
X20179Y-252108D01*
X20703D01*
X20915Y-252620D01*
X21421Y-253126D01*
X21941Y-253341D01*
Y-251600D01*
Y-249859D01*
D02*
G37*
G36*
X17941D02*
X17421Y-250074D01*
X16915Y-250580D01*
X16703Y-251092D01*
X16179D01*
X15967Y-250580D01*
X15461Y-250074D01*
X14941Y-249859D01*
Y-251600D01*
Y-253341D01*
X15461Y-253126D01*
X15967Y-252620D01*
X16179Y-252108D01*
X16703D01*
X16915Y-252620D01*
X17421Y-253126D01*
X17941Y-253341D01*
Y-251600D01*
Y-249859D01*
D02*
G37*
G36*
X13941D02*
X13421Y-250074D01*
X12915Y-250580D01*
X12703Y-251092D01*
X12179D01*
X11967Y-250580D01*
X11461Y-250074D01*
X10941Y-249859D01*
Y-251600D01*
Y-253341D01*
X11461Y-253126D01*
X11967Y-252620D01*
X12179Y-252108D01*
X12703D01*
X12915Y-252620D01*
X13421Y-253126D01*
X13941Y-253341D01*
Y-251600D01*
Y-249859D01*
D02*
G37*
G36*
X53941D02*
X53421Y-250074D01*
X52915Y-250580D01*
X52703Y-251092D01*
X52179D01*
X51967Y-250580D01*
X51461Y-250074D01*
X50941Y-249859D01*
Y-251600D01*
Y-253341D01*
X51461Y-253126D01*
X51967Y-252620D01*
X52179Y-252108D01*
X52703D01*
X52915Y-252620D01*
X53421Y-253126D01*
X53941Y-253341D01*
Y-251600D01*
Y-249859D01*
D02*
G37*
G36*
X54941D02*
Y-251100D01*
X56182D01*
X55967Y-250580D01*
X55461Y-250074D01*
X54941Y-249859D01*
D02*
G37*
G36*
X49941D02*
X49421Y-250074D01*
X48915Y-250580D01*
X48700Y-251100D01*
X49941D01*
Y-249859D01*
D02*
G37*
G36*
X38941D02*
Y-251100D01*
X40182D01*
X39967Y-250580D01*
X39461Y-250074D01*
X38941Y-249859D01*
D02*
G37*
G36*
X33941D02*
X33421Y-250074D01*
X32915Y-250580D01*
X32700Y-251100D01*
X33941D01*
Y-249859D01*
D02*
G37*
G36*
X22941D02*
Y-251100D01*
X24182D01*
X23967Y-250580D01*
X23461Y-250074D01*
X22941Y-249859D01*
D02*
G37*
G36*
X9941D02*
X9421Y-250074D01*
X8915Y-250580D01*
X8700Y-251100D01*
X9941D01*
Y-249859D01*
D02*
G37*
G36*
X-9059D02*
Y-251100D01*
X-7818D01*
X-8033Y-250580D01*
X-8539Y-250074D01*
X-9059Y-249859D01*
D02*
G37*
G36*
X-10059D02*
X-10579Y-250074D01*
X-11085Y-250580D01*
X-11300Y-251100D01*
X-10059D01*
Y-249859D01*
D02*
G37*
G36*
X44791Y-251212D02*
Y-252453D01*
X46033D01*
X45817Y-251933D01*
X45311Y-251427D01*
X44791Y-251212D01*
D02*
G37*
G36*
X43791D02*
X43272Y-251427D01*
X42765Y-251933D01*
X42550Y-252453D01*
X43791D01*
Y-251212D01*
D02*
G37*
G36*
X2237Y-248299D02*
X2035D01*
Y-253130D01*
X6866D01*
Y-252928D01*
X6503Y-251572D01*
X5801Y-250357D01*
X4809Y-249364D01*
X3593Y-248662D01*
X2237Y-248299D01*
D02*
G37*
G36*
X-17763D02*
X-17965D01*
Y-253130D01*
X-13134D01*
Y-252928D01*
X-13497Y-251572D01*
X-14199Y-250357D01*
X-15191Y-249364D01*
X-16407Y-248662D01*
X-17763Y-248299D01*
D02*
G37*
G36*
X-18965D02*
X-19166D01*
X-20522Y-248662D01*
X-21738Y-249364D01*
X-22730Y-250357D01*
X-23432Y-251572D01*
X-23795Y-252928D01*
Y-253130D01*
X-18965D01*
Y-248299D01*
D02*
G37*
G36*
X1035D02*
X834D01*
X-522Y-248662D01*
X-1738Y-249364D01*
X-2730Y-250357D01*
X-3432Y-251572D01*
X-3795Y-252928D01*
Y-253130D01*
X1035D01*
Y-248299D01*
D02*
G37*
G36*
X40182Y-252100D02*
X38941D01*
Y-253341D01*
X39461Y-253126D01*
X39967Y-252620D01*
X40182Y-252100D01*
D02*
G37*
G36*
X33941D02*
X32700D01*
X32915Y-252620D01*
X33421Y-253126D01*
X33941Y-253341D01*
Y-252100D01*
D02*
G37*
G36*
X24182D02*
X22941D01*
Y-253341D01*
X23461Y-253126D01*
X23967Y-252620D01*
X24182Y-252100D01*
D02*
G37*
G36*
X9941D02*
X8700D01*
X8915Y-252620D01*
X9421Y-253126D01*
X9941Y-253341D01*
Y-252100D01*
D02*
G37*
G36*
X-7818D02*
X-9059D01*
Y-253341D01*
X-8539Y-253126D01*
X-8033Y-252620D01*
X-7818Y-252100D01*
D02*
G37*
G36*
X-10059D02*
X-11300D01*
X-11085Y-252620D01*
X-10579Y-253126D01*
X-10059Y-253341D01*
Y-252100D01*
D02*
G37*
G36*
X56182D02*
X54941D01*
Y-253341D01*
X55461Y-253126D01*
X55967Y-252620D01*
X56182Y-252100D01*
D02*
G37*
G36*
X49941D02*
X48700D01*
X48915Y-252620D01*
X49421Y-253126D01*
X49941Y-253341D01*
Y-252100D01*
D02*
G37*
G36*
X19941Y-253859D02*
X19421Y-254074D01*
X18915Y-254580D01*
X18703Y-255092D01*
X18179D01*
X17967Y-254580D01*
X17461Y-254074D01*
X16941Y-253859D01*
Y-255600D01*
Y-257341D01*
X17461Y-257126D01*
X17967Y-256620D01*
X18179Y-256108D01*
X18703D01*
X18915Y-256620D01*
X19421Y-257126D01*
X19941Y-257341D01*
Y-255600D01*
Y-253859D01*
D02*
G37*
G36*
X15941D02*
X15421Y-254074D01*
X14915Y-254580D01*
X14703Y-255092D01*
X14179D01*
X13967Y-254580D01*
X13461Y-254074D01*
X12941Y-253859D01*
Y-255600D01*
Y-257341D01*
X13461Y-257126D01*
X13967Y-256620D01*
X14179Y-256108D01*
X14703D01*
X14915Y-256620D01*
X15421Y-257126D01*
X15941Y-257341D01*
Y-255600D01*
Y-253859D01*
D02*
G37*
G36*
X55941D02*
X55421Y-254074D01*
X54915Y-254580D01*
X54703Y-255092D01*
X54179D01*
X53967Y-254580D01*
X53461Y-254074D01*
X52941Y-253859D01*
Y-255600D01*
Y-257341D01*
X53461Y-257126D01*
X53967Y-256620D01*
X54179Y-256108D01*
X54703D01*
X54915Y-256620D01*
X55421Y-257126D01*
X55941Y-257341D01*
Y-255600D01*
Y-253859D01*
D02*
G37*
G36*
X56941D02*
Y-255100D01*
X58182D01*
X57967Y-254580D01*
X57461Y-254074D01*
X56941Y-253859D01*
D02*
G37*
G36*
X51941D02*
X51421Y-254074D01*
X50915Y-254580D01*
X50700Y-255100D01*
X51941D01*
Y-253859D01*
D02*
G37*
G36*
X36941D02*
Y-255100D01*
X38182D01*
X37967Y-254580D01*
X37461Y-254074D01*
X36941Y-253859D01*
D02*
G37*
G36*
X35941D02*
X35421Y-254074D01*
X34915Y-254580D01*
X34700Y-255100D01*
X35941D01*
Y-253859D01*
D02*
G37*
G36*
X20941D02*
Y-255100D01*
X22182D01*
X21967Y-254580D01*
X21461Y-254074D01*
X20941Y-253859D01*
D02*
G37*
G36*
X11941D02*
X11421Y-254074D01*
X10915Y-254580D01*
X10700Y-255100D01*
X11941D01*
Y-253859D01*
D02*
G37*
G36*
X46033Y-253453D02*
X42550D01*
X42572Y-253505D01*
X42294Y-253921D01*
X38961D01*
Y-256488D01*
X44291D01*
X49622D01*
Y-253921D01*
X46288D01*
X46011Y-253505D01*
X46033Y-253453D01*
D02*
G37*
G36*
X58182Y-256100D02*
X56941D01*
Y-257341D01*
X57461Y-257126D01*
X57967Y-256620D01*
X58182Y-256100D01*
D02*
G37*
G36*
X51941D02*
X50700D01*
X50915Y-256620D01*
X51421Y-257126D01*
X51941Y-257341D01*
Y-256100D01*
D02*
G37*
G36*
X38182D02*
X36941D01*
Y-257341D01*
X37461Y-257126D01*
X37967Y-256620D01*
X38182Y-256100D01*
D02*
G37*
G36*
X35941D02*
X34700D01*
X34915Y-256620D01*
X35421Y-257126D01*
X35941Y-257341D01*
Y-256100D01*
D02*
G37*
G36*
X22182D02*
X20941D01*
Y-257341D01*
X21461Y-257126D01*
X21967Y-256620D01*
X22182Y-256100D01*
D02*
G37*
G36*
X11941D02*
X10700D01*
X10915Y-256620D01*
X11421Y-257126D01*
X11941Y-257341D01*
Y-256100D01*
D02*
G37*
G36*
X87114Y-257117D02*
Y-258358D01*
X88355D01*
X88140Y-257839D01*
X87634Y-257332D01*
X87114Y-257117D01*
D02*
G37*
G36*
X6866Y-254130D02*
X2035D01*
Y-258961D01*
X2237D01*
X3593Y-258597D01*
X4809Y-257896D01*
X5801Y-256903D01*
X6503Y-255687D01*
X6866Y-254332D01*
Y-254130D01*
D02*
G37*
G36*
X1035D02*
X-3795D01*
Y-254332D01*
X-3432Y-255687D01*
X-2730Y-256903D01*
X-1738Y-257896D01*
X-522Y-258597D01*
X834Y-258961D01*
X1035D01*
Y-254130D01*
D02*
G37*
G36*
X-13134D02*
X-17965D01*
Y-258961D01*
X-17763D01*
X-16407Y-258597D01*
X-15191Y-257896D01*
X-14199Y-256903D01*
X-13497Y-255687D01*
X-13134Y-254332D01*
Y-254130D01*
D02*
G37*
G36*
X-18965D02*
X-23795D01*
Y-254332D01*
X-23432Y-255687D01*
X-22730Y-256903D01*
X-21738Y-257896D01*
X-20522Y-258597D01*
X-19166Y-258961D01*
X-18965D01*
Y-254130D01*
D02*
G37*
G36*
X21941Y-257859D02*
X21421Y-258074D01*
X20915Y-258580D01*
X20703Y-259092D01*
X20179D01*
X19967Y-258580D01*
X19461Y-258074D01*
X18941Y-257859D01*
Y-259600D01*
Y-261341D01*
X19461Y-261126D01*
X19967Y-260620D01*
X20179Y-260108D01*
X20703D01*
X20915Y-260620D01*
X21421Y-261126D01*
X21941Y-261341D01*
Y-259600D01*
Y-257859D01*
D02*
G37*
G36*
X17941D02*
X17421Y-258074D01*
X16915Y-258580D01*
X16703Y-259092D01*
X16179D01*
X15967Y-258580D01*
X15461Y-258074D01*
X14941Y-257859D01*
Y-259600D01*
Y-261341D01*
X15461Y-261126D01*
X15967Y-260620D01*
X16179Y-260108D01*
X16703D01*
X16915Y-260620D01*
X17421Y-261126D01*
X17941Y-261341D01*
Y-259600D01*
Y-257859D01*
D02*
G37*
G36*
X13941D02*
X13421Y-258074D01*
X12915Y-258580D01*
X12703Y-259092D01*
X12179D01*
X11967Y-258580D01*
X11461Y-258074D01*
X10941Y-257859D01*
Y-259600D01*
Y-261341D01*
X11461Y-261126D01*
X11967Y-260620D01*
X12179Y-260108D01*
X12703D01*
X12915Y-260620D01*
X13421Y-261126D01*
X13941Y-261341D01*
Y-259600D01*
Y-257859D01*
D02*
G37*
G36*
X22941D02*
Y-259100D01*
X24182D01*
X23967Y-258580D01*
X23461Y-258074D01*
X22941Y-257859D01*
D02*
G37*
G36*
X9941D02*
X9421Y-258074D01*
X8915Y-258580D01*
X8700Y-259100D01*
X9941D01*
Y-257859D01*
D02*
G37*
G36*
X-25059D02*
Y-259100D01*
X-23818D01*
X-24033Y-258580D01*
X-24539Y-258074D01*
X-25059Y-257859D01*
D02*
G37*
G36*
X49622Y-257488D02*
X44791D01*
Y-260055D01*
X49622D01*
Y-257488D01*
D02*
G37*
G36*
X81488Y-260221D02*
X79315D01*
Y-261311D01*
X81488D01*
Y-260221D01*
D02*
G37*
G36*
X24182Y-260100D02*
X22941D01*
Y-261341D01*
X23461Y-261126D01*
X23967Y-260620D01*
X24182Y-260100D01*
D02*
G37*
G36*
X9941D02*
X8700D01*
X8915Y-260620D01*
X9421Y-261126D01*
X9941Y-261341D01*
Y-260100D01*
D02*
G37*
G36*
X-23818D02*
X-25059D01*
Y-261341D01*
X-24539Y-261126D01*
X-24033Y-260620D01*
X-23818Y-260100D01*
D02*
G37*
G36*
X43791Y-257488D02*
X38961D01*
Y-259827D01*
X35221D01*
Y-262203D01*
X-3528D01*
Y-258693D01*
X-13402D01*
Y-268567D01*
X-3528D01*
Y-265057D01*
X34891D01*
X35010Y-265376D01*
X34941Y-265483D01*
Y-267100D01*
X36182D01*
X35967Y-266580D01*
X35650Y-266264D01*
X35857Y-265764D01*
X36762D01*
Y-279315D01*
X35221D01*
Y-286827D01*
X41157D01*
Y-279315D01*
X39616D01*
Y-271669D01*
X42294D01*
X42572Y-272085D01*
X42550Y-272138D01*
X46033D01*
X46011Y-272085D01*
X46288Y-271669D01*
X49622D01*
Y-269102D01*
X44291D01*
Y-268602D01*
X43791D01*
Y-265535D01*
X41354D01*
Y-264223D01*
X52937D01*
Y-265567D01*
X53339D01*
X53439Y-266067D01*
X53421Y-266074D01*
X52915Y-266580D01*
X52700Y-267100D01*
X56182D01*
X55967Y-266580D01*
X55461Y-266074D01*
X55443Y-266067D01*
X55543Y-265567D01*
X57693D01*
Y-260024D01*
X52937D01*
Y-261368D01*
X41354D01*
Y-260055D01*
X43791D01*
Y-257488D01*
D02*
G37*
G36*
X-20059Y-261859D02*
X-20579Y-262074D01*
X-21085Y-262580D01*
X-21297Y-263092D01*
X-21821D01*
X-22033Y-262580D01*
X-22539Y-262074D01*
X-23059Y-261859D01*
Y-263600D01*
Y-265341D01*
X-22539Y-265126D01*
X-22033Y-264620D01*
X-21821Y-264108D01*
X-21297D01*
X-21085Y-264620D01*
X-20579Y-265126D01*
X-20059Y-265341D01*
Y-263600D01*
Y-261859D01*
D02*
G37*
G36*
X-19059D02*
Y-263100D01*
X-17818D01*
X-18033Y-262580D01*
X-18539Y-262074D01*
X-19059Y-261859D01*
D02*
G37*
G36*
X-24059D02*
X-24579Y-262074D01*
X-25085Y-262580D01*
X-25300Y-263100D01*
X-24059D01*
Y-261859D01*
D02*
G37*
G36*
X-17818Y-264100D02*
X-19059D01*
Y-265341D01*
X-18539Y-265126D01*
X-18033Y-264620D01*
X-17818Y-264100D01*
D02*
G37*
G36*
X-24059D02*
X-25300D01*
X-25085Y-264620D01*
X-24579Y-265126D01*
X-24059Y-265341D01*
Y-264100D01*
D02*
G37*
G36*
X21941Y-265859D02*
X21421Y-266074D01*
X20915Y-266580D01*
X20703Y-267092D01*
X20179D01*
X19967Y-266580D01*
X19461Y-266074D01*
X18941Y-265859D01*
Y-267600D01*
Y-269341D01*
X19461Y-269126D01*
X19967Y-268620D01*
X20179Y-268108D01*
X20703D01*
X20915Y-268620D01*
X21421Y-269126D01*
X21941Y-269341D01*
Y-267600D01*
Y-265859D01*
D02*
G37*
G36*
X17941D02*
X17421Y-266074D01*
X16915Y-266580D01*
X16703Y-267092D01*
X16179D01*
X15967Y-266580D01*
X15461Y-266074D01*
X14941Y-265859D01*
Y-267600D01*
Y-269341D01*
X15461Y-269126D01*
X15967Y-268620D01*
X16179Y-268108D01*
X16703D01*
X16915Y-268620D01*
X17421Y-269126D01*
X17941Y-269341D01*
Y-267600D01*
Y-265859D01*
D02*
G37*
G36*
X13941D02*
X13421Y-266074D01*
X12915Y-266580D01*
X12703Y-267092D01*
X12179D01*
X11967Y-266580D01*
X11461Y-266074D01*
X10941Y-265859D01*
Y-267600D01*
Y-269341D01*
X11461Y-269126D01*
X11967Y-268620D01*
X12179Y-268108D01*
X12703D01*
X12915Y-268620D01*
X13421Y-269126D01*
X13941Y-269341D01*
Y-267600D01*
Y-265859D01*
D02*
G37*
G36*
X33941D02*
X33421Y-266074D01*
X32915Y-266580D01*
X32700Y-267100D01*
X33941D01*
Y-265859D01*
D02*
G37*
G36*
X22941D02*
Y-267100D01*
X24182D01*
X23967Y-266580D01*
X23461Y-266074D01*
X22941Y-265859D01*
D02*
G37*
G36*
X9941D02*
X9421Y-266074D01*
X8915Y-266580D01*
X8700Y-267100D01*
X9941D01*
Y-265859D01*
D02*
G37*
G36*
X-25059D02*
Y-267100D01*
X-23818D01*
X-24033Y-266580D01*
X-24539Y-266074D01*
X-25059Y-265859D01*
D02*
G37*
G36*
X86114Y-257117D02*
X85595Y-257332D01*
X85088Y-257839D01*
X84814Y-258500D01*
Y-258856D01*
X84621Y-259050D01*
X84311Y-259513D01*
X84202Y-260059D01*
X83755Y-260221D01*
X82488D01*
Y-261811D01*
X81988D01*
Y-262189D01*
X79315D01*
Y-263402D01*
Y-266523D01*
X78988Y-266588D01*
X78525Y-266898D01*
X78525Y-266898D01*
X77731Y-267691D01*
X77715Y-267715D01*
X77215Y-267564D01*
Y-266732D01*
X77215Y-266732D01*
X77106Y-266186D01*
X76797Y-265723D01*
X75813Y-264739D01*
X75349Y-264429D01*
X74803Y-264321D01*
X74803Y-264321D01*
X72260D01*
Y-260221D01*
X66913D01*
Y-260384D01*
X66713D01*
X66167Y-260492D01*
X65704Y-260802D01*
X65704Y-260802D01*
X65138Y-261368D01*
X63205D01*
Y-260024D01*
X58449D01*
Y-265567D01*
X63205D01*
Y-264223D01*
X65138D01*
X65704Y-264789D01*
X66167Y-265098D01*
X66713Y-265207D01*
X66913Y-265629D01*
Y-269307D01*
X72260D01*
X72290Y-269795D01*
Y-270331D01*
X69900Y-272721D01*
X65732D01*
Y-274061D01*
X64988D01*
X64334Y-273791D01*
X63618D01*
X62957Y-274065D01*
X62450Y-274571D01*
X62176Y-275233D01*
Y-275949D01*
X62450Y-276610D01*
X62957Y-277116D01*
X63618Y-277391D01*
X64334D01*
X64988Y-277120D01*
X65732D01*
Y-278854D01*
Y-280799D01*
X72063D01*
Y-278854D01*
Y-274883D01*
X72455Y-274491D01*
X72917Y-274682D01*
Y-278461D01*
X72917D01*
Y-278626D01*
X72917D01*
Y-284366D01*
X73740D01*
X74074Y-284866D01*
X73987Y-285075D01*
Y-285791D01*
X74261Y-286453D01*
X74768Y-286959D01*
X75429Y-287233D01*
X76145D01*
X76807Y-286959D01*
X77313Y-286453D01*
X77587Y-285791D01*
Y-285075D01*
X77501Y-284866D01*
X77797Y-284423D01*
X77939Y-284420D01*
X78297Y-284769D01*
Y-285433D01*
X78297Y-285433D01*
X78406Y-285979D01*
X78715Y-286442D01*
X80080Y-287807D01*
Y-287940D01*
X80354Y-288602D01*
X80860Y-289108D01*
X81522Y-289382D01*
X82238D01*
X82899Y-289108D01*
X83406Y-288602D01*
X83680Y-287940D01*
Y-287224D01*
X83406Y-286563D01*
X82899Y-286056D01*
X82238Y-285782D01*
X82092D01*
X81176Y-284866D01*
X81211Y-284366D01*
X86532D01*
Y-283544D01*
X87032Y-283209D01*
X87240Y-283296D01*
X87957D01*
X88618Y-283022D01*
X89124Y-282516D01*
X89398Y-281854D01*
Y-281138D01*
X89124Y-280476D01*
X88618Y-279970D01*
X87957Y-279696D01*
X87240D01*
X87032Y-279783D01*
X86532Y-279449D01*
Y-278626D01*
X86532D01*
Y-278461D01*
X86532D01*
Y-277638D01*
X87032Y-277304D01*
X87240Y-277391D01*
X87957D01*
X88618Y-277116D01*
X89124Y-276610D01*
X89398Y-275949D01*
Y-275233D01*
X89124Y-274571D01*
X88618Y-274065D01*
X87957Y-273791D01*
X87240D01*
X87032Y-273877D01*
X86532Y-273543D01*
Y-272721D01*
X81826D01*
X80168Y-271062D01*
Y-269335D01*
X81798D01*
X81798Y-269335D01*
X81936Y-269307D01*
X84661D01*
Y-268177D01*
X85077Y-267899D01*
X85272Y-267980D01*
X85988D01*
X86650Y-267705D01*
X87156Y-267199D01*
X87430Y-266538D01*
Y-265822D01*
X87156Y-265160D01*
X86976Y-264980D01*
X87156Y-264799D01*
X87430Y-264138D01*
Y-263422D01*
X87156Y-262760D01*
X86789Y-262393D01*
X86679Y-261984D01*
X86706Y-261736D01*
X86949Y-261373D01*
X87057Y-260827D01*
X87057Y-260827D01*
Y-260650D01*
X87104Y-260604D01*
X87634Y-260384D01*
X88140Y-259878D01*
X88355Y-259358D01*
X86614D01*
Y-258858D01*
X86114D01*
Y-257117D01*
D02*
G37*
G36*
X49622Y-265535D02*
X44791D01*
Y-268102D01*
X49622D01*
Y-265535D01*
D02*
G37*
G36*
X56182Y-268100D02*
X54941D01*
Y-269341D01*
X55461Y-269126D01*
X55967Y-268620D01*
X56182Y-268100D01*
D02*
G37*
G36*
X53941D02*
X52700D01*
X52915Y-268620D01*
X53421Y-269126D01*
X53941Y-269341D01*
Y-268100D01*
D02*
G37*
G36*
X36182D02*
X34941D01*
Y-269341D01*
X35461Y-269126D01*
X35967Y-268620D01*
X36182Y-268100D01*
D02*
G37*
G36*
X33941D02*
X32700D01*
X32915Y-268620D01*
X33421Y-269126D01*
X33941Y-269341D01*
Y-268100D01*
D02*
G37*
G36*
X24182D02*
X22941D01*
Y-269341D01*
X23461Y-269126D01*
X23967Y-268620D01*
X24182Y-268100D01*
D02*
G37*
G36*
X9941D02*
X8700D01*
X8915Y-268620D01*
X9421Y-269126D01*
X9941Y-269341D01*
Y-268100D01*
D02*
G37*
G36*
X-23818D02*
X-25059D01*
Y-269341D01*
X-24539Y-269126D01*
X-24033Y-268620D01*
X-23818Y-268100D01*
D02*
G37*
G36*
X19941Y-269859D02*
X19421Y-270074D01*
X18915Y-270580D01*
X18703Y-271092D01*
X18179D01*
X17967Y-270580D01*
X17461Y-270074D01*
X16941Y-269859D01*
Y-271600D01*
Y-273341D01*
X17461Y-273126D01*
X17967Y-272620D01*
X18179Y-272108D01*
X18703D01*
X18915Y-272620D01*
X19421Y-273126D01*
X19941Y-273341D01*
Y-271600D01*
Y-269859D01*
D02*
G37*
G36*
X15941D02*
X15421Y-270074D01*
X14915Y-270580D01*
X14703Y-271092D01*
X14179D01*
X13967Y-270580D01*
X13461Y-270074D01*
X12941Y-269859D01*
Y-271600D01*
Y-273341D01*
X13461Y-273126D01*
X13967Y-272620D01*
X14179Y-272108D01*
X14703D01*
X14915Y-272620D01*
X15421Y-273126D01*
X15941Y-273341D01*
Y-271600D01*
Y-269859D01*
D02*
G37*
G36*
X55941D02*
X55421Y-270074D01*
X54915Y-270580D01*
X54703Y-271092D01*
X54179D01*
X53967Y-270580D01*
X53461Y-270074D01*
X52941Y-269859D01*
Y-271600D01*
Y-273341D01*
X53461Y-273126D01*
X53967Y-272620D01*
X54179Y-272108D01*
X54703D01*
X54915Y-272620D01*
X55421Y-273126D01*
X55941Y-273341D01*
Y-271600D01*
Y-269859D01*
D02*
G37*
G36*
X56941D02*
Y-271100D01*
X58182D01*
X57967Y-270580D01*
X57461Y-270074D01*
X56941Y-269859D01*
D02*
G37*
G36*
X51941D02*
X51421Y-270074D01*
X50915Y-270580D01*
X50700Y-271100D01*
X51941D01*
Y-269859D01*
D02*
G37*
G36*
X20941D02*
Y-271100D01*
X22182D01*
X21967Y-270580D01*
X21461Y-270074D01*
X20941Y-269859D01*
D02*
G37*
G36*
X11941D02*
X11421Y-270074D01*
X10915Y-270580D01*
X10700Y-271100D01*
X11941D01*
Y-269859D01*
D02*
G37*
G36*
X2237Y-268299D02*
X2035D01*
Y-273130D01*
X6866D01*
Y-272928D01*
X6503Y-271572D01*
X5801Y-270357D01*
X4809Y-269364D01*
X3593Y-268663D01*
X2237Y-268299D01*
D02*
G37*
G36*
X-17763D02*
X-17965D01*
Y-273130D01*
X-13134D01*
Y-272928D01*
X-13497Y-271572D01*
X-14199Y-270357D01*
X-15191Y-269364D01*
X-16407Y-268663D01*
X-17763Y-268299D01*
D02*
G37*
G36*
X-18965D02*
X-19166D01*
X-20522Y-268663D01*
X-21738Y-269364D01*
X-22730Y-270357D01*
X-23432Y-271572D01*
X-23795Y-272928D01*
Y-273130D01*
X-18965D01*
Y-268299D01*
D02*
G37*
G36*
X1035D02*
X834D01*
X-522Y-268663D01*
X-1738Y-269364D01*
X-2730Y-270357D01*
X-3432Y-271572D01*
X-3795Y-272928D01*
Y-273130D01*
X1035D01*
Y-268299D01*
D02*
G37*
G36*
X22182Y-272100D02*
X20941D01*
Y-273341D01*
X21461Y-273126D01*
X21967Y-272620D01*
X22182Y-272100D01*
D02*
G37*
G36*
X11941D02*
X10700D01*
X10915Y-272620D01*
X11421Y-273126D01*
X11941Y-273341D01*
Y-272100D01*
D02*
G37*
G36*
X58182D02*
X56941D01*
Y-273341D01*
X57461Y-273126D01*
X57967Y-272620D01*
X58182Y-272100D01*
D02*
G37*
G36*
X51941D02*
X50700D01*
X50915Y-272620D01*
X51421Y-273126D01*
X51941Y-273341D01*
Y-272100D01*
D02*
G37*
G36*
X46033Y-273138D02*
X44791D01*
Y-274379D01*
X45311Y-274164D01*
X45817Y-273657D01*
X46033Y-273138D01*
D02*
G37*
G36*
X43791D02*
X42550D01*
X42765Y-273657D01*
X43272Y-274164D01*
X43791Y-274379D01*
Y-273138D01*
D02*
G37*
G36*
X17941Y-273859D02*
X17421Y-274074D01*
X16915Y-274580D01*
X16703Y-275092D01*
X16179D01*
X15967Y-274580D01*
X15461Y-274074D01*
X14941Y-273859D01*
Y-275600D01*
Y-277341D01*
X15461Y-277126D01*
X15967Y-276620D01*
X16179Y-276108D01*
X16703D01*
X16915Y-276620D01*
X17421Y-277126D01*
X17941Y-277341D01*
Y-275600D01*
Y-273859D01*
D02*
G37*
G36*
X13941D02*
X13421Y-274074D01*
X12915Y-274580D01*
X12703Y-275092D01*
X12179D01*
X11967Y-274580D01*
X11461Y-274074D01*
X10941Y-273859D01*
Y-275600D01*
Y-277341D01*
X11461Y-277126D01*
X11967Y-276620D01*
X12179Y-276108D01*
X12703D01*
X12915Y-276620D01*
X13421Y-277126D01*
X13941Y-277341D01*
Y-275600D01*
Y-273859D01*
D02*
G37*
G36*
X53941D02*
X53421Y-274074D01*
X52915Y-274580D01*
X52703Y-275092D01*
X52179D01*
X51967Y-274580D01*
X51461Y-274074D01*
X50941Y-273859D01*
Y-275600D01*
Y-277341D01*
X51461Y-277126D01*
X51967Y-276620D01*
X52179Y-276108D01*
X52703D01*
X52915Y-276620D01*
X53421Y-277126D01*
X53941Y-277341D01*
Y-275600D01*
Y-273859D01*
D02*
G37*
G36*
X54941D02*
Y-275100D01*
X56182D01*
X55967Y-274580D01*
X55461Y-274074D01*
X54941Y-273859D01*
D02*
G37*
G36*
X49941D02*
X49421Y-274074D01*
X48915Y-274580D01*
X48700Y-275100D01*
X49941D01*
Y-273859D01*
D02*
G37*
G36*
X34941D02*
Y-275100D01*
X36182D01*
X35967Y-274580D01*
X35461Y-274074D01*
X34941Y-273859D01*
D02*
G37*
G36*
X33941D02*
X33421Y-274074D01*
X32915Y-274580D01*
X32700Y-275100D01*
X33941D01*
Y-273859D01*
D02*
G37*
G36*
X18941D02*
Y-275100D01*
X20182D01*
X19967Y-274580D01*
X19461Y-274074D01*
X18941Y-273859D01*
D02*
G37*
G36*
X9941D02*
X9421Y-274074D01*
X8915Y-274580D01*
X8700Y-275100D01*
X9941D01*
Y-273859D01*
D02*
G37*
G36*
X-9059D02*
Y-275100D01*
X-7818D01*
X-8033Y-274580D01*
X-8539Y-274074D01*
X-9059Y-273859D01*
D02*
G37*
G36*
X-10059D02*
X-10579Y-274074D01*
X-11085Y-274580D01*
X-11300Y-275100D01*
X-10059D01*
Y-273859D01*
D02*
G37*
G36*
X36182Y-276100D02*
X34941D01*
Y-277341D01*
X35461Y-277126D01*
X35967Y-276620D01*
X36182Y-276100D01*
D02*
G37*
G36*
X33941D02*
X32700D01*
X32915Y-276620D01*
X33421Y-277126D01*
X33941Y-277341D01*
Y-276100D01*
D02*
G37*
G36*
X20182D02*
X18941D01*
Y-277341D01*
X19461Y-277126D01*
X19967Y-276620D01*
X20182Y-276100D01*
D02*
G37*
G36*
X9941D02*
X8700D01*
X8915Y-276620D01*
X9421Y-277126D01*
X9941Y-277341D01*
Y-276100D01*
D02*
G37*
G36*
X-7818D02*
X-9059D01*
Y-277341D01*
X-8539Y-277126D01*
X-8033Y-276620D01*
X-7818Y-276100D01*
D02*
G37*
G36*
X-10059D02*
X-11300D01*
X-11085Y-276620D01*
X-10579Y-277126D01*
X-10059Y-277341D01*
Y-276100D01*
D02*
G37*
G36*
X56182D02*
X54941D01*
Y-277341D01*
X55461Y-277126D01*
X55967Y-276620D01*
X56182Y-276100D01*
D02*
G37*
G36*
X49941D02*
X48700D01*
X48915Y-276620D01*
X49421Y-277126D01*
X49941Y-277341D01*
Y-276100D01*
D02*
G37*
G36*
X6866Y-274130D02*
X2035D01*
Y-278961D01*
X2237D01*
X3593Y-278597D01*
X4809Y-277896D01*
X5801Y-276903D01*
X6503Y-275688D01*
X6866Y-274332D01*
Y-274130D01*
D02*
G37*
G36*
X1035D02*
X-3795D01*
Y-274332D01*
X-3432Y-275688D01*
X-2730Y-276903D01*
X-1738Y-277896D01*
X-522Y-278597D01*
X834Y-278961D01*
X1035D01*
Y-274130D01*
D02*
G37*
G36*
X-13134D02*
X-17965D01*
Y-278961D01*
X-17763D01*
X-16407Y-278597D01*
X-15191Y-277896D01*
X-14199Y-276903D01*
X-13497Y-275688D01*
X-13134Y-274332D01*
Y-274130D01*
D02*
G37*
G36*
X-18965D02*
X-23795D01*
Y-274332D01*
X-23432Y-275688D01*
X-22730Y-276903D01*
X-21738Y-277896D01*
X-20522Y-278597D01*
X-19166Y-278961D01*
X-18965D01*
Y-274130D01*
D02*
G37*
G36*
X15941Y-277859D02*
X15421Y-278074D01*
X14915Y-278580D01*
X14703Y-279092D01*
X14179D01*
X13967Y-278580D01*
X13461Y-278074D01*
X12941Y-277859D01*
Y-279600D01*
Y-281341D01*
X13461Y-281126D01*
X13967Y-280620D01*
X14179Y-280108D01*
X14703D01*
X14915Y-280620D01*
X15421Y-281126D01*
X15941Y-281341D01*
Y-279600D01*
Y-277859D01*
D02*
G37*
G36*
X11941D02*
X11421Y-278074D01*
X10915Y-278580D01*
X10703Y-279092D01*
X10179D01*
X9967Y-278580D01*
X9461Y-278074D01*
X8941Y-277859D01*
Y-279600D01*
Y-281341D01*
X9461Y-281126D01*
X9967Y-280620D01*
X10179Y-280108D01*
X10703D01*
X10915Y-280620D01*
X11421Y-281126D01*
X11941Y-281341D01*
Y-279600D01*
Y-277859D01*
D02*
G37*
G36*
X-8059D02*
X-8579Y-278074D01*
X-9085Y-278580D01*
X-9297Y-279092D01*
X-9821D01*
X-10033Y-278580D01*
X-10539Y-278074D01*
X-11059Y-277859D01*
Y-279600D01*
Y-281341D01*
X-10539Y-281126D01*
X-10033Y-280620D01*
X-9821Y-280108D01*
X-9297D01*
X-9085Y-280620D01*
X-8579Y-281126D01*
X-8059Y-281341D01*
Y-279600D01*
Y-277859D01*
D02*
G37*
G36*
X55941D02*
X55421Y-278074D01*
X54915Y-278580D01*
X54703Y-279092D01*
X54179D01*
X53967Y-278580D01*
X53461Y-278074D01*
X52941Y-277859D01*
Y-279600D01*
Y-281341D01*
X53461Y-281126D01*
X53967Y-280620D01*
X54179Y-280108D01*
X54703D01*
X54915Y-280620D01*
X55421Y-281126D01*
X55941Y-281341D01*
Y-279600D01*
Y-277859D01*
D02*
G37*
G36*
X51941D02*
X51421Y-278074D01*
X50915Y-278580D01*
X50703Y-279092D01*
X50179D01*
X49967Y-278580D01*
X49461Y-278074D01*
X48941Y-277859D01*
Y-279600D01*
Y-281341D01*
X49461Y-281126D01*
X49967Y-280620D01*
X50179Y-280108D01*
X50703D01*
X50915Y-280620D01*
X51421Y-281126D01*
X51941Y-281341D01*
Y-279600D01*
Y-277859D01*
D02*
G37*
G36*
X47941D02*
X47421Y-278074D01*
X46915Y-278580D01*
X46703Y-279092D01*
X46179D01*
X45967Y-278580D01*
X45461Y-278074D01*
X44941Y-277859D01*
Y-279600D01*
Y-281341D01*
X45461Y-281126D01*
X45967Y-280620D01*
X46179Y-280108D01*
X46703D01*
X46915Y-280620D01*
X47421Y-281126D01*
X47941Y-281341D01*
Y-279600D01*
Y-277859D01*
D02*
G37*
G36*
X56941D02*
Y-279100D01*
X58182D01*
X57967Y-278580D01*
X57461Y-278074D01*
X56941Y-277859D01*
D02*
G37*
G36*
X43941D02*
X43421Y-278074D01*
X42915Y-278580D01*
X42700Y-279100D01*
X43941D01*
Y-277859D01*
D02*
G37*
G36*
X16941D02*
Y-279100D01*
X18182D01*
X17967Y-278580D01*
X17461Y-278074D01*
X16941Y-277859D01*
D02*
G37*
G36*
X7941D02*
X7421Y-278074D01*
X6915Y-278580D01*
X6700Y-279100D01*
X7941D01*
Y-277859D01*
D02*
G37*
G36*
X-7059D02*
Y-279100D01*
X-5818D01*
X-6033Y-278580D01*
X-6539Y-278074D01*
X-7059Y-277859D01*
D02*
G37*
G36*
X-12059D02*
X-12579Y-278074D01*
X-13085Y-278580D01*
X-13300Y-279100D01*
X-12059D01*
Y-277859D01*
D02*
G37*
G36*
X18182Y-280100D02*
X16941D01*
Y-281341D01*
X17461Y-281126D01*
X17967Y-280620D01*
X18182Y-280100D01*
D02*
G37*
G36*
X7941D02*
X6700D01*
X6915Y-280620D01*
X7421Y-281126D01*
X7941Y-281341D01*
Y-280100D01*
D02*
G37*
G36*
X-5818D02*
X-7059D01*
Y-281341D01*
X-6539Y-281126D01*
X-6033Y-280620D01*
X-5818Y-280100D01*
D02*
G37*
G36*
X-12059D02*
X-13300D01*
X-13085Y-280620D01*
X-12579Y-281126D01*
X-12059Y-281341D01*
Y-280100D01*
D02*
G37*
G36*
X58182D02*
X56941D01*
Y-281341D01*
X57461Y-281126D01*
X57967Y-280620D01*
X58182Y-280100D01*
D02*
G37*
G36*
X43941D02*
X42700D01*
X42915Y-280620D01*
X43421Y-281126D01*
X43941Y-281341D01*
Y-280100D01*
D02*
G37*
G36*
X22941Y-281859D02*
Y-283100D01*
X24182D01*
X23967Y-282580D01*
X23461Y-282074D01*
X22941Y-281859D01*
D02*
G37*
G36*
X21941D02*
X21421Y-282074D01*
X20915Y-282580D01*
X20700Y-283100D01*
X21941D01*
Y-281859D01*
D02*
G37*
G36*
X72063Y-281799D02*
X65732D01*
Y-284366D01*
X66850D01*
X67184Y-284866D01*
X67156Y-284933D01*
X70639D01*
X70611Y-284866D01*
X70945Y-284366D01*
X72063D01*
Y-281799D01*
D02*
G37*
G36*
X24182Y-284100D02*
X22941D01*
Y-285341D01*
X23461Y-285126D01*
X23967Y-284620D01*
X24182Y-284100D01*
D02*
G37*
G36*
X21941D02*
X20700D01*
X20915Y-284620D01*
X21421Y-285126D01*
X21941Y-285341D01*
Y-284100D01*
D02*
G37*
G36*
X33677Y-279315D02*
X27740D01*
Y-281541D01*
X27131D01*
X26546Y-281658D01*
X26536Y-281665D01*
X26217D01*
X25555Y-281939D01*
X25049Y-282445D01*
X24775Y-283106D01*
Y-283823D01*
X25049Y-284484D01*
X25555Y-284991D01*
X26217Y-285265D01*
X26933D01*
X27240Y-285137D01*
X27740Y-285471D01*
Y-286827D01*
X33677D01*
Y-279315D01*
D02*
G37*
G36*
X23941Y-285859D02*
X23421Y-286074D01*
X22915Y-286580D01*
X22703Y-287092D01*
X22179D01*
X21967Y-286580D01*
X21461Y-286074D01*
X20941Y-285859D01*
Y-287600D01*
Y-289341D01*
X21461Y-289126D01*
X21967Y-288620D01*
X22179Y-288108D01*
X22703D01*
X22915Y-288620D01*
X23421Y-289126D01*
X23941Y-289341D01*
Y-287600D01*
Y-285859D01*
D02*
G37*
G36*
X55941D02*
X55421Y-286074D01*
X54915Y-286580D01*
X54703Y-287092D01*
X54179D01*
X53967Y-286580D01*
X53461Y-286074D01*
X52941Y-285859D01*
Y-287600D01*
Y-289341D01*
X53461Y-289126D01*
X53967Y-288620D01*
X54179Y-288108D01*
X54703D01*
X54915Y-288620D01*
X55421Y-289126D01*
X55941Y-289341D01*
Y-287600D01*
Y-285859D01*
D02*
G37*
G36*
X51941D02*
X51421Y-286074D01*
X50915Y-286580D01*
X50703Y-287092D01*
X50179D01*
X49967Y-286580D01*
X49461Y-286074D01*
X48941Y-285859D01*
Y-287600D01*
Y-289341D01*
X49461Y-289126D01*
X49967Y-288620D01*
X50179Y-288108D01*
X50703D01*
X50915Y-288620D01*
X51421Y-289126D01*
X51941Y-289341D01*
Y-287600D01*
Y-285859D01*
D02*
G37*
G36*
X47941D02*
X47421Y-286074D01*
X46915Y-286580D01*
X46703Y-287092D01*
X46179D01*
X45967Y-286580D01*
X45461Y-286074D01*
X44941Y-285859D01*
Y-287600D01*
Y-289341D01*
X45461Y-289126D01*
X45967Y-288620D01*
X46179Y-288108D01*
X46703D01*
X46915Y-288620D01*
X47421Y-289126D01*
X47941Y-289341D01*
Y-287600D01*
Y-285859D01*
D02*
G37*
G36*
X56941D02*
Y-287100D01*
X58182D01*
X57967Y-286580D01*
X57461Y-286074D01*
X56941Y-285859D01*
D02*
G37*
G36*
X43941D02*
X43421Y-286074D01*
X42915Y-286580D01*
X42700Y-287100D01*
X43941D01*
Y-285859D01*
D02*
G37*
G36*
X24941D02*
Y-287100D01*
X26182D01*
X25967Y-286580D01*
X25461Y-286074D01*
X24941Y-285859D01*
D02*
G37*
G36*
X19941D02*
X19421Y-286074D01*
X18915Y-286580D01*
X18700Y-287100D01*
X19941D01*
Y-285859D01*
D02*
G37*
G36*
X70639Y-285933D02*
X69398D01*
Y-287174D01*
X69917Y-286959D01*
X70424Y-286453D01*
X70639Y-285933D01*
D02*
G37*
G36*
X68398D02*
X67156D01*
X67372Y-286453D01*
X67878Y-286959D01*
X68398Y-287174D01*
Y-285933D01*
D02*
G37*
G36*
X58182Y-288100D02*
X56941D01*
Y-289341D01*
X57461Y-289126D01*
X57967Y-288620D01*
X58182Y-288100D01*
D02*
G37*
G36*
X43941D02*
X42700D01*
X42915Y-288620D01*
X43421Y-289126D01*
X43941Y-289341D01*
Y-288100D01*
D02*
G37*
G36*
X26182D02*
X24941D01*
Y-289341D01*
X25461Y-289126D01*
X25967Y-288620D01*
X26182Y-288100D01*
D02*
G37*
G36*
X19941D02*
X18700D01*
X18915Y-288620D01*
X19421Y-289126D01*
X19941Y-289341D01*
Y-288100D01*
D02*
G37*
G36*
X30996Y-287976D02*
X27740D01*
Y-289332D01*
X27240Y-289666D01*
X27075Y-289597D01*
Y-291339D01*
Y-293138D01*
X27185Y-293160D01*
X27185Y-293160D01*
X27740D01*
Y-295488D01*
X30996D01*
Y-291732D01*
Y-287976D01*
D02*
G37*
G36*
X26075Y-289597D02*
X25555Y-289813D01*
X25049Y-290319D01*
X24834Y-290839D01*
X26075D01*
Y-289597D01*
D02*
G37*
G36*
X21941Y-289859D02*
X21421Y-290074D01*
X20915Y-290580D01*
X20703Y-291092D01*
X20179D01*
X19967Y-290580D01*
X19461Y-290074D01*
X18941Y-289859D01*
Y-291600D01*
Y-293341D01*
X19461Y-293126D01*
X19967Y-292620D01*
X20179Y-292108D01*
X20703D01*
X20915Y-292620D01*
X21421Y-293126D01*
X21941Y-293341D01*
Y-291600D01*
Y-289859D01*
D02*
G37*
G36*
X17941D02*
X17421Y-290074D01*
X16915Y-290580D01*
X16703Y-291092D01*
X16179D01*
X15967Y-290580D01*
X15461Y-290074D01*
X14941Y-289859D01*
Y-291600D01*
Y-293341D01*
X15461Y-293126D01*
X15967Y-292620D01*
X16179Y-292108D01*
X16703D01*
X16915Y-292620D01*
X17421Y-293126D01*
X17941Y-293341D01*
Y-291600D01*
Y-289859D01*
D02*
G37*
G36*
X53941D02*
X53421Y-290074D01*
X52915Y-290580D01*
X52703Y-291092D01*
X52179D01*
X51967Y-290580D01*
X51461Y-290074D01*
X50941Y-289859D01*
Y-291600D01*
Y-293341D01*
X51461Y-293126D01*
X51967Y-292620D01*
X52179Y-292108D01*
X52703D01*
X52915Y-292620D01*
X53421Y-293126D01*
X53941Y-293341D01*
Y-291600D01*
Y-289859D01*
D02*
G37*
G36*
X49941D02*
X49421Y-290074D01*
X48915Y-290580D01*
X48703Y-291092D01*
X48179D01*
X47967Y-290580D01*
X47461Y-290074D01*
X46941Y-289859D01*
Y-291600D01*
Y-293341D01*
X47461Y-293126D01*
X47967Y-292620D01*
X48179Y-292108D01*
X48703D01*
X48915Y-292620D01*
X49421Y-293126D01*
X49941Y-293341D01*
Y-291600D01*
Y-289859D01*
D02*
G37*
G36*
X54941D02*
Y-291100D01*
X56182D01*
X55967Y-290580D01*
X55461Y-290074D01*
X54941Y-289859D01*
D02*
G37*
G36*
X45941D02*
X45421Y-290074D01*
X44915Y-290580D01*
X44700Y-291100D01*
X45941D01*
Y-289859D01*
D02*
G37*
G36*
X22941D02*
Y-291100D01*
X24182D01*
X23967Y-290580D01*
X23461Y-290074D01*
X22941Y-289859D01*
D02*
G37*
G36*
X13941D02*
X13421Y-290074D01*
X12915Y-290580D01*
X12700Y-291100D01*
X13941D01*
Y-289859D01*
D02*
G37*
G36*
X26075Y-291839D02*
X24834D01*
X25049Y-292358D01*
X25555Y-292864D01*
X26075Y-293080D01*
Y-291839D01*
D02*
G37*
G36*
X56182Y-292100D02*
X54941D01*
Y-293341D01*
X55461Y-293126D01*
X55967Y-292620D01*
X56182Y-292100D01*
D02*
G37*
G36*
X45941D02*
X44700D01*
X44915Y-292620D01*
X45421Y-293126D01*
X45941Y-293341D01*
Y-292100D01*
D02*
G37*
G36*
X24182D02*
X22941D01*
Y-293341D01*
X23461Y-293126D01*
X23967Y-292620D01*
X24182Y-292100D01*
D02*
G37*
G36*
X13941D02*
X12700D01*
X12915Y-292620D01*
X13421Y-293126D01*
X13941Y-293341D01*
Y-292100D01*
D02*
G37*
G36*
X-23264Y-280680D02*
X-23980D01*
X-24642Y-280954D01*
X-25148Y-281461D01*
X-25422Y-282122D01*
Y-282838D01*
X-25148Y-283500D01*
X-24642Y-284006D01*
X-24227Y-284178D01*
Y-284719D01*
X-24642Y-284891D01*
X-25148Y-285398D01*
X-25422Y-286059D01*
Y-286775D01*
X-25148Y-287437D01*
X-24642Y-287943D01*
X-24227Y-288115D01*
Y-288656D01*
X-24642Y-288828D01*
X-25148Y-289335D01*
X-25422Y-289996D01*
Y-290712D01*
X-25148Y-291374D01*
X-24642Y-291880D01*
X-24227Y-292052D01*
Y-292593D01*
X-24642Y-292765D01*
X-25148Y-293272D01*
X-25422Y-293933D01*
Y-294649D01*
X-25148Y-295311D01*
X-24642Y-295817D01*
X-23980Y-296091D01*
X-23264D01*
X-22602Y-295817D01*
X-22507Y-295722D01*
X-21177D01*
Y-296276D01*
X-15634D01*
Y-291913D01*
X-17602D01*
Y-288992D01*
Y-285252D01*
X-15634D01*
Y-280890D01*
X-21177D01*
Y-281206D01*
X-22351D01*
X-22602Y-280954D01*
X-23264Y-280680D01*
D02*
G37*
G36*
X25941Y-297859D02*
X25421Y-298074D01*
X24915Y-298580D01*
X24703Y-299092D01*
X24179D01*
X23967Y-298580D01*
X23461Y-298074D01*
X22941Y-297859D01*
Y-299600D01*
Y-301341D01*
X23461Y-301126D01*
X23967Y-300620D01*
X24179Y-300108D01*
X24703D01*
X24915Y-300620D01*
X25421Y-301126D01*
X25941Y-301341D01*
Y-299600D01*
Y-297859D01*
D02*
G37*
G36*
X21941D02*
X21421Y-298074D01*
X20915Y-298580D01*
X20703Y-299092D01*
X20179D01*
X19967Y-298580D01*
X19461Y-298074D01*
X18941Y-297859D01*
Y-299600D01*
Y-301341D01*
X19461Y-301126D01*
X19967Y-300620D01*
X20179Y-300108D01*
X20703D01*
X20915Y-300620D01*
X21421Y-301126D01*
X21941Y-301341D01*
Y-299600D01*
Y-297859D01*
D02*
G37*
G36*
X17941D02*
X17421Y-298074D01*
X16915Y-298580D01*
X16703Y-299092D01*
X16179D01*
X15967Y-298580D01*
X15461Y-298074D01*
X14941Y-297859D01*
Y-299600D01*
Y-301341D01*
X15461Y-301126D01*
X15967Y-300620D01*
X16179Y-300108D01*
X16703D01*
X16915Y-300620D01*
X17421Y-301126D01*
X17941Y-301341D01*
Y-299600D01*
Y-297859D01*
D02*
G37*
G36*
X13941D02*
X13421Y-298074D01*
X12915Y-298580D01*
X12703Y-299092D01*
X12179D01*
X11967Y-298580D01*
X11461Y-298074D01*
X10941Y-297859D01*
Y-299600D01*
Y-301341D01*
X11461Y-301126D01*
X11967Y-300620D01*
X12179Y-300108D01*
X12703D01*
X12915Y-300620D01*
X13421Y-301126D01*
X13941Y-301341D01*
Y-299600D01*
Y-297859D01*
D02*
G37*
G36*
X-6059D02*
X-6579Y-298074D01*
X-7085Y-298580D01*
X-7297Y-299092D01*
X-7821D01*
X-8033Y-298580D01*
X-8539Y-298074D01*
X-9059Y-297859D01*
Y-299600D01*
Y-301341D01*
X-8539Y-301126D01*
X-8033Y-300620D01*
X-7821Y-300108D01*
X-7297D01*
X-7085Y-300620D01*
X-6579Y-301126D01*
X-6059Y-301341D01*
Y-299600D01*
Y-297859D01*
D02*
G37*
G36*
X53941D02*
X53421Y-298074D01*
X52915Y-298580D01*
X52703Y-299092D01*
X52179D01*
X51967Y-298580D01*
X51461Y-298074D01*
X50941Y-297859D01*
Y-299600D01*
Y-301341D01*
X51461Y-301126D01*
X51967Y-300620D01*
X52179Y-300108D01*
X52703D01*
X52915Y-300620D01*
X53421Y-301126D01*
X53941Y-301341D01*
Y-299600D01*
Y-297859D01*
D02*
G37*
G36*
X49941D02*
X49421Y-298074D01*
X48915Y-298580D01*
X48703Y-299092D01*
X48179D01*
X47967Y-298580D01*
X47461Y-298074D01*
X46941Y-297859D01*
Y-299600D01*
Y-301341D01*
X47461Y-301126D01*
X47967Y-300620D01*
X48179Y-300108D01*
X48703D01*
X48915Y-300620D01*
X49421Y-301126D01*
X49941Y-301341D01*
Y-299600D01*
Y-297859D01*
D02*
G37*
G36*
X45941D02*
X45421Y-298074D01*
X44915Y-298580D01*
X44703Y-299092D01*
X44179D01*
X43967Y-298580D01*
X43461Y-298074D01*
X42941Y-297859D01*
Y-299600D01*
Y-301341D01*
X43461Y-301126D01*
X43967Y-300620D01*
X44179Y-300108D01*
X44703D01*
X44915Y-300620D01*
X45421Y-301126D01*
X45941Y-301341D01*
Y-299600D01*
Y-297859D01*
D02*
G37*
G36*
X54941D02*
Y-299100D01*
X56182D01*
X55967Y-298580D01*
X55461Y-298074D01*
X54941Y-297859D01*
D02*
G37*
G36*
X41941D02*
X41421Y-298074D01*
X40915Y-298580D01*
X40700Y-299100D01*
X41941D01*
Y-297859D01*
D02*
G37*
G36*
X34941D02*
Y-299100D01*
X36182D01*
X35967Y-298580D01*
X35461Y-298074D01*
X34941Y-297859D01*
D02*
G37*
G36*
X33941D02*
X33421Y-298074D01*
X32915Y-298580D01*
X32700Y-299100D01*
X33941D01*
Y-297859D01*
D02*
G37*
G36*
X26941D02*
Y-299100D01*
X28182D01*
X27967Y-298580D01*
X27461Y-298074D01*
X26941Y-297859D01*
D02*
G37*
G36*
X9941D02*
X9421Y-298074D01*
X8915Y-298580D01*
X8700Y-299100D01*
X9941D01*
Y-297859D01*
D02*
G37*
G36*
X-5059D02*
Y-299100D01*
X-3818D01*
X-4033Y-298580D01*
X-4539Y-298074D01*
X-5059Y-297859D01*
D02*
G37*
G36*
X-10059D02*
X-10579Y-298074D01*
X-11085Y-298580D01*
X-11300Y-299100D01*
X-10059D01*
Y-297859D01*
D02*
G37*
G36*
X-25059D02*
Y-299100D01*
X-23818D01*
X-24033Y-298580D01*
X-24539Y-298074D01*
X-25059Y-297859D01*
D02*
G37*
G36*
X41941Y-300100D02*
X40700D01*
X40915Y-300620D01*
X41421Y-301126D01*
X41941Y-301341D01*
Y-300100D01*
D02*
G37*
G36*
X36182D02*
X34941D01*
Y-301341D01*
X35461Y-301126D01*
X35967Y-300620D01*
X36182Y-300100D01*
D02*
G37*
G36*
X33941D02*
X32700D01*
X32915Y-300620D01*
X33421Y-301126D01*
X33941Y-301341D01*
Y-300100D01*
D02*
G37*
G36*
X28182D02*
X26941D01*
Y-301341D01*
X27461Y-301126D01*
X27967Y-300620D01*
X28182Y-300100D01*
D02*
G37*
G36*
X9941D02*
X8700D01*
X8915Y-300620D01*
X9421Y-301126D01*
X9941Y-301341D01*
Y-300100D01*
D02*
G37*
G36*
X-3818D02*
X-5059D01*
Y-301341D01*
X-4539Y-301126D01*
X-4033Y-300620D01*
X-3818Y-300100D01*
D02*
G37*
G36*
X-10059D02*
X-11300D01*
X-11085Y-300620D01*
X-10579Y-301126D01*
X-10059Y-301341D01*
Y-300100D01*
D02*
G37*
G36*
X-23818D02*
X-25059D01*
Y-301341D01*
X-24539Y-301126D01*
X-24033Y-300620D01*
X-23818Y-300100D01*
D02*
G37*
G36*
X56182D02*
X54941D01*
Y-301341D01*
X55461Y-301126D01*
X55967Y-300620D01*
X56182Y-300100D01*
D02*
G37*
G36*
X23941Y-301859D02*
X23421Y-302074D01*
X22915Y-302580D01*
X22703Y-303092D01*
X22179D01*
X21967Y-302580D01*
X21461Y-302074D01*
X20941Y-301859D01*
Y-303600D01*
Y-305341D01*
X21461Y-305126D01*
X21967Y-304620D01*
X22179Y-304108D01*
X22703D01*
X22915Y-304620D01*
X23421Y-305126D01*
X23941Y-305341D01*
Y-303600D01*
Y-301859D01*
D02*
G37*
G36*
X19941D02*
X19421Y-302074D01*
X18915Y-302580D01*
X18703Y-303092D01*
X18179D01*
X17967Y-302580D01*
X17461Y-302074D01*
X16941Y-301859D01*
Y-303600D01*
Y-305341D01*
X17461Y-305126D01*
X17967Y-304620D01*
X18179Y-304108D01*
X18703D01*
X18915Y-304620D01*
X19421Y-305126D01*
X19941Y-305341D01*
Y-303600D01*
Y-301859D01*
D02*
G37*
G36*
X15941D02*
X15421Y-302074D01*
X14915Y-302580D01*
X14703Y-303092D01*
X14179D01*
X13967Y-302580D01*
X13461Y-302074D01*
X12941Y-301859D01*
Y-303600D01*
Y-305341D01*
X13461Y-305126D01*
X13967Y-304620D01*
X14179Y-304108D01*
X14703D01*
X14915Y-304620D01*
X15421Y-305126D01*
X15941Y-305341D01*
Y-303600D01*
Y-301859D01*
D02*
G37*
G36*
X55941D02*
X55421Y-302074D01*
X54915Y-302580D01*
X54703Y-303092D01*
X54179D01*
X53967Y-302580D01*
X53461Y-302074D01*
X52941Y-301859D01*
Y-303600D01*
Y-305341D01*
X53461Y-305126D01*
X53967Y-304620D01*
X54179Y-304108D01*
X54703D01*
X54915Y-304620D01*
X55421Y-305126D01*
X55941Y-305341D01*
Y-303600D01*
Y-301859D01*
D02*
G37*
G36*
X51941D02*
X51421Y-302074D01*
X50915Y-302580D01*
X50703Y-303092D01*
X50179D01*
X49967Y-302580D01*
X49461Y-302074D01*
X48941Y-301859D01*
Y-303600D01*
Y-305341D01*
X49461Y-305126D01*
X49967Y-304620D01*
X50179Y-304108D01*
X50703D01*
X50915Y-304620D01*
X51421Y-305126D01*
X51941Y-305341D01*
Y-303600D01*
Y-301859D01*
D02*
G37*
G36*
X56941D02*
Y-303100D01*
X58182D01*
X57967Y-302580D01*
X57461Y-302074D01*
X56941Y-301859D01*
D02*
G37*
G36*
X47941D02*
X47421Y-302074D01*
X46915Y-302580D01*
X46700Y-303100D01*
X47941D01*
Y-301859D01*
D02*
G37*
G36*
X24941D02*
Y-303100D01*
X26182D01*
X25967Y-302580D01*
X25461Y-302074D01*
X24941Y-301859D01*
D02*
G37*
G36*
X11941D02*
X11421Y-302074D01*
X10915Y-302580D01*
X10700Y-303100D01*
X11941D01*
Y-301859D01*
D02*
G37*
G36*
X-7059D02*
Y-303100D01*
X-5818D01*
X-6033Y-302580D01*
X-6539Y-302074D01*
X-7059Y-301859D01*
D02*
G37*
G36*
X-8059D02*
X-8579Y-302074D01*
X-9085Y-302580D01*
X-9300Y-303100D01*
X-8059D01*
Y-301859D01*
D02*
G37*
G36*
X26182Y-304100D02*
X24941D01*
Y-305341D01*
X25461Y-305126D01*
X25967Y-304620D01*
X26182Y-304100D01*
D02*
G37*
G36*
X11941D02*
X10700D01*
X10915Y-304620D01*
X11421Y-305126D01*
X11941Y-305341D01*
Y-304100D01*
D02*
G37*
G36*
X-5818D02*
X-7059D01*
Y-305341D01*
X-6539Y-305126D01*
X-6033Y-304620D01*
X-5818Y-304100D01*
D02*
G37*
G36*
X-8059D02*
X-9300D01*
X-9085Y-304620D01*
X-8579Y-305126D01*
X-8059Y-305341D01*
Y-304100D01*
D02*
G37*
G36*
X58182D02*
X56941D01*
Y-305341D01*
X57461Y-305126D01*
X57967Y-304620D01*
X58182Y-304100D01*
D02*
G37*
G36*
X47941D02*
X46700D01*
X46915Y-304620D01*
X47421Y-305126D01*
X47941Y-305341D01*
Y-304100D01*
D02*
G37*
G36*
X-17763Y-301450D02*
X-17965D01*
Y-306281D01*
X-13134D01*
Y-306079D01*
X-13497Y-304724D01*
X-14199Y-303508D01*
X-15191Y-302516D01*
X-16407Y-301814D01*
X-17763Y-301450D01*
D02*
G37*
G36*
X2237D02*
X2035D01*
Y-306281D01*
X6866D01*
Y-306079D01*
X6503Y-304724D01*
X5801Y-303508D01*
X4809Y-302516D01*
X3593Y-301814D01*
X2237Y-301450D01*
D02*
G37*
G36*
X1035D02*
X834D01*
X-522Y-301814D01*
X-1738Y-302516D01*
X-2730Y-303508D01*
X-3432Y-304724D01*
X-3795Y-306079D01*
Y-306281D01*
X1035D01*
Y-301450D01*
D02*
G37*
G36*
X-18965D02*
X-19166D01*
X-20522Y-301814D01*
X-21738Y-302516D01*
X-22730Y-303508D01*
X-23432Y-304724D01*
X-23795Y-306079D01*
Y-306281D01*
X-18965D01*
Y-301450D01*
D02*
G37*
G36*
X44791Y-305345D02*
Y-306587D01*
X46033D01*
X45817Y-306067D01*
X45311Y-305561D01*
X44791Y-305345D01*
D02*
G37*
G36*
X43791D02*
X43272Y-305561D01*
X42765Y-306067D01*
X42550Y-306587D01*
X43791D01*
Y-305345D01*
D02*
G37*
G36*
X25941Y-305859D02*
X25421Y-306074D01*
X24915Y-306580D01*
X24703Y-307092D01*
X24179D01*
X23967Y-306580D01*
X23461Y-306074D01*
X22941Y-305859D01*
Y-307600D01*
Y-309341D01*
X23461Y-309126D01*
X23967Y-308620D01*
X24179Y-308108D01*
X24703D01*
X24915Y-308620D01*
X25421Y-309126D01*
X25941Y-309341D01*
Y-307600D01*
Y-305859D01*
D02*
G37*
G36*
X21941D02*
X21421Y-306074D01*
X20915Y-306580D01*
X20703Y-307092D01*
X20179D01*
X19967Y-306580D01*
X19461Y-306074D01*
X18941Y-305859D01*
Y-307600D01*
Y-309341D01*
X19461Y-309126D01*
X19967Y-308620D01*
X20179Y-308108D01*
X20703D01*
X20915Y-308620D01*
X21421Y-309126D01*
X21941Y-309341D01*
Y-307600D01*
Y-305859D01*
D02*
G37*
G36*
X17941D02*
X17421Y-306074D01*
X16915Y-306580D01*
X16703Y-307092D01*
X16179D01*
X15967Y-306580D01*
X15461Y-306074D01*
X14941Y-305859D01*
Y-307600D01*
Y-309341D01*
X15461Y-309126D01*
X15967Y-308620D01*
X16179Y-308108D01*
X16703D01*
X16915Y-308620D01*
X17421Y-309126D01*
X17941Y-309341D01*
Y-307600D01*
Y-305859D01*
D02*
G37*
G36*
X54941D02*
Y-307100D01*
X56182D01*
X55967Y-306580D01*
X55461Y-306074D01*
X54941Y-305859D01*
D02*
G37*
G36*
X53941D02*
X53421Y-306074D01*
X52915Y-306580D01*
X52700Y-307100D01*
X53941D01*
Y-305859D01*
D02*
G37*
G36*
X34941D02*
Y-307100D01*
X36182D01*
X35967Y-306580D01*
X35461Y-306074D01*
X34941Y-305859D01*
D02*
G37*
G36*
X33941D02*
X33421Y-306074D01*
X32915Y-306580D01*
X32700Y-307100D01*
X33941D01*
Y-305859D01*
D02*
G37*
G36*
X26941D02*
Y-307100D01*
X28182D01*
X27967Y-306580D01*
X27461Y-306074D01*
X26941Y-305859D01*
D02*
G37*
G36*
X13941D02*
X13421Y-306074D01*
X12915Y-306580D01*
X12700Y-307100D01*
X13941D01*
Y-305859D01*
D02*
G37*
G36*
X36182Y-308100D02*
X34941D01*
Y-309341D01*
X35461Y-309126D01*
X35967Y-308620D01*
X36182Y-308100D01*
D02*
G37*
G36*
X33941D02*
X32700D01*
X32915Y-308620D01*
X33421Y-309126D01*
X33941Y-309341D01*
Y-308100D01*
D02*
G37*
G36*
X28182D02*
X26941D01*
Y-309341D01*
X27461Y-309126D01*
X27967Y-308620D01*
X28182Y-308100D01*
D02*
G37*
G36*
X13941D02*
X12700D01*
X12915Y-308620D01*
X13421Y-309126D01*
X13941Y-309341D01*
Y-308100D01*
D02*
G37*
G36*
X56182D02*
X54941D01*
Y-309341D01*
X55461Y-309126D01*
X55967Y-308620D01*
X56182Y-308100D01*
D02*
G37*
G36*
X53941D02*
X52700D01*
X52915Y-308620D01*
X53421Y-309126D01*
X53941Y-309341D01*
Y-308100D01*
D02*
G37*
G36*
X23941Y-309859D02*
X23421Y-310074D01*
X22915Y-310580D01*
X22703Y-311092D01*
X22179D01*
X21967Y-310580D01*
X21461Y-310074D01*
X20941Y-309859D01*
Y-311600D01*
Y-313341D01*
X21461Y-313126D01*
X21967Y-312620D01*
X22179Y-312108D01*
X22703D01*
X22915Y-312620D01*
X23421Y-313126D01*
X23941Y-313341D01*
Y-311600D01*
Y-309859D01*
D02*
G37*
G36*
X19941D02*
X19421Y-310074D01*
X18915Y-310580D01*
X18703Y-311092D01*
X18179D01*
X17967Y-310580D01*
X17461Y-310074D01*
X16941Y-309859D01*
Y-311600D01*
Y-313341D01*
X17461Y-313126D01*
X17967Y-312620D01*
X18179Y-312108D01*
X18703D01*
X18915Y-312620D01*
X19421Y-313126D01*
X19941Y-313341D01*
Y-311600D01*
Y-309859D01*
D02*
G37*
G36*
X15941D02*
X15421Y-310074D01*
X14915Y-310580D01*
X14703Y-311092D01*
X14179D01*
X13967Y-310580D01*
X13461Y-310074D01*
X12941Y-309859D01*
Y-311600D01*
Y-313341D01*
X13461Y-313126D01*
X13967Y-312620D01*
X14179Y-312108D01*
X14703D01*
X14915Y-312620D01*
X15421Y-313126D01*
X15941Y-313341D01*
Y-311600D01*
Y-309859D01*
D02*
G37*
G36*
X55941D02*
X55421Y-310074D01*
X54915Y-310580D01*
X54703Y-311092D01*
X54179D01*
X53967Y-310580D01*
X53461Y-310074D01*
X52941Y-309859D01*
Y-311600D01*
Y-313341D01*
X53461Y-313126D01*
X53967Y-312620D01*
X54179Y-312108D01*
X54703D01*
X54915Y-312620D01*
X55421Y-313126D01*
X55941Y-313341D01*
Y-311600D01*
Y-309859D01*
D02*
G37*
G36*
X56941D02*
Y-311100D01*
X58182D01*
X57967Y-310580D01*
X57461Y-310074D01*
X56941Y-309859D01*
D02*
G37*
G36*
X51941D02*
X51421Y-310074D01*
X50915Y-310580D01*
X50700Y-311100D01*
X51941D01*
Y-309859D01*
D02*
G37*
G36*
X24941D02*
Y-311100D01*
X26182D01*
X25967Y-310580D01*
X25461Y-310074D01*
X24941Y-309859D01*
D02*
G37*
G36*
X11941D02*
X11421Y-310074D01*
X10915Y-310580D01*
X10700Y-311100D01*
X11941D01*
Y-309859D01*
D02*
G37*
G36*
X6866Y-307281D02*
X2035D01*
Y-312112D01*
X2237D01*
X3593Y-311749D01*
X4809Y-311047D01*
X5801Y-310054D01*
X6503Y-308839D01*
X6866Y-307483D01*
Y-307281D01*
D02*
G37*
G36*
X1035D02*
X-3795D01*
Y-307483D01*
X-3432Y-308839D01*
X-2730Y-310054D01*
X-1738Y-311047D01*
X-522Y-311749D01*
X834Y-312112D01*
X1035D01*
Y-307281D01*
D02*
G37*
G36*
X-13134D02*
X-17965D01*
Y-312112D01*
X-17763D01*
X-16407Y-311749D01*
X-15191Y-311047D01*
X-14199Y-310054D01*
X-13497Y-308839D01*
X-13134Y-307483D01*
Y-307281D01*
D02*
G37*
G36*
X-18965D02*
X-23795D01*
Y-307483D01*
X-23432Y-308839D01*
X-22730Y-310054D01*
X-21738Y-311047D01*
X-20522Y-311749D01*
X-19166Y-312112D01*
X-18965D01*
Y-307281D01*
D02*
G37*
G36*
X26182Y-312100D02*
X24941D01*
Y-313341D01*
X25461Y-313126D01*
X25967Y-312620D01*
X26182Y-312100D01*
D02*
G37*
G36*
X11941D02*
X10700D01*
X10915Y-312620D01*
X11421Y-313126D01*
X11941Y-313341D01*
Y-312100D01*
D02*
G37*
G36*
X58182D02*
X56941D01*
Y-313341D01*
X57461Y-313126D01*
X57967Y-312620D01*
X58182Y-312100D01*
D02*
G37*
G36*
X51941D02*
X50700D01*
X50915Y-312620D01*
X51421Y-313126D01*
X51941Y-313341D01*
Y-312100D01*
D02*
G37*
G36*
X86130Y-312235D02*
Y-313476D01*
X87371D01*
X87156Y-312957D01*
X86650Y-312450D01*
X86130Y-312235D01*
D02*
G37*
G36*
X49622Y-311622D02*
X44791D01*
Y-314189D01*
X49622D01*
Y-311622D01*
D02*
G37*
G36*
X-22059Y-313859D02*
X-22579Y-314074D01*
X-23085Y-314580D01*
X-23297Y-315092D01*
X-23821D01*
X-24033Y-314580D01*
X-24539Y-314074D01*
X-25059Y-313859D01*
Y-315600D01*
Y-317341D01*
X-24539Y-317126D01*
X-24033Y-316620D01*
X-23821Y-316108D01*
X-23297D01*
X-23085Y-316620D01*
X-22579Y-317126D01*
X-22059Y-317341D01*
Y-315600D01*
Y-313859D01*
D02*
G37*
G36*
X-21059D02*
Y-315100D01*
X-19818D01*
X-20033Y-314580D01*
X-20539Y-314074D01*
X-21059Y-313859D01*
D02*
G37*
G36*
X41157Y-287976D02*
X31996D01*
Y-291732D01*
Y-295488D01*
X36762D01*
Y-313961D01*
X35221D01*
Y-315354D01*
X-3528D01*
Y-311844D01*
X-13402D01*
Y-321718D01*
X-3528D01*
Y-318209D01*
X35221D01*
Y-319898D01*
X38961D01*
Y-322236D01*
X43791D01*
Y-319669D01*
X41354D01*
Y-318357D01*
X51756D01*
Y-319701D01*
X56512D01*
Y-314158D01*
X51756D01*
Y-315502D01*
X41354D01*
Y-314189D01*
X43791D01*
Y-311122D01*
X44291D01*
Y-310622D01*
X49622D01*
Y-308055D01*
X46288D01*
X46011Y-307639D01*
X46033Y-307587D01*
X42550D01*
X42572Y-307639D01*
X42294Y-308055D01*
X39616D01*
Y-295488D01*
X41157D01*
Y-287976D01*
D02*
G37*
G36*
X80504Y-314354D02*
X78331D01*
Y-315445D01*
X80504D01*
Y-314354D01*
D02*
G37*
G36*
X-19818Y-316100D02*
X-21059D01*
Y-317341D01*
X-20539Y-317126D01*
X-20033Y-316620D01*
X-19818Y-316100D01*
D02*
G37*
G36*
X85130Y-312235D02*
X84610Y-312450D01*
X84104Y-312957D01*
X83830Y-313618D01*
Y-313758D01*
X83233Y-314354D01*
X81504D01*
Y-315945D01*
X81004D01*
Y-316323D01*
X78331D01*
Y-317535D01*
Y-320657D01*
X78003Y-320722D01*
X77540Y-321032D01*
X77540Y-321032D01*
X76747Y-321825D01*
X76731Y-321849D01*
X76231Y-321697D01*
Y-320866D01*
X76231Y-320866D01*
X76122Y-320320D01*
X75813Y-319857D01*
X74828Y-318872D01*
X74365Y-318563D01*
X73819Y-318454D01*
X73819Y-318455D01*
X71276D01*
Y-314354D01*
X65929D01*
Y-314521D01*
X65399Y-314626D01*
X64935Y-314935D01*
X64369Y-315502D01*
X62024D01*
Y-314158D01*
X57268D01*
Y-319701D01*
X62024D01*
Y-318357D01*
X64369D01*
X64935Y-318923D01*
X64935Y-318923D01*
X65399Y-319232D01*
X65929Y-319338D01*
Y-323441D01*
X70321D01*
Y-325351D01*
X68817Y-326854D01*
X64748D01*
Y-328195D01*
X64003D01*
X63350Y-327924D01*
X62634D01*
X61972Y-328199D01*
X61466Y-328705D01*
X61192Y-329366D01*
Y-330083D01*
X61466Y-330744D01*
X61972Y-331250D01*
X62634Y-331524D01*
X63350D01*
X64003Y-331254D01*
X64748D01*
Y-332988D01*
Y-334933D01*
X71079D01*
Y-332988D01*
Y-328919D01*
X71471Y-328526D01*
X71933Y-328718D01*
Y-332594D01*
X71933D01*
Y-332760D01*
X71933D01*
Y-338500D01*
X72756D01*
X73090Y-339000D01*
X73003Y-339209D01*
Y-339925D01*
X73277Y-340586D01*
X73783Y-341093D01*
X74445Y-341367D01*
X75161D01*
X75823Y-341093D01*
X76329Y-340586D01*
X76440Y-340318D01*
X76940Y-340418D01*
Y-340909D01*
X77214Y-341571D01*
X77720Y-342077D01*
X78382Y-342351D01*
X79098D01*
X79760Y-342077D01*
X80266Y-341571D01*
X80540Y-340909D01*
Y-340193D01*
X80266Y-339532D01*
X80168Y-339433D01*
Y-338500D01*
X85547D01*
Y-337159D01*
X86587D01*
X87240Y-337430D01*
X87957D01*
X88618Y-337156D01*
X89124Y-336649D01*
X89398Y-335988D01*
Y-335272D01*
X89124Y-334610D01*
X88618Y-334104D01*
X87957Y-333830D01*
X87240D01*
X86587Y-334101D01*
X85547D01*
Y-332760D01*
X85547D01*
Y-332594D01*
X85547D01*
Y-331254D01*
X86587D01*
X87240Y-331524D01*
X87957D01*
X88618Y-331250D01*
X89124Y-330744D01*
X89398Y-330083D01*
Y-329366D01*
X89124Y-328705D01*
X88618Y-328199D01*
X87957Y-327924D01*
X87240D01*
X86587Y-328195D01*
X85547D01*
Y-326854D01*
X80841D01*
X79183Y-325196D01*
Y-323468D01*
X80813D01*
X80813Y-323468D01*
X80951Y-323441D01*
X83677D01*
Y-321560D01*
X83896Y-321444D01*
X84177Y-321406D01*
X84610Y-321839D01*
X85272Y-322113D01*
X85988D01*
X86650Y-321839D01*
X87156Y-321333D01*
X87430Y-320671D01*
Y-319955D01*
X87156Y-319294D01*
X86761Y-318899D01*
X86942Y-318719D01*
X87216Y-318057D01*
Y-317341D01*
X86942Y-316680D01*
X86435Y-316173D01*
X86386Y-316153D01*
Y-315612D01*
X86650Y-315502D01*
X87156Y-314996D01*
X87371Y-314476D01*
X85630D01*
Y-313976D01*
X85130D01*
Y-312235D01*
D02*
G37*
G36*
X49622Y-319669D02*
X44791D01*
Y-322236D01*
X49622D01*
Y-319669D01*
D02*
G37*
G36*
X21941Y-321859D02*
X21421Y-322074D01*
X20915Y-322580D01*
X20703Y-323092D01*
X20179D01*
X19967Y-322580D01*
X19461Y-322074D01*
X18941Y-321859D01*
Y-323600D01*
Y-325341D01*
X19461Y-325126D01*
X19967Y-324620D01*
X20179Y-324108D01*
X20703D01*
X20915Y-324620D01*
X21421Y-325126D01*
X21941Y-325341D01*
Y-323600D01*
Y-321859D01*
D02*
G37*
G36*
X17941D02*
X17421Y-322074D01*
X16915Y-322580D01*
X16703Y-323092D01*
X16179D01*
X15967Y-322580D01*
X15461Y-322074D01*
X14941Y-321859D01*
Y-323600D01*
Y-325341D01*
X15461Y-325126D01*
X15967Y-324620D01*
X16179Y-324108D01*
X16703D01*
X16915Y-324620D01*
X17421Y-325126D01*
X17941Y-325341D01*
Y-323600D01*
Y-321859D01*
D02*
G37*
G36*
X13941D02*
X13421Y-322074D01*
X12915Y-322580D01*
X12703Y-323092D01*
X12179D01*
X11967Y-322580D01*
X11461Y-322074D01*
X10941Y-321859D01*
Y-323600D01*
Y-325341D01*
X11461Y-325126D01*
X11967Y-324620D01*
X12179Y-324108D01*
X12703D01*
X12915Y-324620D01*
X13421Y-325126D01*
X13941Y-325341D01*
Y-323600D01*
Y-321859D01*
D02*
G37*
G36*
X54941D02*
Y-323100D01*
X56182D01*
X55967Y-322580D01*
X55461Y-322074D01*
X54941Y-321859D01*
D02*
G37*
G36*
X53941D02*
X53421Y-322074D01*
X52915Y-322580D01*
X52700Y-323100D01*
X53941D01*
Y-321859D01*
D02*
G37*
G36*
X34941D02*
Y-323100D01*
X36182D01*
X35967Y-322580D01*
X35461Y-322074D01*
X34941Y-321859D01*
D02*
G37*
G36*
X33941D02*
X33421Y-322074D01*
X32915Y-322580D01*
X32700Y-323100D01*
X33941D01*
Y-321859D01*
D02*
G37*
G36*
X22941D02*
Y-323100D01*
X24182D01*
X23967Y-322580D01*
X23461Y-322074D01*
X22941Y-321859D01*
D02*
G37*
G36*
X9941D02*
X9421Y-322074D01*
X8915Y-322580D01*
X8700Y-323100D01*
X9941D01*
Y-321859D01*
D02*
G37*
G36*
X56182Y-324100D02*
X54941D01*
Y-325341D01*
X55461Y-325126D01*
X55967Y-324620D01*
X56182Y-324100D01*
D02*
G37*
G36*
X53941D02*
X52700D01*
X52915Y-324620D01*
X53421Y-325126D01*
X53941Y-325341D01*
Y-324100D01*
D02*
G37*
G36*
X36182D02*
X34941D01*
Y-325341D01*
X35461Y-325126D01*
X35967Y-324620D01*
X36182Y-324100D01*
D02*
G37*
G36*
X33941D02*
X32700D01*
X32915Y-324620D01*
X33421Y-325126D01*
X33941Y-325341D01*
Y-324100D01*
D02*
G37*
G36*
X24182D02*
X22941D01*
Y-325341D01*
X23461Y-325126D01*
X23967Y-324620D01*
X24182Y-324100D01*
D02*
G37*
G36*
X9941D02*
X8700D01*
X8915Y-324620D01*
X9421Y-325126D01*
X9941Y-325341D01*
Y-324100D01*
D02*
G37*
G36*
X49622Y-323236D02*
X44291D01*
X38961D01*
Y-325803D01*
X42294D01*
X42572Y-326219D01*
X42550Y-326272D01*
X46033D01*
X46011Y-326219D01*
X46288Y-325803D01*
X49622D01*
Y-323236D01*
D02*
G37*
G36*
X-17763Y-321450D02*
X-17965D01*
Y-326281D01*
X-13134D01*
Y-326079D01*
X-13497Y-324724D01*
X-14199Y-323508D01*
X-15191Y-322516D01*
X-16407Y-321814D01*
X-17763Y-321450D01*
D02*
G37*
G36*
X2237D02*
X2035D01*
Y-326281D01*
X6866D01*
Y-326079D01*
X6503Y-324724D01*
X5801Y-323508D01*
X4809Y-322516D01*
X3593Y-321814D01*
X2237Y-321450D01*
D02*
G37*
G36*
X1035D02*
X834D01*
X-522Y-321814D01*
X-1738Y-322516D01*
X-2730Y-323508D01*
X-3432Y-324724D01*
X-3795Y-326079D01*
Y-326281D01*
X1035D01*
Y-321450D01*
D02*
G37*
G36*
X-18965D02*
X-19166D01*
X-20522Y-321814D01*
X-21738Y-322516D01*
X-22730Y-323508D01*
X-23432Y-324724D01*
X-23795Y-326079D01*
Y-326281D01*
X-18965D01*
Y-321450D01*
D02*
G37*
G36*
X35941Y-325859D02*
X35421Y-326074D01*
X34915Y-326580D01*
X34703Y-327092D01*
X34179D01*
X33967Y-326580D01*
X33461Y-326074D01*
X32941Y-325859D01*
Y-327600D01*
Y-329341D01*
X33461Y-329126D01*
X33967Y-328620D01*
X34179Y-328108D01*
X34703D01*
X34915Y-328620D01*
X35421Y-329126D01*
X35941Y-329341D01*
Y-327600D01*
Y-325859D01*
D02*
G37*
G36*
X31941D02*
X31421Y-326074D01*
X30915Y-326580D01*
X30703Y-327092D01*
X30179D01*
X29967Y-326580D01*
X29461Y-326074D01*
X28941Y-325859D01*
Y-327600D01*
Y-329341D01*
X29461Y-329126D01*
X29967Y-328620D01*
X30179Y-328108D01*
X30703D01*
X30915Y-328620D01*
X31421Y-329126D01*
X31941Y-329341D01*
Y-327600D01*
Y-325859D01*
D02*
G37*
G36*
X15941D02*
X15421Y-326074D01*
X14915Y-326580D01*
X14703Y-327092D01*
X14179D01*
X13967Y-326580D01*
X13461Y-326074D01*
X12941Y-325859D01*
Y-327600D01*
Y-329341D01*
X13461Y-329126D01*
X13967Y-328620D01*
X14179Y-328108D01*
X14703D01*
X14915Y-328620D01*
X15421Y-329126D01*
X15941Y-329341D01*
Y-327600D01*
Y-325859D01*
D02*
G37*
G36*
X55941D02*
X55421Y-326074D01*
X54915Y-326580D01*
X54703Y-327092D01*
X54179D01*
X53967Y-326580D01*
X53461Y-326074D01*
X52941Y-325859D01*
Y-327600D01*
Y-329341D01*
X53461Y-329126D01*
X53967Y-328620D01*
X54179Y-328108D01*
X54703D01*
X54915Y-328620D01*
X55421Y-329126D01*
X55941Y-329341D01*
Y-327600D01*
Y-325859D01*
D02*
G37*
G36*
X56941D02*
Y-327100D01*
X58182D01*
X57967Y-326580D01*
X57461Y-326074D01*
X56941Y-325859D01*
D02*
G37*
G36*
X51941D02*
X51421Y-326074D01*
X50915Y-326580D01*
X50700Y-327100D01*
X51941D01*
Y-325859D01*
D02*
G37*
G36*
X36941D02*
Y-327100D01*
X38182D01*
X37967Y-326580D01*
X37461Y-326074D01*
X36941Y-325859D01*
D02*
G37*
G36*
X27941D02*
X27421Y-326074D01*
X26915Y-326580D01*
X26700Y-327100D01*
X27941D01*
Y-325859D01*
D02*
G37*
G36*
X16941D02*
Y-327100D01*
X18182D01*
X17967Y-326580D01*
X17461Y-326074D01*
X16941Y-325859D01*
D02*
G37*
G36*
X11941D02*
X11421Y-326074D01*
X10915Y-326580D01*
X10700Y-327100D01*
X11941D01*
Y-325859D01*
D02*
G37*
G36*
X-7059D02*
Y-327100D01*
X-5818D01*
X-6033Y-326580D01*
X-6539Y-326074D01*
X-7059Y-325859D01*
D02*
G37*
G36*
X-8059D02*
X-8579Y-326074D01*
X-9085Y-326580D01*
X-9300Y-327100D01*
X-8059D01*
Y-325859D01*
D02*
G37*
G36*
X46033Y-327272D02*
X44791D01*
Y-328513D01*
X45311Y-328298D01*
X45817Y-327791D01*
X46033Y-327272D01*
D02*
G37*
G36*
X43791D02*
X42550D01*
X42765Y-327791D01*
X43272Y-328298D01*
X43791Y-328513D01*
Y-327272D01*
D02*
G37*
G36*
X38182Y-328100D02*
X36941D01*
Y-329341D01*
X37461Y-329126D01*
X37967Y-328620D01*
X38182Y-328100D01*
D02*
G37*
G36*
X27941D02*
X26700D01*
X26915Y-328620D01*
X27421Y-329126D01*
X27941Y-329341D01*
Y-328100D01*
D02*
G37*
G36*
X18182D02*
X16941D01*
Y-329341D01*
X17461Y-329126D01*
X17967Y-328620D01*
X18182Y-328100D01*
D02*
G37*
G36*
X11941D02*
X10700D01*
X10915Y-328620D01*
X11421Y-329126D01*
X11941Y-329341D01*
Y-328100D01*
D02*
G37*
G36*
X-5818D02*
X-7059D01*
Y-329341D01*
X-6539Y-329126D01*
X-6033Y-328620D01*
X-5818Y-328100D01*
D02*
G37*
G36*
X-8059D02*
X-9300D01*
X-9085Y-328620D01*
X-8579Y-329126D01*
X-8059Y-329341D01*
Y-328100D01*
D02*
G37*
G36*
X58182D02*
X56941D01*
Y-329341D01*
X57461Y-329126D01*
X57967Y-328620D01*
X58182Y-328100D01*
D02*
G37*
G36*
X51941D02*
X50700D01*
X50915Y-328620D01*
X51421Y-329126D01*
X51941Y-329341D01*
Y-328100D01*
D02*
G37*
G36*
X41941Y-329859D02*
X41421Y-330074D01*
X40915Y-330580D01*
X40703Y-331092D01*
X40179D01*
X39967Y-330580D01*
X39461Y-330074D01*
X38941Y-329859D01*
Y-331600D01*
Y-333341D01*
X39461Y-333126D01*
X39967Y-332620D01*
X40179Y-332108D01*
X40703D01*
X40915Y-332620D01*
X41421Y-333126D01*
X41941Y-333341D01*
Y-331600D01*
Y-329859D01*
D02*
G37*
G36*
X37941D02*
X37421Y-330074D01*
X36915Y-330580D01*
X36703Y-331092D01*
X36179D01*
X35967Y-330580D01*
X35461Y-330074D01*
X34941Y-329859D01*
Y-331600D01*
Y-333341D01*
X35461Y-333126D01*
X35967Y-332620D01*
X36179Y-332108D01*
X36703D01*
X36915Y-332620D01*
X37421Y-333126D01*
X37941Y-333341D01*
Y-331600D01*
Y-329859D01*
D02*
G37*
G36*
X33941D02*
X33421Y-330074D01*
X32915Y-330580D01*
X32703Y-331092D01*
X32179D01*
X31967Y-330580D01*
X31461Y-330074D01*
X30941Y-329859D01*
Y-331600D01*
Y-333341D01*
X31461Y-333126D01*
X31967Y-332620D01*
X32179Y-332108D01*
X32703D01*
X32915Y-332620D01*
X33421Y-333126D01*
X33941Y-333341D01*
Y-331600D01*
Y-329859D01*
D02*
G37*
G36*
X29941D02*
X29421Y-330074D01*
X28915Y-330580D01*
X28703Y-331092D01*
X28179D01*
X27967Y-330580D01*
X27461Y-330074D01*
X26941Y-329859D01*
Y-331600D01*
Y-333341D01*
X27461Y-333126D01*
X27967Y-332620D01*
X28179Y-332108D01*
X28703D01*
X28915Y-332620D01*
X29421Y-333126D01*
X29941Y-333341D01*
Y-331600D01*
Y-329859D01*
D02*
G37*
G36*
X13941D02*
X13421Y-330074D01*
X12915Y-330580D01*
X12703Y-331092D01*
X12179D01*
X11967Y-330580D01*
X11461Y-330074D01*
X10941Y-329859D01*
Y-331600D01*
Y-333341D01*
X11461Y-333126D01*
X11967Y-332620D01*
X12179Y-332108D01*
X12703D01*
X12915Y-332620D01*
X13421Y-333126D01*
X13941Y-333341D01*
Y-331600D01*
Y-329859D01*
D02*
G37*
G36*
X53941D02*
X53421Y-330074D01*
X52915Y-330580D01*
X52703Y-331092D01*
X52179D01*
X51967Y-330580D01*
X51461Y-330074D01*
X50941Y-329859D01*
Y-331600D01*
Y-333341D01*
X51461Y-333126D01*
X51967Y-332620D01*
X52179Y-332108D01*
X52703D01*
X52915Y-332620D01*
X53421Y-333126D01*
X53941Y-333341D01*
Y-331600D01*
Y-329859D01*
D02*
G37*
G36*
X49941D02*
X49421Y-330074D01*
X48915Y-330580D01*
X48703Y-331092D01*
X48179D01*
X47967Y-330580D01*
X47461Y-330074D01*
X46941Y-329859D01*
Y-331600D01*
Y-333341D01*
X47461Y-333126D01*
X47967Y-332620D01*
X48179Y-332108D01*
X48703D01*
X48915Y-332620D01*
X49421Y-333126D01*
X49941Y-333341D01*
Y-331600D01*
Y-329859D01*
D02*
G37*
G36*
X45941D02*
X45421Y-330074D01*
X44915Y-330580D01*
X44703Y-331092D01*
X44179D01*
X43967Y-330580D01*
X43461Y-330074D01*
X42941Y-329859D01*
Y-331600D01*
Y-333341D01*
X43461Y-333126D01*
X43967Y-332620D01*
X44179Y-332108D01*
X44703D01*
X44915Y-332620D01*
X45421Y-333126D01*
X45941Y-333341D01*
Y-331600D01*
Y-329859D01*
D02*
G37*
G36*
X54941D02*
Y-331100D01*
X56182D01*
X55967Y-330580D01*
X55461Y-330074D01*
X54941Y-329859D01*
D02*
G37*
G36*
X25941D02*
X25421Y-330074D01*
X24915Y-330580D01*
X24700Y-331100D01*
X25941D01*
Y-329859D01*
D02*
G37*
G36*
X14941D02*
Y-331100D01*
X16182D01*
X15967Y-330580D01*
X15461Y-330074D01*
X14941Y-329859D01*
D02*
G37*
G36*
X9941D02*
X9421Y-330074D01*
X8915Y-330580D01*
X8700Y-331100D01*
X9941D01*
Y-329859D01*
D02*
G37*
G36*
X-9059D02*
Y-331100D01*
X-7818D01*
X-8033Y-330580D01*
X-8539Y-330074D01*
X-9059Y-329859D01*
D02*
G37*
G36*
X-10059D02*
X-10579Y-330074D01*
X-11085Y-330580D01*
X-11300Y-331100D01*
X-10059D01*
Y-329859D01*
D02*
G37*
G36*
X6866Y-327281D02*
X2035D01*
Y-332112D01*
X2237D01*
X3593Y-331749D01*
X4809Y-331047D01*
X5801Y-330054D01*
X6503Y-328839D01*
X6866Y-327483D01*
Y-327281D01*
D02*
G37*
G36*
X1035D02*
X-3795D01*
Y-327483D01*
X-3432Y-328839D01*
X-2730Y-330054D01*
X-1738Y-331047D01*
X-522Y-331749D01*
X834Y-332112D01*
X1035D01*
Y-327281D01*
D02*
G37*
G36*
X-13134D02*
X-17965D01*
Y-332112D01*
X-17763D01*
X-16407Y-331749D01*
X-15191Y-331047D01*
X-14199Y-330054D01*
X-13497Y-328839D01*
X-13134Y-327483D01*
Y-327281D01*
D02*
G37*
G36*
X-18965D02*
X-23795D01*
Y-327483D01*
X-23432Y-328839D01*
X-22730Y-330054D01*
X-21738Y-331047D01*
X-20522Y-331749D01*
X-19166Y-332112D01*
X-18965D01*
Y-327281D01*
D02*
G37*
G36*
X25941Y-332100D02*
X24700D01*
X24915Y-332620D01*
X25421Y-333126D01*
X25941Y-333341D01*
Y-332100D01*
D02*
G37*
G36*
X16182D02*
X14941D01*
Y-333341D01*
X15461Y-333126D01*
X15967Y-332620D01*
X16182Y-332100D01*
D02*
G37*
G36*
X9941D02*
X8700D01*
X8915Y-332620D01*
X9421Y-333126D01*
X9941Y-333341D01*
Y-332100D01*
D02*
G37*
G36*
X-7818D02*
X-9059D01*
Y-333341D01*
X-8539Y-333126D01*
X-8033Y-332620D01*
X-7818Y-332100D01*
D02*
G37*
G36*
X-10059D02*
X-11300D01*
X-11085Y-332620D01*
X-10579Y-333126D01*
X-10059Y-333341D01*
Y-332100D01*
D02*
G37*
G36*
X56182D02*
X54941D01*
Y-333341D01*
X55461Y-333126D01*
X55967Y-332620D01*
X56182Y-332100D01*
D02*
G37*
G36*
X-15634Y-333646D02*
X-21177D01*
Y-334301D01*
X-22406D01*
X-22602Y-334104D01*
X-23264Y-333830D01*
X-23980D01*
X-24642Y-334104D01*
X-25148Y-334610D01*
X-25422Y-335272D01*
Y-335988D01*
X-25148Y-336649D01*
X-24642Y-337156D01*
X-24227Y-337328D01*
Y-337869D01*
X-24642Y-338041D01*
X-25148Y-338547D01*
X-25422Y-339209D01*
Y-339925D01*
X-25148Y-340586D01*
X-24691Y-341043D01*
X-25148Y-341500D01*
X-25422Y-342162D01*
Y-342878D01*
X-25148Y-343539D01*
X-24642Y-344046D01*
X-24227Y-344218D01*
Y-344759D01*
X-24642Y-344931D01*
X-25148Y-345437D01*
X-25422Y-346099D01*
Y-346815D01*
X-25148Y-347476D01*
X-24642Y-347983D01*
X-23980Y-348257D01*
X-23264D01*
X-22888Y-348101D01*
X-21177D01*
Y-349031D01*
X-15634D01*
Y-344669D01*
X-17602D01*
Y-341748D01*
Y-338008D01*
X-15634D01*
Y-333646D01*
D02*
G37*
G36*
X43941Y-333859D02*
X43421Y-334074D01*
X42915Y-334580D01*
X42703Y-335092D01*
X42179D01*
X41967Y-334580D01*
X41461Y-334074D01*
X40941Y-333859D01*
Y-335600D01*
Y-337341D01*
X41461Y-337126D01*
X41967Y-336620D01*
X42179Y-336108D01*
X42703D01*
X42915Y-336620D01*
X43421Y-337126D01*
X43941Y-337341D01*
Y-335600D01*
Y-333859D01*
D02*
G37*
G36*
X39941D02*
X39421Y-334074D01*
X38915Y-334580D01*
X38703Y-335092D01*
X38179D01*
X37967Y-334580D01*
X37461Y-334074D01*
X36941Y-333859D01*
Y-335600D01*
Y-337341D01*
X37461Y-337126D01*
X37967Y-336620D01*
X38179Y-336108D01*
X38703D01*
X38915Y-336620D01*
X39421Y-337126D01*
X39941Y-337341D01*
Y-335600D01*
Y-333859D01*
D02*
G37*
G36*
X35941D02*
X35421Y-334074D01*
X34915Y-334580D01*
X34703Y-335092D01*
X34179D01*
X33967Y-334580D01*
X33461Y-334074D01*
X32941Y-333859D01*
Y-335600D01*
Y-337341D01*
X33461Y-337126D01*
X33967Y-336620D01*
X34179Y-336108D01*
X34703D01*
X34915Y-336620D01*
X35421Y-337126D01*
X35941Y-337341D01*
Y-335600D01*
Y-333859D01*
D02*
G37*
G36*
X31941D02*
X31421Y-334074D01*
X30915Y-334580D01*
X30703Y-335092D01*
X30179D01*
X29967Y-334580D01*
X29461Y-334074D01*
X28941Y-333859D01*
Y-335600D01*
Y-337341D01*
X29461Y-337126D01*
X29967Y-336620D01*
X30179Y-336108D01*
X30703D01*
X30915Y-336620D01*
X31421Y-337126D01*
X31941Y-337341D01*
Y-335600D01*
Y-333859D01*
D02*
G37*
G36*
X27941D02*
X27421Y-334074D01*
X26915Y-334580D01*
X26703Y-335092D01*
X26179D01*
X25967Y-334580D01*
X25461Y-334074D01*
X24941Y-333859D01*
Y-335600D01*
Y-337341D01*
X25461Y-337126D01*
X25967Y-336620D01*
X26179Y-336108D01*
X26703D01*
X26915Y-336620D01*
X27421Y-337126D01*
X27941Y-337341D01*
Y-335600D01*
Y-333859D01*
D02*
G37*
G36*
X23941D02*
X23421Y-334074D01*
X22915Y-334580D01*
X22703Y-335092D01*
X22179D01*
X21967Y-334580D01*
X21461Y-334074D01*
X20941Y-333859D01*
Y-335600D01*
Y-337341D01*
X21461Y-337126D01*
X21967Y-336620D01*
X22179Y-336108D01*
X22703D01*
X22915Y-336620D01*
X23421Y-337126D01*
X23941Y-337341D01*
Y-335600D01*
Y-333859D01*
D02*
G37*
G36*
X55941D02*
X55421Y-334074D01*
X54915Y-334580D01*
X54703Y-335092D01*
X54179D01*
X53967Y-334580D01*
X53461Y-334074D01*
X52941Y-333859D01*
Y-335600D01*
Y-337341D01*
X53461Y-337126D01*
X53967Y-336620D01*
X54179Y-336108D01*
X54703D01*
X54915Y-336620D01*
X55421Y-337126D01*
X55941Y-337341D01*
Y-335600D01*
Y-333859D01*
D02*
G37*
G36*
X51941D02*
X51421Y-334074D01*
X50915Y-334580D01*
X50703Y-335092D01*
X50179D01*
X49967Y-334580D01*
X49461Y-334074D01*
X48941Y-333859D01*
Y-335600D01*
Y-337341D01*
X49461Y-337126D01*
X49967Y-336620D01*
X50179Y-336108D01*
X50703D01*
X50915Y-336620D01*
X51421Y-337126D01*
X51941Y-337341D01*
Y-335600D01*
Y-333859D01*
D02*
G37*
G36*
X47941D02*
X47421Y-334074D01*
X46915Y-334580D01*
X46703Y-335092D01*
X46179D01*
X45967Y-334580D01*
X45461Y-334074D01*
X44941Y-333859D01*
Y-335600D01*
Y-337341D01*
X45461Y-337126D01*
X45967Y-336620D01*
X46179Y-336108D01*
X46703D01*
X46915Y-336620D01*
X47421Y-337126D01*
X47941Y-337341D01*
Y-335600D01*
Y-333859D01*
D02*
G37*
G36*
X56941D02*
Y-335100D01*
X58182D01*
X57967Y-334580D01*
X57461Y-334074D01*
X56941Y-333859D01*
D02*
G37*
G36*
X19941D02*
X19421Y-334074D01*
X18915Y-334580D01*
X18700Y-335100D01*
X19941D01*
Y-333859D01*
D02*
G37*
G36*
X58182Y-336100D02*
X56941D01*
Y-337341D01*
X57461Y-337126D01*
X57967Y-336620D01*
X58182Y-336100D01*
D02*
G37*
G36*
X19941D02*
X18700D01*
X18915Y-336620D01*
X19421Y-337126D01*
X19941Y-337341D01*
Y-336100D01*
D02*
G37*
G36*
X41941Y-337859D02*
X41421Y-338074D01*
X40915Y-338580D01*
X40703Y-339092D01*
X40179D01*
X39967Y-338580D01*
X39461Y-338074D01*
X38941Y-337859D01*
Y-339600D01*
Y-341341D01*
X39461Y-341126D01*
X39967Y-340620D01*
X40179Y-340108D01*
X40703D01*
X40915Y-340620D01*
X41421Y-341126D01*
X41941Y-341341D01*
Y-339600D01*
Y-337859D01*
D02*
G37*
G36*
X37941D02*
X37421Y-338074D01*
X36915Y-338580D01*
X36703Y-339092D01*
X36179D01*
X35967Y-338580D01*
X35461Y-338074D01*
X34941Y-337859D01*
Y-339600D01*
Y-341341D01*
X35461Y-341126D01*
X35967Y-340620D01*
X36179Y-340108D01*
X36703D01*
X36915Y-340620D01*
X37421Y-341126D01*
X37941Y-341341D01*
Y-339600D01*
Y-337859D01*
D02*
G37*
G36*
X33941D02*
X33421Y-338074D01*
X32915Y-338580D01*
X32703Y-339092D01*
X32179D01*
X31967Y-338580D01*
X31461Y-338074D01*
X30941Y-337859D01*
Y-339600D01*
Y-341341D01*
X31461Y-341126D01*
X31967Y-340620D01*
X32179Y-340108D01*
X32703D01*
X32915Y-340620D01*
X33421Y-341126D01*
X33941Y-341341D01*
Y-339600D01*
Y-337859D01*
D02*
G37*
G36*
X29941D02*
X29421Y-338074D01*
X28915Y-338580D01*
X28703Y-339092D01*
X28179D01*
X27967Y-338580D01*
X27461Y-338074D01*
X26941Y-337859D01*
Y-339600D01*
Y-341341D01*
X27461Y-341126D01*
X27967Y-340620D01*
X28179Y-340108D01*
X28703D01*
X28915Y-340620D01*
X29421Y-341126D01*
X29941Y-341341D01*
Y-339600D01*
Y-337859D01*
D02*
G37*
G36*
X25941D02*
X25421Y-338074D01*
X24915Y-338580D01*
X24703Y-339092D01*
X24179D01*
X23967Y-338580D01*
X23461Y-338074D01*
X22941Y-337859D01*
Y-339600D01*
Y-341341D01*
X23461Y-341126D01*
X23967Y-340620D01*
X24179Y-340108D01*
X24703D01*
X24915Y-340620D01*
X25421Y-341126D01*
X25941Y-341341D01*
Y-339600D01*
Y-337859D01*
D02*
G37*
G36*
X21941D02*
X21421Y-338074D01*
X20915Y-338580D01*
X20703Y-339092D01*
X20179D01*
X19967Y-338580D01*
X19461Y-338074D01*
X18941Y-337859D01*
Y-339600D01*
Y-341341D01*
X19461Y-341126D01*
X19967Y-340620D01*
X20179Y-340108D01*
X20703D01*
X20915Y-340620D01*
X21421Y-341126D01*
X21941Y-341341D01*
Y-339600D01*
Y-337859D01*
D02*
G37*
G36*
X53941D02*
X53421Y-338074D01*
X52915Y-338580D01*
X52703Y-339092D01*
X52179D01*
X51967Y-338580D01*
X51461Y-338074D01*
X50941Y-337859D01*
Y-339600D01*
Y-341341D01*
X51461Y-341126D01*
X51967Y-340620D01*
X52179Y-340108D01*
X52703D01*
X52915Y-340620D01*
X53421Y-341126D01*
X53941Y-341341D01*
Y-339600D01*
Y-337859D01*
D02*
G37*
G36*
X49941D02*
X49421Y-338074D01*
X48915Y-338580D01*
X48703Y-339092D01*
X48179D01*
X47967Y-338580D01*
X47461Y-338074D01*
X46941Y-337859D01*
Y-339600D01*
Y-341341D01*
X47461Y-341126D01*
X47967Y-340620D01*
X48179Y-340108D01*
X48703D01*
X48915Y-340620D01*
X49421Y-341126D01*
X49941Y-341341D01*
Y-339600D01*
Y-337859D01*
D02*
G37*
G36*
X45941D02*
X45421Y-338074D01*
X44915Y-338580D01*
X44703Y-339092D01*
X44179D01*
X43967Y-338580D01*
X43461Y-338074D01*
X42941Y-337859D01*
Y-339600D01*
Y-341341D01*
X43461Y-341126D01*
X43967Y-340620D01*
X44179Y-340108D01*
X44703D01*
X44915Y-340620D01*
X45421Y-341126D01*
X45941Y-341341D01*
Y-339600D01*
Y-337859D01*
D02*
G37*
G36*
X54941D02*
Y-339100D01*
X56182D01*
X55967Y-338580D01*
X55461Y-338074D01*
X54941Y-337859D01*
D02*
G37*
G36*
X17941D02*
X17421Y-338074D01*
X16915Y-338580D01*
X16700Y-339100D01*
X17941D01*
Y-337859D01*
D02*
G37*
G36*
X71079Y-335933D02*
X64748D01*
Y-338500D01*
X66486D01*
Y-339433D01*
X66387Y-339532D01*
X66172Y-340051D01*
X69655D01*
X69439Y-339532D01*
X69341Y-339433D01*
Y-338500D01*
X71079D01*
Y-335933D01*
D02*
G37*
G36*
X17941Y-340100D02*
X16700D01*
X16915Y-340620D01*
X17421Y-341126D01*
X17941Y-341341D01*
Y-340100D01*
D02*
G37*
G36*
X56182D02*
X54941D01*
Y-341341D01*
X55461Y-341126D01*
X55967Y-340620D01*
X56182Y-340100D01*
D02*
G37*
G36*
X69655Y-341051D02*
X68413D01*
Y-342292D01*
X68933Y-342077D01*
X69439Y-341571D01*
X69655Y-341051D01*
D02*
G37*
G36*
X67413D02*
X66172D01*
X66387Y-341571D01*
X66894Y-342077D01*
X67413Y-342292D01*
Y-341051D01*
D02*
G37*
G36*
X43941Y-341859D02*
X43421Y-342074D01*
X42915Y-342580D01*
X42703Y-343092D01*
X42179D01*
X41967Y-342580D01*
X41461Y-342074D01*
X40941Y-341859D01*
Y-343600D01*
Y-345341D01*
X41461Y-345126D01*
X41967Y-344620D01*
X42179Y-344108D01*
X42703D01*
X42915Y-344620D01*
X43421Y-345126D01*
X43941Y-345341D01*
Y-343600D01*
Y-341859D01*
D02*
G37*
G36*
X39941D02*
X39421Y-342074D01*
X38915Y-342580D01*
X38703Y-343092D01*
X38179D01*
X37967Y-342580D01*
X37461Y-342074D01*
X36941Y-341859D01*
Y-343600D01*
Y-345341D01*
X37461Y-345126D01*
X37967Y-344620D01*
X38179Y-344108D01*
X38703D01*
X38915Y-344620D01*
X39421Y-345126D01*
X39941Y-345341D01*
Y-343600D01*
Y-341859D01*
D02*
G37*
G36*
X35941D02*
X35421Y-342074D01*
X34915Y-342580D01*
X34703Y-343092D01*
X34179D01*
X33967Y-342580D01*
X33461Y-342074D01*
X32941Y-341859D01*
Y-343600D01*
Y-345341D01*
X33461Y-345126D01*
X33967Y-344620D01*
X34179Y-344108D01*
X34703D01*
X34915Y-344620D01*
X35421Y-345126D01*
X35941Y-345341D01*
Y-343600D01*
Y-341859D01*
D02*
G37*
G36*
X31941D02*
X31421Y-342074D01*
X30915Y-342580D01*
X30703Y-343092D01*
X30179D01*
X29967Y-342580D01*
X29461Y-342074D01*
X28941Y-341859D01*
Y-343600D01*
Y-345341D01*
X29461Y-345126D01*
X29967Y-344620D01*
X30179Y-344108D01*
X30703D01*
X30915Y-344620D01*
X31421Y-345126D01*
X31941Y-345341D01*
Y-343600D01*
Y-341859D01*
D02*
G37*
G36*
X27941D02*
X27421Y-342074D01*
X26915Y-342580D01*
X26703Y-343092D01*
X26179D01*
X25967Y-342580D01*
X25461Y-342074D01*
X24941Y-341859D01*
Y-343600D01*
Y-345341D01*
X25461Y-345126D01*
X25967Y-344620D01*
X26179Y-344108D01*
X26703D01*
X26915Y-344620D01*
X27421Y-345126D01*
X27941Y-345341D01*
Y-343600D01*
Y-341859D01*
D02*
G37*
G36*
X23941D02*
X23421Y-342074D01*
X22915Y-342580D01*
X22703Y-343092D01*
X22179D01*
X21967Y-342580D01*
X21461Y-342074D01*
X20941Y-341859D01*
Y-343600D01*
Y-345341D01*
X21461Y-345126D01*
X21967Y-344620D01*
X22179Y-344108D01*
X22703D01*
X22915Y-344620D01*
X23421Y-345126D01*
X23941Y-345341D01*
Y-343600D01*
Y-341859D01*
D02*
G37*
G36*
X19941D02*
X19421Y-342074D01*
X18915Y-342580D01*
X18703Y-343092D01*
X18179D01*
X17967Y-342580D01*
X17461Y-342074D01*
X16941Y-341859D01*
Y-343600D01*
Y-345341D01*
X17461Y-345126D01*
X17967Y-344620D01*
X18179Y-344108D01*
X18703D01*
X18915Y-344620D01*
X19421Y-345126D01*
X19941Y-345341D01*
Y-343600D01*
Y-341859D01*
D02*
G37*
G36*
X15941D02*
X15421Y-342074D01*
X14915Y-342580D01*
X14703Y-343092D01*
X14179D01*
X13967Y-342580D01*
X13461Y-342074D01*
X12941Y-341859D01*
Y-343600D01*
Y-345341D01*
X13461Y-345126D01*
X13967Y-344620D01*
X14179Y-344108D01*
X14703D01*
X14915Y-344620D01*
X15421Y-345126D01*
X15941Y-345341D01*
Y-343600D01*
Y-341859D01*
D02*
G37*
G36*
X55941D02*
X55421Y-342074D01*
X54915Y-342580D01*
X54703Y-343092D01*
X54179D01*
X53967Y-342580D01*
X53461Y-342074D01*
X52941Y-341859D01*
Y-343600D01*
Y-345341D01*
X53461Y-345126D01*
X53967Y-344620D01*
X54179Y-344108D01*
X54703D01*
X54915Y-344620D01*
X55421Y-345126D01*
X55941Y-345341D01*
Y-343600D01*
Y-341859D01*
D02*
G37*
G36*
X51941D02*
X51421Y-342074D01*
X50915Y-342580D01*
X50703Y-343092D01*
X50179D01*
X49967Y-342580D01*
X49461Y-342074D01*
X48941Y-341859D01*
Y-343600D01*
Y-345341D01*
X49461Y-345126D01*
X49967Y-344620D01*
X50179Y-344108D01*
X50703D01*
X50915Y-344620D01*
X51421Y-345126D01*
X51941Y-345341D01*
Y-343600D01*
Y-341859D01*
D02*
G37*
G36*
X47941D02*
X47421Y-342074D01*
X46915Y-342580D01*
X46703Y-343092D01*
X46179D01*
X45967Y-342580D01*
X45461Y-342074D01*
X44941Y-341859D01*
Y-343600D01*
Y-345341D01*
X45461Y-345126D01*
X45967Y-344620D01*
X46179Y-344108D01*
X46703D01*
X46915Y-344620D01*
X47421Y-345126D01*
X47941Y-345341D01*
Y-343600D01*
Y-341859D01*
D02*
G37*
G36*
X56941D02*
Y-343100D01*
X58182D01*
X57967Y-342580D01*
X57461Y-342074D01*
X56941Y-341859D01*
D02*
G37*
G36*
X11941D02*
X11421Y-342074D01*
X10915Y-342580D01*
X10700Y-343100D01*
X11941D01*
Y-341859D01*
D02*
G37*
G36*
X58182Y-344100D02*
X56941D01*
Y-345341D01*
X57461Y-345126D01*
X57967Y-344620D01*
X58182Y-344100D01*
D02*
G37*
G36*
X11941D02*
X10700D01*
X10915Y-344620D01*
X11421Y-345126D01*
X11941Y-345341D01*
Y-344100D01*
D02*
G37*
G36*
X43941Y-349859D02*
X43421Y-350074D01*
X42915Y-350580D01*
X42703Y-351092D01*
X42179D01*
X41967Y-350580D01*
X41461Y-350074D01*
X40941Y-349859D01*
Y-351600D01*
Y-353341D01*
X41461Y-353126D01*
X41967Y-352620D01*
X42179Y-352108D01*
X42703D01*
X42915Y-352620D01*
X43421Y-353126D01*
X43941Y-353341D01*
Y-351600D01*
Y-349859D01*
D02*
G37*
G36*
X39941D02*
X39421Y-350074D01*
X38915Y-350580D01*
X38703Y-351092D01*
X38179D01*
X37967Y-350580D01*
X37461Y-350074D01*
X36941Y-349859D01*
Y-351600D01*
Y-353341D01*
X37461Y-353126D01*
X37967Y-352620D01*
X38179Y-352108D01*
X38703D01*
X38915Y-352620D01*
X39421Y-353126D01*
X39941Y-353341D01*
Y-351600D01*
Y-349859D01*
D02*
G37*
G36*
X35941D02*
X35421Y-350074D01*
X34915Y-350580D01*
X34703Y-351092D01*
X34179D01*
X33967Y-350580D01*
X33461Y-350074D01*
X32941Y-349859D01*
Y-351600D01*
Y-353341D01*
X33461Y-353126D01*
X33967Y-352620D01*
X34179Y-352108D01*
X34703D01*
X34915Y-352620D01*
X35421Y-353126D01*
X35941Y-353341D01*
Y-351600D01*
Y-349859D01*
D02*
G37*
G36*
X31941D02*
X31421Y-350074D01*
X30915Y-350580D01*
X30703Y-351092D01*
X30179D01*
X29967Y-350580D01*
X29461Y-350074D01*
X28941Y-349859D01*
Y-351600D01*
Y-353341D01*
X29461Y-353126D01*
X29967Y-352620D01*
X30179Y-352108D01*
X30703D01*
X30915Y-352620D01*
X31421Y-353126D01*
X31941Y-353341D01*
Y-351600D01*
Y-349859D01*
D02*
G37*
G36*
X27941D02*
X27421Y-350074D01*
X26915Y-350580D01*
X26703Y-351092D01*
X26179D01*
X25967Y-350580D01*
X25461Y-350074D01*
X24941Y-349859D01*
Y-351600D01*
Y-353341D01*
X25461Y-353126D01*
X25967Y-352620D01*
X26179Y-352108D01*
X26703D01*
X26915Y-352620D01*
X27421Y-353126D01*
X27941Y-353341D01*
Y-351600D01*
Y-349859D01*
D02*
G37*
G36*
X23941D02*
X23421Y-350074D01*
X22915Y-350580D01*
X22703Y-351092D01*
X22179D01*
X21967Y-350580D01*
X21461Y-350074D01*
X20941Y-349859D01*
Y-351600D01*
Y-353341D01*
X21461Y-353126D01*
X21967Y-352620D01*
X22179Y-352108D01*
X22703D01*
X22915Y-352620D01*
X23421Y-353126D01*
X23941Y-353341D01*
Y-351600D01*
Y-349859D01*
D02*
G37*
G36*
X19941D02*
X19421Y-350074D01*
X18915Y-350580D01*
X18703Y-351092D01*
X18179D01*
X17967Y-350580D01*
X17461Y-350074D01*
X16941Y-349859D01*
Y-351600D01*
Y-353341D01*
X17461Y-353126D01*
X17967Y-352620D01*
X18179Y-352108D01*
X18703D01*
X18915Y-352620D01*
X19421Y-353126D01*
X19941Y-353341D01*
Y-351600D01*
Y-349859D01*
D02*
G37*
G36*
X15941D02*
X15421Y-350074D01*
X14915Y-350580D01*
X14703Y-351092D01*
X14179D01*
X13967Y-350580D01*
X13461Y-350074D01*
X12941Y-349859D01*
Y-351600D01*
Y-353341D01*
X13461Y-353126D01*
X13967Y-352620D01*
X14179Y-352108D01*
X14703D01*
X14915Y-352620D01*
X15421Y-353126D01*
X15941Y-353341D01*
Y-351600D01*
Y-349859D01*
D02*
G37*
G36*
X11941D02*
X11421Y-350074D01*
X10915Y-350580D01*
X10703Y-351092D01*
X10179D01*
X9967Y-350580D01*
X9461Y-350074D01*
X8941Y-349859D01*
Y-351600D01*
Y-353341D01*
X9461Y-353126D01*
X9967Y-352620D01*
X10179Y-352108D01*
X10703D01*
X10915Y-352620D01*
X11421Y-353126D01*
X11941Y-353341D01*
Y-351600D01*
Y-349859D01*
D02*
G37*
G36*
X7941D02*
X7421Y-350074D01*
X6915Y-350580D01*
X6703Y-351092D01*
X6179D01*
X5967Y-350580D01*
X5461Y-350074D01*
X4941Y-349859D01*
Y-351600D01*
Y-353341D01*
X5461Y-353126D01*
X5967Y-352620D01*
X6179Y-352108D01*
X6703D01*
X6915Y-352620D01*
X7421Y-353126D01*
X7941Y-353341D01*
Y-351600D01*
Y-349859D01*
D02*
G37*
G36*
X3941D02*
X3421Y-350074D01*
X2915Y-350580D01*
X2703Y-351092D01*
X2179D01*
X1967Y-350580D01*
X1461Y-350074D01*
X941Y-349859D01*
Y-351600D01*
Y-353341D01*
X1461Y-353126D01*
X1967Y-352620D01*
X2179Y-352108D01*
X2703D01*
X2915Y-352620D01*
X3421Y-353126D01*
X3941Y-353341D01*
Y-351600D01*
Y-349859D01*
D02*
G37*
G36*
X-59D02*
X-579Y-350074D01*
X-1085Y-350580D01*
X-1297Y-351092D01*
X-1821D01*
X-2033Y-350580D01*
X-2539Y-350074D01*
X-3059Y-349859D01*
Y-351600D01*
Y-353341D01*
X-2539Y-353126D01*
X-2033Y-352620D01*
X-1821Y-352108D01*
X-1297D01*
X-1085Y-352620D01*
X-579Y-353126D01*
X-59Y-353341D01*
Y-351600D01*
Y-349859D01*
D02*
G37*
G36*
X-4059D02*
X-4579Y-350074D01*
X-5085Y-350580D01*
X-5297Y-351092D01*
X-5821D01*
X-6033Y-350580D01*
X-6539Y-350074D01*
X-7059Y-349859D01*
Y-351600D01*
Y-353341D01*
X-6539Y-353126D01*
X-6033Y-352620D01*
X-5821Y-352108D01*
X-5297D01*
X-5085Y-352620D01*
X-4579Y-353126D01*
X-4059Y-353341D01*
Y-351600D01*
Y-349859D01*
D02*
G37*
G36*
X-8059D02*
X-8579Y-350074D01*
X-9085Y-350580D01*
X-9297Y-351092D01*
X-9821D01*
X-10033Y-350580D01*
X-10539Y-350074D01*
X-11059Y-349859D01*
Y-351600D01*
Y-353341D01*
X-10539Y-353126D01*
X-10033Y-352620D01*
X-9821Y-352108D01*
X-9297D01*
X-9085Y-352620D01*
X-8579Y-353126D01*
X-8059Y-353341D01*
Y-351600D01*
Y-349859D01*
D02*
G37*
G36*
X-12059D02*
X-12579Y-350074D01*
X-13085Y-350580D01*
X-13297Y-351092D01*
X-13821D01*
X-14033Y-350580D01*
X-14539Y-350074D01*
X-15059Y-349859D01*
Y-351600D01*
Y-353341D01*
X-14539Y-353126D01*
X-14033Y-352620D01*
X-13821Y-352108D01*
X-13297D01*
X-13085Y-352620D01*
X-12579Y-353126D01*
X-12059Y-353341D01*
Y-351600D01*
Y-349859D01*
D02*
G37*
G36*
X-16059D02*
X-16579Y-350074D01*
X-17085Y-350580D01*
X-17297Y-351092D01*
X-17821D01*
X-18033Y-350580D01*
X-18539Y-350074D01*
X-19059Y-349859D01*
Y-351600D01*
Y-353341D01*
X-18539Y-353126D01*
X-18033Y-352620D01*
X-17821Y-352108D01*
X-17297D01*
X-17085Y-352620D01*
X-16579Y-353126D01*
X-16059Y-353341D01*
Y-351600D01*
Y-349859D01*
D02*
G37*
G36*
X-20059D02*
X-20579Y-350074D01*
X-21085Y-350580D01*
X-21297Y-351092D01*
X-21821D01*
X-22033Y-350580D01*
X-22539Y-350074D01*
X-23059Y-349859D01*
Y-351600D01*
Y-353341D01*
X-22539Y-353126D01*
X-22033Y-352620D01*
X-21821Y-352108D01*
X-21297D01*
X-21085Y-352620D01*
X-20579Y-353126D01*
X-20059Y-353341D01*
Y-351600D01*
Y-349859D01*
D02*
G37*
G36*
X55941D02*
X55421Y-350074D01*
X54915Y-350580D01*
X54703Y-351092D01*
X54179D01*
X53967Y-350580D01*
X53461Y-350074D01*
X52941Y-349859D01*
Y-351600D01*
Y-353341D01*
X53461Y-353126D01*
X53967Y-352620D01*
X54179Y-352108D01*
X54703D01*
X54915Y-352620D01*
X55421Y-353126D01*
X55941Y-353341D01*
Y-351600D01*
Y-349859D01*
D02*
G37*
G36*
X51941D02*
X51421Y-350074D01*
X50915Y-350580D01*
X50703Y-351092D01*
X50179D01*
X49967Y-350580D01*
X49461Y-350074D01*
X48941Y-349859D01*
Y-351600D01*
Y-353341D01*
X49461Y-353126D01*
X49967Y-352620D01*
X50179Y-352108D01*
X50703D01*
X50915Y-352620D01*
X51421Y-353126D01*
X51941Y-353341D01*
Y-351600D01*
Y-349859D01*
D02*
G37*
G36*
X47941D02*
X47421Y-350074D01*
X46915Y-350580D01*
X46703Y-351092D01*
X46179D01*
X45967Y-350580D01*
X45461Y-350074D01*
X44941Y-349859D01*
Y-351600D01*
Y-353341D01*
X45461Y-353126D01*
X45967Y-352620D01*
X46179Y-352108D01*
X46703D01*
X46915Y-352620D01*
X47421Y-353126D01*
X47941Y-353341D01*
Y-351600D01*
Y-349859D01*
D02*
G37*
G36*
X56941D02*
Y-351100D01*
X58182D01*
X57967Y-350580D01*
X57461Y-350074D01*
X56941Y-349859D01*
D02*
G37*
G36*
X-24059D02*
X-24579Y-350074D01*
X-25085Y-350580D01*
X-25300Y-351100D01*
X-24059D01*
Y-349859D01*
D02*
G37*
G36*
X58182Y-352100D02*
X56941D01*
Y-353341D01*
X57461Y-353126D01*
X57967Y-352620D01*
X58182Y-352100D01*
D02*
G37*
G36*
X-24059D02*
X-25300D01*
X-25085Y-352620D01*
X-24579Y-353126D01*
X-24059Y-353341D01*
Y-352100D01*
D02*
G37*
G36*
X573980Y-197019D02*
X573264D01*
X572602Y-197293D01*
X572096Y-197799D01*
X571822Y-198461D01*
Y-199177D01*
X572096Y-199838D01*
X572602Y-200345D01*
X573256Y-200616D01*
X574310Y-201670D01*
Y-202204D01*
X574249D01*
Y-205779D01*
X577430D01*
Y-202204D01*
X577369D01*
Y-201037D01*
X577253Y-200451D01*
X576921Y-199955D01*
X575419Y-198453D01*
X575148Y-197799D01*
X574642Y-197293D01*
X573980Y-197019D01*
D02*
G37*
G36*
X563744Y-256074D02*
X563028D01*
X562366Y-256348D01*
X561860Y-256854D01*
X561586Y-257516D01*
Y-258232D01*
X561860Y-258894D01*
X562366Y-259400D01*
X563028Y-259674D01*
X563167D01*
X563238Y-259745D01*
Y-260811D01*
X563075D01*
Y-264386D01*
X566256D01*
Y-260811D01*
X566093D01*
Y-259154D01*
X566093Y-259154D01*
X565984Y-258607D01*
X565675Y-258144D01*
X565675Y-258144D01*
X565186Y-257655D01*
Y-257516D01*
X564912Y-256854D01*
X564405Y-256348D01*
X563744Y-256074D01*
D02*
G37*
G36*
X163543Y-139693D02*
X161496D01*
X159476Y-140013D01*
X157529Y-140645D01*
X155706Y-141574D01*
X154051Y-142777D01*
X152604Y-144224D01*
X151401Y-145879D01*
X150472Y-147703D01*
X149840Y-149649D01*
X149520Y-151670D01*
Y-152840D01*
X147520Y-153376D01*
X147180Y-152868D01*
X146344Y-152032D01*
X145362Y-151376D01*
X144270Y-150924D01*
X143111Y-150693D01*
X141929D01*
X140770Y-150924D01*
X139678Y-151376D01*
X138695Y-152032D01*
X137859Y-152868D01*
X137203Y-153851D01*
X136750Y-154943D01*
X136520Y-156102D01*
Y-157284D01*
X136750Y-158443D01*
X137203Y-159535D01*
X137859Y-160518D01*
X138695Y-161353D01*
X139678Y-162010D01*
X140770Y-162462D01*
X141929Y-162693D01*
X143111D01*
X144270Y-162462D01*
X145362Y-162010D01*
X146344Y-161353D01*
X147180Y-160518D01*
X147837Y-159535D01*
X148289Y-158443D01*
X148413Y-157819D01*
X150472Y-157683D01*
X151401Y-159506D01*
X152604Y-161162D01*
X154051Y-162609D01*
X155706Y-163812D01*
X157529Y-164741D01*
X159476Y-165373D01*
X161496Y-165693D01*
X163543D01*
X165564Y-165373D01*
X167510Y-164741D01*
X169333Y-163812D01*
X170989Y-162609D01*
X172435Y-161162D01*
X173638Y-159506D01*
X174567Y-157683D01*
X175199Y-155737D01*
X175520Y-153716D01*
Y-151670D01*
X175199Y-149649D01*
X174567Y-147703D01*
X173638Y-145879D01*
X172435Y-144224D01*
X170989Y-142777D01*
X169333Y-141574D01*
X167510Y-140645D01*
X165564Y-140013D01*
X163543Y-139693D01*
D02*
G37*
G36*
X303545Y-149234D02*
X302105D01*
X300692Y-149515D01*
X299362Y-150066D01*
X298165Y-150866D01*
X297146Y-151885D01*
X296346Y-153082D01*
X295795Y-154412D01*
X295778Y-154496D01*
X293608Y-155154D01*
X293331Y-154877D01*
X291676Y-153674D01*
X289852Y-152745D01*
X287906Y-152113D01*
X285885Y-151793D01*
X283839D01*
X281818Y-152113D01*
X279872Y-152745D01*
X278049Y-153674D01*
X276393Y-154877D01*
X274946Y-156324D01*
X273744Y-157979D01*
X272815Y-159803D01*
X272182Y-161749D01*
X271862Y-163770D01*
Y-165816D01*
X272182Y-167837D01*
X272815Y-169783D01*
X273744Y-171606D01*
X274946Y-173262D01*
X276393Y-174709D01*
X278049Y-175911D01*
X279872Y-176840D01*
X281818Y-177473D01*
X283839Y-177793D01*
X285885D01*
X287906Y-177473D01*
X289852Y-176840D01*
X291676Y-175911D01*
X293331Y-174709D01*
X294778Y-173262D01*
X295981Y-171606D01*
X296910Y-169783D01*
X297542Y-167837D01*
X297862Y-165816D01*
Y-164427D01*
X298696Y-163647D01*
X299103Y-163407D01*
X299798Y-163204D01*
X300692Y-163575D01*
X302105Y-163856D01*
X303545D01*
X304957Y-163575D01*
X306288Y-163023D01*
X307485Y-162223D01*
X308503Y-161205D01*
X309303Y-160008D01*
X309855Y-158677D01*
X310135Y-157265D01*
Y-155825D01*
X309855Y-154412D01*
X309303Y-153082D01*
X308503Y-151885D01*
X307485Y-150866D01*
X306288Y-150066D01*
X304957Y-149515D01*
X303545Y-149234D01*
D02*
G37*
G36*
X161043Y-301535D02*
X158996D01*
X156975Y-301855D01*
X155029Y-302488D01*
X153206Y-303417D01*
X151551Y-304620D01*
X150104Y-306066D01*
X148901Y-307722D01*
X148360Y-308783D01*
X146976Y-309596D01*
X145833Y-309655D01*
X145115Y-309358D01*
X143702Y-309077D01*
X142262D01*
X140850Y-309358D01*
X139519Y-309909D01*
X138322Y-310709D01*
X137304Y-311727D01*
X136504Y-312925D01*
X135952Y-314255D01*
X135672Y-315667D01*
Y-317107D01*
X135952Y-318520D01*
X136504Y-319850D01*
X137304Y-321048D01*
X138322Y-322066D01*
X139519Y-322866D01*
X140850Y-323417D01*
X142262Y-323698D01*
X143702D01*
X145115Y-323417D01*
X146445Y-322866D01*
X147223Y-322346D01*
X147678Y-322076D01*
X149863Y-322674D01*
X150104Y-323004D01*
X151551Y-324451D01*
X153206Y-325654D01*
X155029Y-326583D01*
X156975Y-327215D01*
X158996Y-327535D01*
X161043D01*
X163064Y-327215D01*
X165010Y-326583D01*
X166833Y-325654D01*
X168489Y-324451D01*
X169936Y-323004D01*
X171138Y-321349D01*
X172067Y-319526D01*
X172699Y-317580D01*
X173020Y-315559D01*
Y-313512D01*
X172699Y-311491D01*
X172067Y-309545D01*
X171138Y-307722D01*
X169936Y-306066D01*
X168489Y-304620D01*
X166833Y-303417D01*
X165010Y-302488D01*
X163064Y-301855D01*
X161043Y-301535D01*
D02*
G37*
G36*
X286151Y-295632D02*
X284105D01*
X282084Y-295952D01*
X280138Y-296585D01*
X278314Y-297514D01*
X276659Y-298716D01*
X275212Y-300163D01*
X274009Y-301819D01*
X273080Y-303642D01*
X272448Y-305588D01*
X272128Y-307609D01*
Y-309655D01*
X272448Y-311677D01*
X273080Y-313623D01*
X274009Y-315446D01*
X275212Y-317101D01*
X276659Y-318548D01*
X278314Y-319751D01*
X278747Y-319971D01*
X278915Y-320426D01*
X278829Y-322258D01*
X278459Y-322505D01*
X277623Y-323341D01*
X277542Y-323462D01*
X277449Y-323508D01*
X275307D01*
X275214Y-323462D01*
X275133Y-323341D01*
X274297Y-322505D01*
X273314Y-321848D01*
X272223Y-321396D01*
X271063Y-321165D01*
X269882D01*
X268722Y-321396D01*
X267630Y-321848D01*
X266648Y-322505D01*
X265812Y-323341D01*
X265649Y-323585D01*
X265295Y-323726D01*
X263650D01*
X263296Y-323585D01*
X263133Y-323341D01*
X262297Y-322505D01*
X261315Y-321848D01*
X260223Y-321396D01*
X259063Y-321165D01*
X257881D01*
X256722Y-321396D01*
X255630Y-321848D01*
X254648Y-322505D01*
X253812Y-323341D01*
X253649Y-323585D01*
X253295Y-323726D01*
X251650D01*
X251296Y-323585D01*
X251133Y-323341D01*
X250297Y-322505D01*
X249314Y-321848D01*
X248223Y-321396D01*
X247063Y-321165D01*
X245882D01*
X244722Y-321396D01*
X243630Y-321848D01*
X242648Y-322505D01*
X241812Y-323341D01*
X241155Y-324323D01*
X240703Y-325415D01*
X240472Y-326574D01*
Y-327756D01*
X240703Y-328916D01*
X241155Y-330007D01*
X241812Y-330990D01*
X242648Y-331826D01*
X243630Y-332483D01*
X244722Y-332935D01*
X245882Y-333165D01*
X247063D01*
X248223Y-332935D01*
X249314Y-332483D01*
X250297Y-331826D01*
X251133Y-330990D01*
X251296Y-330746D01*
X251650Y-330605D01*
X253295D01*
X253649Y-330746D01*
X253812Y-330990D01*
X254648Y-331826D01*
X255630Y-332483D01*
X256722Y-332935D01*
X257881Y-333165D01*
X259063D01*
X260223Y-332935D01*
X261315Y-332483D01*
X262297Y-331826D01*
X263133Y-330990D01*
X263296Y-330746D01*
X263650Y-330605D01*
X265295D01*
X265649Y-330746D01*
X265812Y-330990D01*
X266648Y-331826D01*
X267630Y-332483D01*
X268722Y-332935D01*
X269882Y-333165D01*
X271063D01*
X272223Y-332935D01*
X273314Y-332483D01*
X274297Y-331826D01*
X275133Y-330990D01*
X275214Y-330869D01*
X275307Y-330823D01*
X277449D01*
X277542Y-330869D01*
X277623Y-330990D01*
X278459Y-331826D01*
X279441Y-332483D01*
X280533Y-332935D01*
X281693Y-333165D01*
X282874D01*
X284034Y-332935D01*
X285125Y-332483D01*
X286108Y-331826D01*
X286944Y-330990D01*
X287025Y-330869D01*
X287118Y-330823D01*
X289260D01*
X289353Y-330869D01*
X289434Y-330990D01*
X290270Y-331826D01*
X291252Y-332483D01*
X292344Y-332935D01*
X293503Y-333165D01*
X294685D01*
X295845Y-332935D01*
X296937Y-332483D01*
X297919Y-331826D01*
X298755Y-330990D01*
X299412Y-330007D01*
X299864Y-328916D01*
X300095Y-327756D01*
Y-326574D01*
X299864Y-325415D01*
X299412Y-324323D01*
X298755Y-323341D01*
X297919Y-322505D01*
X296937Y-321848D01*
X295845Y-321396D01*
X294685Y-321165D01*
X293503D01*
X293357Y-321195D01*
X292536Y-319319D01*
X293597Y-318548D01*
X295044Y-317101D01*
X296246Y-315446D01*
X297175Y-313623D01*
X297808Y-311677D01*
X298128Y-309655D01*
Y-307609D01*
X297808Y-305588D01*
X297175Y-303642D01*
X296246Y-301819D01*
X295044Y-300163D01*
X293597Y-298716D01*
X291941Y-297514D01*
X290118Y-296585D01*
X288172Y-295952D01*
X286151Y-295632D01*
D02*
G37*
G36*
X380046Y-333636D02*
X379949D01*
Y-333668D01*
X379917D01*
Y-333636D01*
X376142D01*
Y-333668D01*
X375981D01*
Y-333700D01*
X375884D01*
Y-333733D01*
X375820D01*
Y-333765D01*
X375787D01*
Y-333797D01*
X375755D01*
Y-333829D01*
X375723D01*
Y-333862D01*
X375691D01*
Y-333894D01*
X375658D01*
Y-333926D01*
X375626D01*
Y-333958D01*
X375594D01*
Y-333991D01*
X375562D01*
Y-334023D01*
X375529D01*
Y-334055D01*
X375497D01*
Y-334087D01*
X375465D01*
Y-334120D01*
X375433D01*
Y-334152D01*
X375400D01*
Y-334184D01*
X375368D01*
Y-334216D01*
X375336D01*
Y-334249D01*
X375304D01*
Y-334281D01*
X375271D01*
Y-334313D01*
X375239D01*
Y-334346D01*
X375207D01*
Y-334378D01*
X375174D01*
Y-334410D01*
X375142D01*
Y-334442D01*
X375110D01*
Y-334474D01*
X375078D01*
Y-334507D01*
X375045D01*
Y-334539D01*
X375013D01*
Y-334571D01*
X374981D01*
Y-334604D01*
X374949D01*
Y-334636D01*
X374916D01*
Y-334668D01*
X374884D01*
Y-334700D01*
Y-334733D01*
Y-334765D01*
X374852D01*
Y-334797D01*
Y-334829D01*
Y-334862D01*
Y-334894D01*
Y-334926D01*
X374820D01*
Y-334959D01*
Y-334991D01*
Y-335023D01*
Y-335055D01*
Y-335087D01*
Y-335120D01*
Y-335152D01*
Y-335184D01*
Y-335217D01*
Y-335249D01*
Y-335281D01*
Y-335313D01*
Y-335346D01*
Y-335378D01*
Y-335410D01*
Y-335442D01*
Y-335475D01*
Y-335507D01*
Y-335539D01*
Y-335572D01*
Y-335604D01*
Y-335636D01*
Y-335668D01*
Y-335700D01*
Y-335733D01*
Y-335765D01*
Y-335797D01*
Y-335830D01*
Y-335862D01*
Y-335894D01*
Y-335926D01*
Y-335959D01*
Y-335991D01*
Y-336023D01*
Y-336055D01*
Y-336088D01*
Y-336120D01*
Y-336152D01*
Y-336184D01*
Y-336217D01*
Y-336249D01*
Y-336281D01*
Y-336314D01*
Y-336346D01*
Y-336378D01*
Y-336410D01*
Y-336442D01*
Y-336475D01*
Y-336507D01*
Y-336539D01*
Y-336572D01*
Y-336604D01*
Y-336636D01*
Y-336668D01*
Y-336701D01*
Y-336733D01*
Y-336765D01*
Y-336797D01*
Y-336830D01*
Y-336862D01*
Y-336894D01*
Y-336927D01*
Y-336959D01*
Y-336991D01*
Y-337023D01*
Y-337055D01*
Y-337088D01*
Y-337120D01*
Y-337152D01*
Y-337185D01*
Y-337217D01*
Y-337249D01*
Y-337281D01*
Y-337314D01*
Y-337346D01*
Y-337378D01*
Y-337410D01*
Y-337443D01*
Y-337475D01*
Y-337507D01*
Y-337539D01*
Y-337572D01*
Y-337604D01*
Y-337636D01*
Y-337668D01*
Y-337701D01*
Y-337733D01*
Y-337765D01*
Y-337797D01*
Y-337830D01*
Y-337862D01*
Y-337894D01*
Y-337927D01*
Y-337959D01*
Y-337991D01*
Y-338023D01*
Y-338056D01*
Y-338088D01*
Y-338120D01*
Y-338152D01*
Y-338185D01*
Y-338217D01*
Y-338249D01*
Y-338281D01*
Y-338314D01*
Y-338346D01*
Y-338378D01*
Y-338410D01*
Y-338443D01*
Y-338475D01*
Y-338507D01*
Y-338540D01*
Y-338572D01*
Y-338604D01*
Y-338636D01*
Y-338669D01*
Y-338701D01*
Y-338733D01*
Y-338765D01*
Y-338798D01*
Y-338830D01*
Y-338862D01*
Y-338894D01*
Y-338927D01*
Y-338959D01*
Y-338991D01*
Y-339023D01*
Y-339056D01*
Y-339088D01*
Y-339120D01*
Y-339153D01*
Y-339185D01*
Y-339217D01*
Y-339249D01*
Y-339282D01*
Y-339314D01*
Y-339346D01*
Y-339378D01*
Y-339411D01*
X374852D01*
Y-339443D01*
Y-339475D01*
Y-339507D01*
Y-339540D01*
Y-339572D01*
X374884D01*
Y-339604D01*
Y-339636D01*
X374916D01*
Y-339669D01*
Y-339701D01*
X374949D01*
Y-339733D01*
X374981D01*
Y-339766D01*
X375013D01*
Y-339798D01*
X375045D01*
Y-339830D01*
X375078D01*
Y-339862D01*
X375110D01*
Y-339895D01*
X375142D01*
Y-339927D01*
X375174D01*
Y-339959D01*
X375207D01*
Y-339991D01*
X375239D01*
Y-340024D01*
X375271D01*
Y-340056D01*
X375304D01*
Y-340088D01*
X375336D01*
Y-340120D01*
X375368D01*
Y-340153D01*
X375400D01*
Y-340185D01*
X375433D01*
Y-340217D01*
X375465D01*
Y-340249D01*
X375497D01*
Y-340282D01*
X375529D01*
Y-340314D01*
X375562D01*
Y-340346D01*
X375594D01*
Y-340378D01*
X375626D01*
Y-340411D01*
X375658D01*
Y-340443D01*
X375691D01*
Y-340475D01*
X375723D01*
Y-340508D01*
X375755D01*
Y-340540D01*
X375787D01*
Y-340572D01*
X375820D01*
Y-340604D01*
X375884D01*
Y-340637D01*
X376013D01*
Y-340669D01*
X380111D01*
Y-340637D01*
X380143D01*
Y-340604D01*
X380175D01*
Y-340572D01*
Y-340540D01*
X380207D01*
Y-340508D01*
Y-340475D01*
Y-340443D01*
Y-340411D01*
Y-340378D01*
Y-340346D01*
Y-340314D01*
Y-340282D01*
Y-340249D01*
Y-340217D01*
Y-340185D01*
Y-340153D01*
Y-340120D01*
Y-340088D01*
Y-340056D01*
Y-340024D01*
Y-339991D01*
Y-339959D01*
Y-339927D01*
Y-339895D01*
Y-339862D01*
Y-339830D01*
Y-339798D01*
Y-339766D01*
Y-339733D01*
Y-339701D01*
Y-339669D01*
Y-339636D01*
Y-339604D01*
Y-339572D01*
Y-339540D01*
Y-339507D01*
Y-339475D01*
Y-339443D01*
Y-339411D01*
Y-339378D01*
Y-339346D01*
Y-339314D01*
Y-339282D01*
Y-339249D01*
Y-339217D01*
Y-339185D01*
Y-339153D01*
X380175D01*
Y-339120D01*
Y-339088D01*
X380143D01*
Y-339056D01*
X380078D01*
Y-339023D01*
X376626D01*
Y-338991D01*
X376594D01*
Y-338959D01*
Y-338927D01*
Y-338894D01*
Y-338862D01*
Y-338830D01*
Y-338798D01*
Y-338765D01*
Y-338733D01*
Y-338701D01*
Y-338669D01*
Y-338636D01*
Y-338604D01*
Y-338572D01*
Y-338540D01*
Y-338507D01*
Y-338475D01*
Y-338443D01*
Y-338410D01*
Y-338378D01*
Y-338346D01*
Y-338314D01*
Y-338281D01*
Y-338249D01*
Y-338217D01*
Y-338185D01*
Y-338152D01*
Y-338120D01*
Y-338088D01*
Y-338056D01*
Y-338023D01*
Y-337991D01*
Y-337959D01*
Y-337927D01*
Y-337894D01*
X376626D01*
Y-337862D01*
X379594D01*
Y-337830D01*
X379659D01*
Y-337797D01*
Y-337765D01*
X379691D01*
Y-337733D01*
Y-337701D01*
Y-337668D01*
Y-337636D01*
Y-337604D01*
Y-337572D01*
Y-337539D01*
Y-337507D01*
Y-337475D01*
Y-337443D01*
Y-337410D01*
Y-337378D01*
Y-337346D01*
Y-337314D01*
Y-337281D01*
Y-337249D01*
Y-337217D01*
Y-337185D01*
Y-337152D01*
Y-337120D01*
Y-337088D01*
Y-337055D01*
Y-337023D01*
Y-336991D01*
Y-336959D01*
Y-336927D01*
Y-336894D01*
Y-336862D01*
Y-336830D01*
Y-336797D01*
Y-336765D01*
Y-336733D01*
Y-336701D01*
Y-336668D01*
Y-336636D01*
Y-336604D01*
Y-336572D01*
X379659D01*
Y-336539D01*
Y-336507D01*
X379594D01*
Y-336475D01*
X376626D01*
Y-336442D01*
X376594D01*
Y-336410D01*
Y-336378D01*
Y-336346D01*
Y-336314D01*
Y-336281D01*
Y-336249D01*
Y-336217D01*
Y-336184D01*
Y-336152D01*
Y-336120D01*
Y-336088D01*
Y-336055D01*
Y-336023D01*
Y-335991D01*
Y-335959D01*
Y-335926D01*
Y-335894D01*
Y-335862D01*
Y-335830D01*
Y-335797D01*
Y-335765D01*
Y-335733D01*
Y-335700D01*
Y-335668D01*
Y-335636D01*
Y-335604D01*
Y-335572D01*
Y-335539D01*
Y-335507D01*
Y-335475D01*
Y-335442D01*
Y-335410D01*
Y-335378D01*
Y-335346D01*
Y-335313D01*
X376626D01*
Y-335281D01*
X380111D01*
Y-335249D01*
X380143D01*
Y-335217D01*
X380175D01*
Y-335184D01*
X380207D01*
Y-335152D01*
Y-335120D01*
Y-335087D01*
Y-335055D01*
Y-335023D01*
Y-334991D01*
Y-334959D01*
Y-334926D01*
Y-334894D01*
Y-334862D01*
Y-334829D01*
Y-334797D01*
Y-334765D01*
Y-334733D01*
Y-334700D01*
Y-334668D01*
Y-334636D01*
Y-334604D01*
Y-334571D01*
Y-334539D01*
Y-334507D01*
Y-334474D01*
Y-334442D01*
Y-334410D01*
Y-334378D01*
Y-334346D01*
Y-334313D01*
Y-334281D01*
Y-334249D01*
Y-334216D01*
Y-334184D01*
Y-334152D01*
Y-334120D01*
Y-334087D01*
Y-334055D01*
Y-334023D01*
Y-333991D01*
Y-333958D01*
Y-333926D01*
Y-333894D01*
Y-333862D01*
Y-333829D01*
Y-333797D01*
X380175D01*
Y-333765D01*
Y-333733D01*
X380143D01*
Y-333700D01*
X380111D01*
Y-333668D01*
X380046D01*
Y-333636D01*
D02*
G37*
G36*
X363528D02*
X363463D01*
Y-333668D01*
X363431D01*
Y-333636D01*
X358463D01*
Y-333668D01*
X358366D01*
Y-333700D01*
X358334D01*
Y-333733D01*
Y-333765D01*
X358302D01*
Y-333797D01*
Y-333829D01*
Y-333862D01*
Y-333894D01*
Y-333926D01*
Y-333958D01*
Y-333991D01*
Y-334023D01*
Y-334055D01*
Y-334087D01*
Y-334120D01*
Y-334152D01*
Y-334184D01*
Y-334216D01*
Y-334249D01*
Y-334281D01*
Y-334313D01*
Y-334346D01*
Y-334378D01*
Y-334410D01*
Y-334442D01*
Y-334474D01*
Y-334507D01*
Y-334539D01*
Y-334571D01*
Y-334604D01*
Y-334636D01*
Y-334668D01*
Y-334700D01*
Y-334733D01*
Y-334765D01*
Y-334797D01*
Y-334829D01*
Y-334862D01*
Y-334894D01*
Y-334926D01*
Y-334959D01*
Y-334991D01*
Y-335023D01*
Y-335055D01*
Y-335087D01*
Y-335120D01*
Y-335152D01*
Y-335184D01*
Y-335217D01*
Y-335249D01*
X358334D01*
Y-335281D01*
X358366D01*
Y-335313D01*
X358398D01*
Y-335346D01*
X358463D01*
Y-335378D01*
X360012D01*
Y-335410D01*
X360044D01*
Y-335442D01*
X360076D01*
Y-335475D01*
Y-335507D01*
X360108D01*
Y-335539D01*
Y-335572D01*
Y-335604D01*
Y-335636D01*
Y-335668D01*
Y-335700D01*
Y-335733D01*
Y-335765D01*
Y-335797D01*
Y-335830D01*
Y-335862D01*
Y-335894D01*
Y-335926D01*
Y-335959D01*
Y-335991D01*
Y-336023D01*
Y-336055D01*
Y-336088D01*
Y-336120D01*
Y-336152D01*
Y-336184D01*
Y-336217D01*
Y-336249D01*
Y-336281D01*
Y-336314D01*
Y-336346D01*
Y-336378D01*
Y-336410D01*
Y-336442D01*
Y-336475D01*
Y-336507D01*
Y-336539D01*
Y-336572D01*
Y-336604D01*
Y-336636D01*
Y-336668D01*
Y-336701D01*
Y-336733D01*
Y-336765D01*
Y-336797D01*
Y-336830D01*
Y-336862D01*
Y-336894D01*
Y-336927D01*
Y-336959D01*
Y-336991D01*
Y-337023D01*
Y-337055D01*
Y-337088D01*
Y-337120D01*
Y-337152D01*
Y-337185D01*
Y-337217D01*
Y-337249D01*
Y-337281D01*
Y-337314D01*
Y-337346D01*
Y-337378D01*
Y-337410D01*
Y-337443D01*
Y-337475D01*
Y-337507D01*
Y-337539D01*
Y-337572D01*
Y-337604D01*
Y-337636D01*
Y-337668D01*
Y-337701D01*
Y-337733D01*
Y-337765D01*
Y-337797D01*
Y-337830D01*
Y-337862D01*
Y-337894D01*
Y-337927D01*
Y-337959D01*
Y-337991D01*
Y-338023D01*
Y-338056D01*
Y-338088D01*
Y-338120D01*
Y-338152D01*
Y-338185D01*
Y-338217D01*
Y-338249D01*
Y-338281D01*
Y-338314D01*
Y-338346D01*
Y-338378D01*
Y-338410D01*
Y-338443D01*
Y-338475D01*
Y-338507D01*
Y-338540D01*
Y-338572D01*
Y-338604D01*
Y-338636D01*
Y-338669D01*
Y-338701D01*
Y-338733D01*
Y-338765D01*
Y-338798D01*
Y-338830D01*
Y-338862D01*
Y-338894D01*
Y-338927D01*
Y-338959D01*
Y-338991D01*
Y-339023D01*
Y-339056D01*
Y-339088D01*
Y-339120D01*
Y-339153D01*
Y-339185D01*
Y-339217D01*
Y-339249D01*
Y-339282D01*
Y-339314D01*
Y-339346D01*
Y-339378D01*
Y-339411D01*
Y-339443D01*
Y-339475D01*
Y-339507D01*
Y-339540D01*
Y-339572D01*
Y-339604D01*
Y-339636D01*
Y-339669D01*
Y-339701D01*
Y-339733D01*
Y-339766D01*
Y-339798D01*
Y-339830D01*
Y-339862D01*
Y-339895D01*
Y-339927D01*
Y-339959D01*
Y-339991D01*
Y-340024D01*
Y-340056D01*
Y-340088D01*
Y-340120D01*
Y-340153D01*
Y-340185D01*
Y-340217D01*
Y-340249D01*
Y-340282D01*
Y-340314D01*
Y-340346D01*
Y-340378D01*
Y-340411D01*
Y-340443D01*
Y-340475D01*
Y-340508D01*
Y-340540D01*
Y-340572D01*
X360140D01*
Y-340604D01*
X360173D01*
Y-340637D01*
X360205D01*
Y-340669D01*
X361786D01*
Y-340637D01*
X361818D01*
Y-340604D01*
X361850D01*
Y-340572D01*
Y-340540D01*
Y-340508D01*
X361883D01*
Y-340475D01*
Y-340443D01*
Y-340411D01*
Y-340378D01*
Y-340346D01*
Y-340314D01*
Y-340282D01*
Y-340249D01*
Y-340217D01*
Y-340185D01*
Y-340153D01*
Y-340120D01*
Y-340088D01*
Y-340056D01*
Y-340024D01*
Y-339991D01*
Y-339959D01*
Y-339927D01*
Y-339895D01*
Y-339862D01*
Y-339830D01*
Y-339798D01*
Y-339766D01*
Y-339733D01*
Y-339701D01*
Y-339669D01*
Y-339636D01*
Y-339604D01*
Y-339572D01*
Y-339540D01*
Y-339507D01*
Y-339475D01*
Y-339443D01*
Y-339411D01*
Y-339378D01*
Y-339346D01*
Y-339314D01*
Y-339282D01*
Y-339249D01*
Y-339217D01*
Y-339185D01*
Y-339153D01*
Y-339120D01*
Y-339088D01*
Y-339056D01*
Y-339023D01*
Y-338991D01*
Y-338959D01*
Y-338927D01*
Y-338894D01*
Y-338862D01*
Y-338830D01*
Y-338798D01*
Y-338765D01*
Y-338733D01*
Y-338701D01*
Y-338669D01*
Y-338636D01*
Y-338604D01*
Y-338572D01*
Y-338540D01*
Y-338507D01*
Y-338475D01*
Y-338443D01*
Y-338410D01*
Y-338378D01*
Y-338346D01*
Y-338314D01*
Y-338281D01*
Y-338249D01*
Y-338217D01*
Y-338185D01*
Y-338152D01*
Y-338120D01*
Y-338088D01*
Y-338056D01*
Y-338023D01*
Y-337991D01*
Y-337959D01*
Y-337927D01*
Y-337894D01*
Y-337862D01*
Y-337830D01*
Y-337797D01*
Y-337765D01*
Y-337733D01*
Y-337701D01*
Y-337668D01*
Y-337636D01*
Y-337604D01*
Y-337572D01*
Y-337539D01*
Y-337507D01*
Y-337475D01*
Y-337443D01*
Y-337410D01*
Y-337378D01*
Y-337346D01*
Y-337314D01*
Y-337281D01*
Y-337249D01*
Y-337217D01*
Y-337185D01*
Y-337152D01*
Y-337120D01*
Y-337088D01*
Y-337055D01*
Y-337023D01*
Y-336991D01*
Y-336959D01*
Y-336927D01*
Y-336894D01*
Y-336862D01*
Y-336830D01*
Y-336797D01*
Y-336765D01*
Y-336733D01*
Y-336701D01*
Y-336668D01*
Y-336636D01*
Y-336604D01*
Y-336572D01*
Y-336539D01*
Y-336507D01*
Y-336475D01*
Y-336442D01*
Y-336410D01*
Y-336378D01*
Y-336346D01*
Y-336314D01*
Y-336281D01*
Y-336249D01*
Y-336217D01*
Y-336184D01*
Y-336152D01*
Y-336120D01*
Y-336088D01*
Y-336055D01*
Y-336023D01*
Y-335991D01*
Y-335959D01*
Y-335926D01*
Y-335894D01*
Y-335862D01*
Y-335830D01*
Y-335797D01*
Y-335765D01*
Y-335733D01*
Y-335700D01*
Y-335668D01*
Y-335636D01*
Y-335604D01*
Y-335572D01*
Y-335539D01*
Y-335507D01*
Y-335475D01*
Y-335442D01*
X361915D01*
Y-335410D01*
X361947D01*
Y-335378D01*
X363496D01*
Y-335346D01*
X363593D01*
Y-335313D01*
X363625D01*
Y-335281D01*
X363657D01*
Y-335249D01*
Y-335217D01*
Y-335184D01*
X363689D01*
Y-335152D01*
Y-335120D01*
Y-335087D01*
Y-335055D01*
Y-335023D01*
Y-334991D01*
Y-334959D01*
Y-334926D01*
Y-334894D01*
Y-334862D01*
Y-334829D01*
Y-334797D01*
Y-334765D01*
Y-334733D01*
Y-334700D01*
Y-334668D01*
Y-334636D01*
Y-334604D01*
Y-334571D01*
Y-334539D01*
Y-334507D01*
Y-334474D01*
Y-334442D01*
Y-334410D01*
Y-334378D01*
Y-334346D01*
Y-334313D01*
Y-334281D01*
Y-334249D01*
Y-334216D01*
Y-334184D01*
Y-334152D01*
Y-334120D01*
Y-334087D01*
Y-334055D01*
Y-334023D01*
Y-333991D01*
Y-333958D01*
Y-333926D01*
Y-333894D01*
Y-333862D01*
Y-333829D01*
X363657D01*
Y-333797D01*
Y-333765D01*
Y-333733D01*
X363625D01*
Y-333700D01*
X363593D01*
Y-333668D01*
X363528D01*
Y-333636D01*
D02*
G37*
G36*
X371755D02*
X366819D01*
Y-333668D01*
X366722D01*
Y-333700D01*
X366690D01*
Y-333733D01*
Y-333765D01*
X366657D01*
Y-333797D01*
Y-333829D01*
Y-333862D01*
Y-333894D01*
Y-333926D01*
Y-333958D01*
Y-333991D01*
Y-334023D01*
Y-334055D01*
Y-334087D01*
Y-334120D01*
Y-334152D01*
Y-334184D01*
Y-334216D01*
Y-334249D01*
Y-334281D01*
Y-334313D01*
Y-334346D01*
Y-334378D01*
Y-334410D01*
Y-334442D01*
Y-334474D01*
Y-334507D01*
Y-334539D01*
Y-334571D01*
Y-334604D01*
Y-334636D01*
Y-334668D01*
Y-334700D01*
Y-334733D01*
Y-334765D01*
Y-334797D01*
Y-334829D01*
Y-334862D01*
Y-334894D01*
Y-334926D01*
Y-334959D01*
Y-334991D01*
Y-335023D01*
Y-335055D01*
Y-335087D01*
Y-335120D01*
Y-335152D01*
Y-335184D01*
Y-335217D01*
Y-335249D01*
Y-335281D01*
Y-335313D01*
Y-335346D01*
Y-335378D01*
Y-335410D01*
Y-335442D01*
Y-335475D01*
Y-335507D01*
Y-335539D01*
Y-335572D01*
Y-335604D01*
Y-335636D01*
Y-335668D01*
Y-335700D01*
Y-335733D01*
Y-335765D01*
Y-335797D01*
Y-335830D01*
Y-335862D01*
Y-335894D01*
Y-335926D01*
Y-335959D01*
Y-335991D01*
Y-336023D01*
Y-336055D01*
Y-336088D01*
Y-336120D01*
Y-336152D01*
Y-336184D01*
Y-336217D01*
Y-336249D01*
Y-336281D01*
Y-336314D01*
Y-336346D01*
Y-336378D01*
Y-336410D01*
Y-336442D01*
Y-336475D01*
Y-336507D01*
Y-336539D01*
Y-336572D01*
Y-336604D01*
Y-336636D01*
Y-336668D01*
Y-336701D01*
Y-336733D01*
Y-336765D01*
Y-336797D01*
Y-336830D01*
Y-336862D01*
Y-336894D01*
Y-336927D01*
Y-336959D01*
Y-336991D01*
Y-337023D01*
Y-337055D01*
Y-337088D01*
Y-337120D01*
Y-337152D01*
Y-337185D01*
Y-337217D01*
Y-337249D01*
Y-337281D01*
Y-337314D01*
Y-337346D01*
Y-337378D01*
Y-337410D01*
Y-337443D01*
Y-337475D01*
Y-337507D01*
Y-337539D01*
Y-337572D01*
Y-337604D01*
Y-337636D01*
Y-337668D01*
Y-337701D01*
Y-337733D01*
Y-337765D01*
Y-337797D01*
Y-337830D01*
Y-337862D01*
Y-337894D01*
Y-337927D01*
Y-337959D01*
Y-337991D01*
Y-338023D01*
Y-338056D01*
Y-338088D01*
Y-338120D01*
Y-338152D01*
Y-338185D01*
Y-338217D01*
Y-338249D01*
Y-338281D01*
Y-338314D01*
Y-338346D01*
Y-338378D01*
Y-338410D01*
Y-338443D01*
Y-338475D01*
Y-338507D01*
Y-338540D01*
Y-338572D01*
Y-338604D01*
Y-338636D01*
Y-338669D01*
Y-338701D01*
Y-338733D01*
Y-338765D01*
Y-338798D01*
Y-338830D01*
Y-338862D01*
Y-338894D01*
Y-338927D01*
Y-338959D01*
Y-338991D01*
Y-339023D01*
Y-339056D01*
Y-339088D01*
Y-339120D01*
Y-339153D01*
Y-339185D01*
Y-339217D01*
Y-339249D01*
Y-339282D01*
Y-339314D01*
Y-339346D01*
Y-339378D01*
Y-339411D01*
Y-339443D01*
Y-339475D01*
Y-339507D01*
Y-339540D01*
Y-339572D01*
Y-339604D01*
Y-339636D01*
Y-339669D01*
Y-339701D01*
Y-339733D01*
Y-339766D01*
Y-339798D01*
Y-339830D01*
Y-339862D01*
Y-339895D01*
Y-339927D01*
Y-339959D01*
Y-339991D01*
Y-340024D01*
Y-340056D01*
Y-340088D01*
Y-340120D01*
Y-340153D01*
Y-340185D01*
Y-340217D01*
Y-340249D01*
Y-340282D01*
Y-340314D01*
Y-340346D01*
Y-340378D01*
Y-340411D01*
Y-340443D01*
Y-340475D01*
Y-340508D01*
Y-340540D01*
Y-340572D01*
X366690D01*
Y-340604D01*
Y-340637D01*
X366754D01*
Y-340669D01*
X368335D01*
Y-340637D01*
X368367D01*
Y-340604D01*
X368400D01*
Y-340572D01*
Y-340540D01*
X368432D01*
Y-340508D01*
Y-340475D01*
Y-340443D01*
Y-340411D01*
Y-340378D01*
Y-340346D01*
Y-340314D01*
Y-340282D01*
Y-340249D01*
Y-340217D01*
Y-340185D01*
Y-340153D01*
Y-340120D01*
Y-340088D01*
Y-340056D01*
Y-340024D01*
Y-339991D01*
Y-339959D01*
Y-339927D01*
Y-339895D01*
Y-339862D01*
Y-339830D01*
Y-339798D01*
Y-339766D01*
Y-339733D01*
Y-339701D01*
Y-339669D01*
Y-339636D01*
Y-339604D01*
Y-339572D01*
Y-339540D01*
Y-339507D01*
Y-339475D01*
Y-339443D01*
Y-339411D01*
Y-339378D01*
Y-339346D01*
Y-339314D01*
Y-339282D01*
Y-339249D01*
Y-339217D01*
Y-339185D01*
Y-339153D01*
Y-339120D01*
Y-339088D01*
Y-339056D01*
Y-339023D01*
Y-338991D01*
Y-338959D01*
Y-338927D01*
Y-338894D01*
Y-338862D01*
Y-338830D01*
Y-338798D01*
Y-338765D01*
Y-338733D01*
Y-338701D01*
Y-338669D01*
Y-338636D01*
Y-338604D01*
Y-338572D01*
Y-338540D01*
Y-338507D01*
Y-338475D01*
Y-338443D01*
Y-338410D01*
Y-338378D01*
Y-338346D01*
Y-338314D01*
Y-338281D01*
Y-338249D01*
Y-338217D01*
Y-338185D01*
Y-338152D01*
Y-338120D01*
Y-338088D01*
Y-338056D01*
Y-338023D01*
Y-337991D01*
Y-337959D01*
Y-337927D01*
Y-337894D01*
Y-337862D01*
Y-337830D01*
Y-337797D01*
Y-337765D01*
Y-337733D01*
Y-337701D01*
Y-337668D01*
Y-337636D01*
Y-337604D01*
Y-337572D01*
Y-337539D01*
Y-337507D01*
Y-337475D01*
Y-337443D01*
Y-337410D01*
Y-337378D01*
Y-337346D01*
Y-337314D01*
Y-337281D01*
Y-337249D01*
Y-337217D01*
Y-337185D01*
Y-337152D01*
Y-337120D01*
Y-337088D01*
Y-337055D01*
Y-337023D01*
Y-336991D01*
Y-336959D01*
Y-336927D01*
Y-336894D01*
Y-336862D01*
Y-336830D01*
Y-336797D01*
Y-336765D01*
Y-336733D01*
Y-336701D01*
Y-336668D01*
Y-336636D01*
Y-336604D01*
Y-336572D01*
Y-336539D01*
Y-336507D01*
Y-336475D01*
Y-336442D01*
Y-336410D01*
Y-336378D01*
Y-336346D01*
Y-336314D01*
Y-336281D01*
Y-336249D01*
Y-336217D01*
Y-336184D01*
Y-336152D01*
Y-336120D01*
Y-336088D01*
Y-336055D01*
Y-336023D01*
Y-335991D01*
Y-335959D01*
Y-335926D01*
Y-335894D01*
Y-335862D01*
Y-335830D01*
Y-335797D01*
Y-335765D01*
Y-335733D01*
Y-335700D01*
Y-335668D01*
Y-335636D01*
Y-335604D01*
Y-335572D01*
Y-335539D01*
Y-335507D01*
Y-335475D01*
Y-335442D01*
Y-335410D01*
Y-335378D01*
X369529D01*
Y-335410D01*
Y-335442D01*
Y-335475D01*
Y-335507D01*
Y-335539D01*
Y-335572D01*
Y-335604D01*
Y-335636D01*
Y-335668D01*
Y-335700D01*
Y-335733D01*
Y-335765D01*
Y-335797D01*
Y-335830D01*
Y-335862D01*
Y-335894D01*
Y-335926D01*
Y-335959D01*
Y-335991D01*
Y-336023D01*
Y-336055D01*
Y-336088D01*
Y-336120D01*
Y-336152D01*
Y-336184D01*
Y-336217D01*
Y-336249D01*
Y-336281D01*
Y-336314D01*
Y-336346D01*
Y-336378D01*
Y-336410D01*
Y-336442D01*
Y-336475D01*
Y-336507D01*
Y-336539D01*
Y-336572D01*
Y-336604D01*
Y-336636D01*
Y-336668D01*
Y-336701D01*
Y-336733D01*
Y-336765D01*
Y-336797D01*
Y-336830D01*
Y-336862D01*
Y-336894D01*
Y-336927D01*
Y-336959D01*
Y-336991D01*
Y-337023D01*
Y-337055D01*
Y-337088D01*
Y-337120D01*
Y-337152D01*
Y-337185D01*
Y-337217D01*
Y-337249D01*
Y-337281D01*
Y-337314D01*
Y-337346D01*
Y-337378D01*
Y-337410D01*
Y-337443D01*
Y-337475D01*
Y-337507D01*
Y-337539D01*
Y-337572D01*
Y-337604D01*
Y-337636D01*
Y-337668D01*
Y-337701D01*
Y-337733D01*
Y-337765D01*
Y-337797D01*
Y-337830D01*
Y-337862D01*
Y-337894D01*
Y-337927D01*
Y-337959D01*
Y-337991D01*
Y-338023D01*
Y-338056D01*
Y-338088D01*
Y-338120D01*
Y-338152D01*
Y-338185D01*
Y-338217D01*
Y-338249D01*
Y-338281D01*
Y-338314D01*
Y-338346D01*
Y-338378D01*
Y-338410D01*
Y-338443D01*
Y-338475D01*
Y-338507D01*
Y-338540D01*
Y-338572D01*
Y-338604D01*
Y-338636D01*
Y-338669D01*
Y-338701D01*
Y-338733D01*
Y-338765D01*
Y-338798D01*
Y-338830D01*
Y-338862D01*
Y-338894D01*
Y-338927D01*
Y-338959D01*
Y-338991D01*
Y-339023D01*
Y-339056D01*
Y-339088D01*
Y-339120D01*
Y-339153D01*
Y-339185D01*
Y-339217D01*
Y-339249D01*
Y-339282D01*
Y-339314D01*
Y-339346D01*
Y-339378D01*
Y-339411D01*
Y-339443D01*
Y-339475D01*
Y-339507D01*
Y-339540D01*
Y-339572D01*
Y-339604D01*
Y-339636D01*
Y-339669D01*
Y-339701D01*
Y-339733D01*
Y-339766D01*
Y-339798D01*
Y-339830D01*
Y-339862D01*
Y-339895D01*
Y-339927D01*
Y-339959D01*
Y-339991D01*
Y-340024D01*
Y-340056D01*
Y-340088D01*
Y-340120D01*
Y-340153D01*
Y-340185D01*
Y-340217D01*
Y-340249D01*
Y-340282D01*
Y-340314D01*
Y-340346D01*
Y-340378D01*
Y-340411D01*
Y-340443D01*
Y-340475D01*
Y-340508D01*
Y-340540D01*
X369561D01*
Y-340572D01*
Y-340604D01*
X369593D01*
Y-340637D01*
X369658D01*
Y-340669D01*
X371077D01*
Y-340637D01*
X371110D01*
Y-340604D01*
X371142D01*
Y-340572D01*
X371174D01*
Y-340540D01*
Y-340508D01*
Y-340475D01*
Y-340443D01*
Y-340411D01*
Y-340378D01*
Y-340346D01*
Y-340314D01*
Y-340282D01*
Y-340249D01*
Y-340217D01*
Y-340185D01*
Y-340153D01*
Y-340120D01*
Y-340088D01*
Y-340056D01*
Y-340024D01*
Y-339991D01*
Y-339959D01*
Y-339927D01*
Y-339895D01*
Y-339862D01*
Y-339830D01*
Y-339798D01*
Y-339766D01*
Y-339733D01*
Y-339701D01*
Y-339669D01*
Y-339636D01*
Y-339604D01*
Y-339572D01*
Y-339540D01*
Y-339507D01*
Y-339475D01*
Y-339443D01*
Y-339411D01*
Y-339378D01*
Y-339346D01*
Y-339314D01*
Y-339282D01*
Y-339249D01*
Y-339217D01*
Y-339185D01*
Y-339153D01*
Y-339120D01*
Y-339088D01*
Y-339056D01*
Y-339023D01*
Y-338991D01*
Y-338959D01*
Y-338927D01*
Y-338894D01*
Y-338862D01*
Y-338830D01*
Y-338798D01*
Y-338765D01*
Y-338733D01*
Y-338701D01*
Y-338669D01*
Y-338636D01*
Y-338604D01*
Y-338572D01*
Y-338540D01*
Y-338507D01*
Y-338475D01*
Y-338443D01*
Y-338410D01*
Y-338378D01*
Y-338346D01*
Y-338314D01*
Y-338281D01*
Y-338249D01*
Y-338217D01*
Y-338185D01*
Y-338152D01*
Y-338120D01*
Y-338088D01*
Y-338056D01*
Y-338023D01*
Y-337991D01*
Y-337959D01*
Y-337927D01*
Y-337894D01*
Y-337862D01*
Y-337830D01*
Y-337797D01*
Y-337765D01*
Y-337733D01*
Y-337701D01*
Y-337668D01*
Y-337636D01*
Y-337604D01*
Y-337572D01*
Y-337539D01*
Y-337507D01*
Y-337475D01*
Y-337443D01*
Y-337410D01*
Y-337378D01*
Y-337346D01*
Y-337314D01*
Y-337281D01*
Y-337249D01*
Y-337217D01*
Y-337185D01*
Y-337152D01*
Y-337120D01*
Y-337088D01*
Y-337055D01*
Y-337023D01*
Y-336991D01*
Y-336959D01*
Y-336927D01*
Y-336894D01*
Y-336862D01*
Y-336830D01*
Y-336797D01*
Y-336765D01*
Y-336733D01*
Y-336701D01*
Y-336668D01*
Y-336636D01*
Y-336604D01*
Y-336572D01*
Y-336539D01*
Y-336507D01*
Y-336475D01*
Y-336442D01*
Y-336410D01*
Y-336378D01*
Y-336346D01*
Y-336314D01*
Y-336281D01*
Y-336249D01*
Y-336217D01*
Y-336184D01*
Y-336152D01*
Y-336120D01*
Y-336088D01*
Y-336055D01*
Y-336023D01*
Y-335991D01*
Y-335959D01*
Y-335926D01*
Y-335894D01*
Y-335862D01*
Y-335830D01*
Y-335797D01*
Y-335765D01*
Y-335733D01*
Y-335700D01*
Y-335668D01*
Y-335636D01*
Y-335604D01*
Y-335572D01*
Y-335539D01*
Y-335507D01*
Y-335475D01*
Y-335442D01*
Y-335410D01*
Y-335378D01*
X371626D01*
Y-335346D01*
X371658D01*
Y-335378D01*
X371755D01*
Y-335346D01*
Y-335313D01*
Y-335281D01*
Y-335249D01*
Y-335217D01*
Y-335184D01*
Y-335152D01*
Y-335120D01*
Y-335087D01*
Y-335055D01*
Y-335023D01*
Y-334991D01*
Y-334959D01*
Y-334926D01*
Y-334894D01*
Y-334862D01*
Y-334829D01*
Y-334797D01*
Y-334765D01*
Y-334733D01*
Y-334700D01*
Y-334668D01*
Y-334636D01*
Y-334604D01*
Y-334571D01*
Y-334539D01*
Y-334507D01*
Y-334474D01*
Y-334442D01*
Y-334410D01*
Y-334378D01*
Y-334346D01*
Y-334313D01*
Y-334281D01*
Y-334249D01*
Y-334216D01*
Y-334184D01*
Y-334152D01*
Y-334120D01*
Y-334087D01*
Y-334055D01*
Y-334023D01*
Y-333991D01*
Y-333958D01*
Y-333926D01*
Y-333894D01*
Y-333862D01*
Y-333829D01*
Y-333797D01*
Y-333765D01*
Y-333733D01*
Y-333700D01*
Y-333668D01*
Y-333636D01*
D02*
G37*
G36*
X365722D02*
X364238D01*
Y-333668D01*
X364141D01*
Y-333700D01*
Y-333733D01*
X364109D01*
Y-333765D01*
Y-333797D01*
X364076D01*
Y-333829D01*
Y-333862D01*
Y-333894D01*
Y-333926D01*
Y-333958D01*
Y-333991D01*
Y-334023D01*
Y-334055D01*
Y-334087D01*
Y-334120D01*
Y-334152D01*
Y-334184D01*
Y-334216D01*
Y-334249D01*
Y-334281D01*
Y-334313D01*
Y-334346D01*
Y-334378D01*
Y-334410D01*
Y-334442D01*
Y-334474D01*
Y-334507D01*
Y-334539D01*
Y-334571D01*
Y-334604D01*
Y-334636D01*
Y-334668D01*
Y-334700D01*
Y-334733D01*
Y-334765D01*
Y-334797D01*
Y-334829D01*
Y-334862D01*
Y-334894D01*
Y-334926D01*
Y-334959D01*
Y-334991D01*
Y-335023D01*
Y-335055D01*
Y-335087D01*
Y-335120D01*
Y-335152D01*
Y-335184D01*
Y-335217D01*
Y-335249D01*
Y-335281D01*
Y-335313D01*
Y-335346D01*
Y-335378D01*
Y-335410D01*
Y-335442D01*
Y-335475D01*
Y-335507D01*
Y-335539D01*
Y-335572D01*
Y-335604D01*
Y-335636D01*
Y-335668D01*
Y-335700D01*
Y-335733D01*
Y-335765D01*
Y-335797D01*
Y-335830D01*
Y-335862D01*
Y-335894D01*
Y-335926D01*
Y-335959D01*
Y-335991D01*
Y-336023D01*
Y-336055D01*
Y-336088D01*
Y-336120D01*
Y-336152D01*
Y-336184D01*
Y-336217D01*
Y-336249D01*
Y-336281D01*
Y-336314D01*
Y-336346D01*
Y-336378D01*
Y-336410D01*
Y-336442D01*
Y-336475D01*
Y-336507D01*
Y-336539D01*
Y-336572D01*
Y-336604D01*
Y-336636D01*
Y-336668D01*
Y-336701D01*
Y-336733D01*
Y-336765D01*
Y-336797D01*
Y-336830D01*
Y-336862D01*
Y-336894D01*
Y-336927D01*
Y-336959D01*
Y-336991D01*
Y-337023D01*
Y-337055D01*
Y-337088D01*
Y-337120D01*
Y-337152D01*
Y-337185D01*
Y-337217D01*
Y-337249D01*
Y-337281D01*
Y-337314D01*
Y-337346D01*
Y-337378D01*
Y-337410D01*
Y-337443D01*
Y-337475D01*
Y-337507D01*
Y-337539D01*
Y-337572D01*
Y-337604D01*
Y-337636D01*
Y-337668D01*
Y-337701D01*
Y-337733D01*
Y-337765D01*
Y-337797D01*
Y-337830D01*
Y-337862D01*
Y-337894D01*
Y-337927D01*
Y-337959D01*
Y-337991D01*
Y-338023D01*
Y-338056D01*
Y-338088D01*
Y-338120D01*
Y-338152D01*
Y-338185D01*
Y-338217D01*
Y-338249D01*
Y-338281D01*
Y-338314D01*
Y-338346D01*
Y-338378D01*
Y-338410D01*
Y-338443D01*
Y-338475D01*
Y-338507D01*
Y-338540D01*
Y-338572D01*
Y-338604D01*
Y-338636D01*
Y-338669D01*
Y-338701D01*
Y-338733D01*
Y-338765D01*
Y-338798D01*
Y-338830D01*
Y-338862D01*
Y-338894D01*
Y-338927D01*
Y-338959D01*
Y-338991D01*
Y-339023D01*
Y-339056D01*
Y-339088D01*
Y-339120D01*
Y-339153D01*
Y-339185D01*
Y-339217D01*
Y-339249D01*
Y-339282D01*
Y-339314D01*
Y-339346D01*
Y-339378D01*
Y-339411D01*
Y-339443D01*
Y-339475D01*
Y-339507D01*
Y-339540D01*
Y-339572D01*
Y-339604D01*
Y-339636D01*
Y-339669D01*
Y-339701D01*
Y-339733D01*
Y-339766D01*
Y-339798D01*
Y-339830D01*
Y-339862D01*
Y-339895D01*
Y-339927D01*
Y-339959D01*
Y-339991D01*
Y-340024D01*
Y-340056D01*
Y-340088D01*
Y-340120D01*
Y-340153D01*
Y-340185D01*
Y-340217D01*
Y-340249D01*
Y-340282D01*
Y-340314D01*
Y-340346D01*
Y-340378D01*
Y-340411D01*
Y-340443D01*
Y-340475D01*
Y-340508D01*
Y-340540D01*
X364109D01*
Y-340572D01*
Y-340604D01*
X364141D01*
Y-340637D01*
X364173D01*
Y-340669D01*
X365786D01*
Y-340637D01*
X365819D01*
Y-340604D01*
X365851D01*
Y-340572D01*
Y-340540D01*
Y-340508D01*
Y-340475D01*
Y-340443D01*
Y-340411D01*
Y-340378D01*
Y-340346D01*
Y-340314D01*
Y-340282D01*
Y-340249D01*
Y-340217D01*
Y-340185D01*
Y-340153D01*
Y-340120D01*
Y-340088D01*
Y-340056D01*
Y-340024D01*
Y-339991D01*
Y-339959D01*
Y-339927D01*
Y-339895D01*
Y-339862D01*
Y-339830D01*
Y-339798D01*
Y-339766D01*
Y-339733D01*
Y-339701D01*
Y-339669D01*
Y-339636D01*
Y-339604D01*
Y-339572D01*
Y-339540D01*
Y-339507D01*
Y-339475D01*
Y-339443D01*
Y-339411D01*
Y-339378D01*
Y-339346D01*
Y-339314D01*
Y-339282D01*
Y-339249D01*
Y-339217D01*
Y-339185D01*
Y-339153D01*
Y-339120D01*
Y-339088D01*
Y-339056D01*
Y-339023D01*
Y-338991D01*
Y-338959D01*
Y-338927D01*
Y-338894D01*
Y-338862D01*
Y-338830D01*
Y-338798D01*
Y-338765D01*
Y-338733D01*
Y-338701D01*
Y-338669D01*
Y-338636D01*
Y-338604D01*
Y-338572D01*
Y-338540D01*
Y-338507D01*
Y-338475D01*
Y-338443D01*
Y-338410D01*
Y-338378D01*
Y-338346D01*
Y-338314D01*
Y-338281D01*
Y-338249D01*
Y-338217D01*
Y-338185D01*
Y-338152D01*
Y-338120D01*
Y-338088D01*
Y-338056D01*
Y-338023D01*
Y-337991D01*
Y-337959D01*
Y-337927D01*
Y-337894D01*
Y-337862D01*
Y-337830D01*
Y-337797D01*
Y-337765D01*
Y-337733D01*
Y-337701D01*
Y-337668D01*
Y-337636D01*
Y-337604D01*
Y-337572D01*
Y-337539D01*
Y-337507D01*
Y-337475D01*
Y-337443D01*
Y-337410D01*
Y-337378D01*
Y-337346D01*
Y-337314D01*
Y-337281D01*
Y-337249D01*
Y-337217D01*
Y-337185D01*
Y-337152D01*
Y-337120D01*
Y-337088D01*
Y-337055D01*
Y-337023D01*
Y-336991D01*
Y-336959D01*
Y-336927D01*
Y-336894D01*
Y-336862D01*
Y-336830D01*
Y-336797D01*
Y-336765D01*
Y-336733D01*
Y-336701D01*
Y-336668D01*
Y-336636D01*
Y-336604D01*
Y-336572D01*
Y-336539D01*
Y-336507D01*
Y-336475D01*
Y-336442D01*
Y-336410D01*
Y-336378D01*
Y-336346D01*
Y-336314D01*
Y-336281D01*
Y-336249D01*
Y-336217D01*
Y-336184D01*
Y-336152D01*
Y-336120D01*
Y-336088D01*
Y-336055D01*
Y-336023D01*
Y-335991D01*
Y-335959D01*
Y-335926D01*
Y-335894D01*
Y-335862D01*
Y-335830D01*
Y-335797D01*
Y-335765D01*
Y-335733D01*
Y-335700D01*
Y-335668D01*
Y-335636D01*
Y-335604D01*
Y-335572D01*
Y-335539D01*
Y-335507D01*
Y-335475D01*
Y-335442D01*
Y-335410D01*
Y-335378D01*
Y-335346D01*
Y-335313D01*
Y-335281D01*
Y-335249D01*
Y-335217D01*
Y-335184D01*
Y-335152D01*
Y-335120D01*
Y-335087D01*
Y-335055D01*
Y-335023D01*
Y-334991D01*
Y-334959D01*
Y-334926D01*
Y-334894D01*
Y-334862D01*
Y-334829D01*
Y-334797D01*
Y-334765D01*
Y-334733D01*
Y-334700D01*
Y-334668D01*
Y-334636D01*
Y-334604D01*
Y-334571D01*
Y-334539D01*
Y-334507D01*
Y-334474D01*
Y-334442D01*
Y-334410D01*
Y-334378D01*
Y-334346D01*
Y-334313D01*
Y-334281D01*
Y-334249D01*
Y-334216D01*
Y-334184D01*
Y-334152D01*
Y-334120D01*
Y-334087D01*
Y-334055D01*
Y-334023D01*
Y-333991D01*
Y-333958D01*
Y-333926D01*
Y-333894D01*
Y-333862D01*
Y-333829D01*
Y-333797D01*
Y-333765D01*
Y-333733D01*
X365819D01*
Y-333700D01*
X365786D01*
Y-333668D01*
X365722D01*
Y-333636D01*
D02*
G37*
G36*
X373981Y-328442D02*
X372787D01*
Y-328474D01*
X372303D01*
Y-328506D01*
X371981D01*
Y-328538D01*
X371723D01*
Y-328571D01*
X371529D01*
Y-328603D01*
X371303D01*
Y-328635D01*
X371110D01*
Y-328667D01*
X370948D01*
Y-328700D01*
X370787D01*
Y-328732D01*
X370626D01*
Y-328764D01*
X370497D01*
Y-328797D01*
X370368D01*
Y-328829D01*
X370238D01*
Y-328861D01*
X370109D01*
Y-328893D01*
X370013D01*
Y-328925D01*
X369884D01*
Y-328958D01*
X369787D01*
Y-328990D01*
X369690D01*
Y-329022D01*
X369561D01*
Y-329055D01*
X369464D01*
Y-329087D01*
X369367D01*
Y-329119D01*
X369271D01*
Y-329151D01*
X369206D01*
Y-329184D01*
X369109D01*
Y-329216D01*
X369012D01*
Y-329248D01*
X368916D01*
Y-329280D01*
X368851D01*
Y-329313D01*
X368754D01*
Y-329345D01*
X368690D01*
Y-329377D01*
X368593D01*
Y-329410D01*
X368529D01*
Y-329442D01*
X368464D01*
Y-329474D01*
X368367D01*
Y-329506D01*
X368303D01*
Y-329538D01*
X368238D01*
Y-329571D01*
X368174D01*
Y-329603D01*
X368077D01*
Y-329635D01*
X368012D01*
Y-329667D01*
X367948D01*
Y-329700D01*
X367883D01*
Y-329732D01*
X367819D01*
Y-329764D01*
X367754D01*
Y-329797D01*
X367690D01*
Y-329829D01*
X367625D01*
Y-329861D01*
X367561D01*
Y-329893D01*
X367496D01*
Y-329926D01*
X367464D01*
Y-329958D01*
X367399D01*
Y-329990D01*
X367335D01*
Y-330022D01*
X367270D01*
Y-330055D01*
X367206D01*
Y-330087D01*
X367174D01*
Y-330119D01*
X367109D01*
Y-330152D01*
X367044D01*
Y-330184D01*
X367012D01*
Y-330216D01*
X366948D01*
Y-330248D01*
X366883D01*
Y-330280D01*
X366851D01*
Y-330313D01*
X366786D01*
Y-330345D01*
X366722D01*
Y-330377D01*
X366690D01*
Y-330410D01*
X366625D01*
Y-330442D01*
X366593D01*
Y-330474D01*
X366528D01*
Y-330506D01*
X366496D01*
Y-330539D01*
X366431D01*
Y-330571D01*
X366399D01*
Y-330603D01*
X366335D01*
Y-330635D01*
X366302D01*
Y-330668D01*
X366238D01*
Y-330700D01*
X366206D01*
Y-330732D01*
X366173D01*
Y-330764D01*
X366109D01*
Y-330797D01*
X366077D01*
Y-330829D01*
X366012D01*
Y-330861D01*
X365980D01*
Y-330893D01*
X365948D01*
Y-330926D01*
X365883D01*
Y-330958D01*
X365851D01*
Y-330990D01*
X365819D01*
Y-331023D01*
X365754D01*
Y-331055D01*
X365722D01*
Y-331087D01*
X365689D01*
Y-331119D01*
X365657D01*
Y-331152D01*
X365593D01*
Y-331184D01*
X365561D01*
Y-331216D01*
X365528D01*
Y-331248D01*
X365496D01*
Y-331281D01*
X365431D01*
Y-331313D01*
X365399D01*
Y-331345D01*
X365367D01*
Y-331377D01*
X365335D01*
Y-331410D01*
X365302D01*
Y-331442D01*
X365238D01*
Y-331474D01*
X365206D01*
Y-331506D01*
X365173D01*
Y-331539D01*
X365141D01*
Y-331571D01*
X365109D01*
Y-331603D01*
X365076D01*
Y-331635D01*
X365044D01*
Y-331668D01*
X365012D01*
Y-331700D01*
X364948D01*
Y-331732D01*
X364915D01*
Y-331765D01*
X364883D01*
Y-331797D01*
X364851D01*
Y-331829D01*
X364818D01*
Y-331861D01*
X364786D01*
Y-331894D01*
X364754D01*
Y-331926D01*
X364722D01*
Y-331958D01*
X364689D01*
Y-331990D01*
X364657D01*
Y-332023D01*
X364625D01*
Y-332055D01*
X364593D01*
Y-332087D01*
X364560D01*
Y-332119D01*
X364528D01*
Y-332152D01*
X364496D01*
Y-332184D01*
X364464D01*
Y-332216D01*
X364431D01*
Y-332248D01*
X364399D01*
Y-332281D01*
X364367D01*
Y-332313D01*
X364335D01*
Y-332345D01*
X364302D01*
Y-332378D01*
X364270D01*
Y-332410D01*
X364238D01*
Y-332442D01*
X364206D01*
Y-332474D01*
X364173D01*
Y-332507D01*
Y-332539D01*
X364141D01*
Y-332571D01*
X364109D01*
Y-332603D01*
X364076D01*
Y-332636D01*
X364044D01*
Y-332668D01*
X364012D01*
Y-332700D01*
X363980D01*
Y-332732D01*
X363947D01*
Y-332765D01*
X363915D01*
Y-332797D01*
Y-332829D01*
X363883D01*
Y-332861D01*
X363851D01*
Y-332894D01*
X363818D01*
Y-332926D01*
X363786D01*
Y-332958D01*
X363754D01*
Y-332991D01*
Y-333023D01*
X363721D01*
Y-333055D01*
X363689D01*
Y-333087D01*
X363657D01*
Y-333120D01*
X364173D01*
Y-333087D01*
X364206D01*
Y-333055D01*
X364238D01*
Y-333023D01*
Y-332991D01*
X364270D01*
Y-332958D01*
X364302D01*
Y-332926D01*
X364335D01*
Y-332894D01*
X364367D01*
Y-332861D01*
X364399D01*
Y-332829D01*
X364431D01*
Y-332797D01*
X364464D01*
Y-332765D01*
X364496D01*
Y-332732D01*
Y-332700D01*
X364528D01*
Y-332668D01*
X364560D01*
Y-332636D01*
X364593D01*
Y-332603D01*
X364625D01*
Y-332571D01*
X364657D01*
Y-332539D01*
X364689D01*
Y-332507D01*
X364722D01*
Y-332474D01*
X364754D01*
Y-332442D01*
X364786D01*
Y-332410D01*
X364818D01*
Y-332378D01*
X364851D01*
Y-332345D01*
X364883D01*
Y-332313D01*
X364915D01*
Y-332281D01*
X364948D01*
Y-332248D01*
X364980D01*
Y-332216D01*
X365012D01*
Y-332184D01*
X365044D01*
Y-332152D01*
X365076D01*
Y-332119D01*
X365109D01*
Y-332087D01*
X365141D01*
Y-332055D01*
X365206D01*
Y-332023D01*
X365238D01*
Y-331990D01*
X365270D01*
Y-331958D01*
X365302D01*
Y-331926D01*
X365335D01*
Y-331894D01*
X365367D01*
Y-331861D01*
X365399D01*
Y-331829D01*
X365431D01*
Y-331797D01*
X365464D01*
Y-331765D01*
X365528D01*
Y-331732D01*
X365561D01*
Y-331700D01*
X365593D01*
Y-331668D01*
X365625D01*
Y-331635D01*
X365657D01*
Y-331603D01*
X365722D01*
Y-331571D01*
X365754D01*
Y-331539D01*
X365786D01*
Y-331506D01*
X365819D01*
Y-331474D01*
X365883D01*
Y-331442D01*
X365915D01*
Y-331410D01*
X365948D01*
Y-331377D01*
X365980D01*
Y-331345D01*
X366044D01*
Y-331313D01*
X366077D01*
Y-331281D01*
X366109D01*
Y-331248D01*
X366173D01*
Y-331216D01*
X366206D01*
Y-331184D01*
X366238D01*
Y-331152D01*
X366302D01*
Y-331119D01*
X366335D01*
Y-331087D01*
X366367D01*
Y-331055D01*
X366431D01*
Y-331023D01*
X366464D01*
Y-330990D01*
X366528D01*
Y-330958D01*
X366561D01*
Y-330926D01*
X366625D01*
Y-330893D01*
X366657D01*
Y-330861D01*
X366722D01*
Y-330829D01*
X366754D01*
Y-330797D01*
X366819D01*
Y-330764D01*
X366851D01*
Y-330732D01*
X366915D01*
Y-330700D01*
X366948D01*
Y-330668D01*
X367012D01*
Y-330635D01*
X367077D01*
Y-330603D01*
X367109D01*
Y-330571D01*
X367174D01*
Y-330539D01*
X367238D01*
Y-330506D01*
X367270D01*
Y-330474D01*
X367335D01*
Y-330442D01*
X367399D01*
Y-330410D01*
X367432D01*
Y-330377D01*
X367496D01*
Y-330345D01*
X367561D01*
Y-330313D01*
X367625D01*
Y-330280D01*
X367690D01*
Y-330248D01*
X367754D01*
Y-330216D01*
X367819D01*
Y-330184D01*
X367851D01*
Y-330152D01*
X367916D01*
Y-330119D01*
X367980D01*
Y-330087D01*
X368045D01*
Y-330055D01*
X368109D01*
Y-330022D01*
X368206D01*
Y-329990D01*
X368270D01*
Y-329958D01*
X368335D01*
Y-329926D01*
X368400D01*
Y-329893D01*
X368464D01*
Y-329861D01*
X368529D01*
Y-329829D01*
X368625D01*
Y-329797D01*
X368690D01*
Y-329764D01*
X368754D01*
Y-329732D01*
X368851D01*
Y-329700D01*
X368916D01*
Y-329667D01*
X369012D01*
Y-329635D01*
X369109D01*
Y-329603D01*
X369174D01*
Y-329571D01*
X369271D01*
Y-329538D01*
X369367D01*
Y-329506D01*
X369464D01*
Y-329474D01*
X369529D01*
Y-329442D01*
X369658D01*
Y-329410D01*
X369755D01*
Y-329377D01*
X369851D01*
Y-329345D01*
X369948D01*
Y-329313D01*
X370077D01*
Y-329280D01*
X370174D01*
Y-329248D01*
X370303D01*
Y-329216D01*
X370432D01*
Y-329184D01*
X370561D01*
Y-329151D01*
X370690D01*
Y-329119D01*
X370851D01*
Y-329087D01*
X371013D01*
Y-329055D01*
X371142D01*
Y-329022D01*
X371368D01*
Y-328990D01*
X371561D01*
Y-328958D01*
X371787D01*
Y-328925D01*
X372045D01*
Y-328893D01*
X372400D01*
Y-328861D01*
X372981D01*
Y-328829D01*
X373787D01*
Y-328861D01*
X373819D01*
Y-328829D01*
X373852D01*
Y-328861D01*
X374368D01*
Y-328893D01*
X374723D01*
Y-328925D01*
X375013D01*
Y-328958D01*
X375207D01*
Y-328990D01*
X375400D01*
Y-329022D01*
X375594D01*
Y-329055D01*
X375755D01*
Y-329087D01*
X375917D01*
Y-329119D01*
X376078D01*
Y-329151D01*
X376207D01*
Y-329184D01*
X376336D01*
Y-329216D01*
X376465D01*
Y-329248D01*
X376594D01*
Y-329280D01*
X376691D01*
Y-329313D01*
X376820D01*
Y-329345D01*
X376917D01*
Y-329377D01*
X377013D01*
Y-329410D01*
X377110D01*
Y-329442D01*
X377207D01*
Y-329474D01*
X377304D01*
Y-329506D01*
X377401D01*
Y-329538D01*
X377497D01*
Y-329571D01*
X377594D01*
Y-329603D01*
X377659D01*
Y-329635D01*
X377755D01*
Y-329667D01*
X377820D01*
Y-329700D01*
X377917D01*
Y-329732D01*
X377981D01*
Y-329764D01*
X378078D01*
Y-329797D01*
X378143D01*
Y-329829D01*
X378207D01*
Y-329861D01*
X378304D01*
Y-329893D01*
X378368D01*
Y-329926D01*
X378433D01*
Y-329958D01*
X378497D01*
Y-329990D01*
X378562D01*
Y-330022D01*
X378659D01*
Y-330055D01*
X378723D01*
Y-330087D01*
X378755D01*
Y-330119D01*
X378820D01*
Y-330152D01*
X378885D01*
Y-330184D01*
X378949D01*
Y-330216D01*
X379014D01*
Y-330248D01*
X379078D01*
Y-330280D01*
X379143D01*
Y-330313D01*
X379207D01*
Y-330345D01*
X379272D01*
Y-330377D01*
X379304D01*
Y-330410D01*
X379368D01*
Y-330442D01*
X379433D01*
Y-330474D01*
X379498D01*
Y-330506D01*
X379530D01*
Y-330539D01*
X379594D01*
Y-330571D01*
X379659D01*
Y-330603D01*
X379691D01*
Y-330635D01*
X379756D01*
Y-330668D01*
X379820D01*
Y-330700D01*
X379852D01*
Y-330732D01*
X379917D01*
Y-330764D01*
X379949D01*
Y-330797D01*
X380014D01*
Y-330829D01*
X380046D01*
Y-330861D01*
X380111D01*
Y-330893D01*
X380143D01*
Y-330926D01*
X380207D01*
Y-330958D01*
X380240D01*
Y-330990D01*
X380304D01*
Y-331023D01*
X380336D01*
Y-331055D01*
X380369D01*
Y-331087D01*
X380433D01*
Y-331119D01*
X380465D01*
Y-331152D01*
X380530D01*
Y-331184D01*
X380562D01*
Y-331216D01*
X380594D01*
Y-331248D01*
X380659D01*
Y-331281D01*
X380691D01*
Y-331313D01*
X380724D01*
Y-331345D01*
X380788D01*
Y-331377D01*
X380820D01*
Y-331410D01*
X380853D01*
Y-331442D01*
X380885D01*
Y-331474D01*
X380949D01*
Y-331506D01*
X380982D01*
Y-331539D01*
X381014D01*
Y-331571D01*
X381046D01*
Y-331603D01*
X381111D01*
Y-331635D01*
X381143D01*
Y-331668D01*
X381175D01*
Y-331700D01*
X381207D01*
Y-331732D01*
X381240D01*
Y-331765D01*
X381272D01*
Y-331797D01*
X381336D01*
Y-331829D01*
X381369D01*
Y-331861D01*
X381401D01*
Y-331894D01*
X381433D01*
Y-331926D01*
X381466D01*
Y-331958D01*
X381498D01*
Y-331990D01*
X381530D01*
Y-332023D01*
X381562D01*
Y-332055D01*
X381595D01*
Y-332087D01*
X381659D01*
Y-332119D01*
X381691D01*
Y-332152D01*
X381724D01*
Y-332184D01*
X381756D01*
Y-332216D01*
X381788D01*
Y-332248D01*
X381820D01*
Y-332281D01*
X381853D01*
Y-332313D01*
X381885D01*
Y-332345D01*
X381917D01*
Y-332378D01*
X381949D01*
Y-332410D01*
X381982D01*
Y-332442D01*
X382014D01*
Y-332474D01*
X382046D01*
Y-332507D01*
X382079D01*
Y-332539D01*
X382111D01*
Y-332571D01*
X382143D01*
Y-332603D01*
X382175D01*
Y-332636D01*
X382207D01*
Y-332668D01*
Y-332700D01*
X382240D01*
Y-332732D01*
X382272D01*
Y-332765D01*
X382304D01*
Y-332797D01*
X382337D01*
Y-332829D01*
X382369D01*
Y-332861D01*
X382401D01*
Y-332894D01*
X382433D01*
Y-332926D01*
X382466D01*
Y-332958D01*
X382498D01*
Y-332991D01*
Y-333023D01*
X382530D01*
Y-333055D01*
X382562D01*
Y-333087D01*
X382595D01*
Y-333120D01*
X382627D01*
Y-333152D01*
X382659D01*
Y-333184D01*
X382692D01*
Y-333216D01*
Y-333249D01*
X382724D01*
Y-333281D01*
X382756D01*
Y-333313D01*
X382788D01*
Y-333345D01*
X382821D01*
Y-333378D01*
Y-333410D01*
X382853D01*
Y-333442D01*
X382885D01*
Y-333474D01*
X382917D01*
Y-333507D01*
X382950D01*
Y-333539D01*
Y-333571D01*
X382982D01*
Y-333604D01*
X383014D01*
Y-333636D01*
X383046D01*
Y-333668D01*
Y-333700D01*
X383079D01*
Y-333733D01*
X383111D01*
Y-333765D01*
X383143D01*
Y-333797D01*
Y-333829D01*
X383175D01*
Y-333862D01*
X383208D01*
Y-333894D01*
Y-333926D01*
X383240D01*
Y-333958D01*
X383272D01*
Y-333991D01*
X383304D01*
Y-334023D01*
Y-334055D01*
X383337D01*
Y-334087D01*
X383369D01*
Y-334120D01*
Y-334152D01*
X383401D01*
Y-334184D01*
X383434D01*
Y-334216D01*
Y-334249D01*
X383466D01*
Y-334281D01*
X383498D01*
Y-334313D01*
Y-334346D01*
X383530D01*
Y-334378D01*
X383562D01*
Y-334410D01*
Y-334442D01*
X383595D01*
Y-334474D01*
X383627D01*
Y-334507D01*
Y-334539D01*
X383659D01*
Y-334571D01*
Y-334604D01*
X383692D01*
Y-334636D01*
X383724D01*
Y-334668D01*
Y-334700D01*
X383756D01*
Y-334733D01*
Y-334765D01*
X383788D01*
Y-334797D01*
X383821D01*
Y-334829D01*
Y-334862D01*
X383853D01*
Y-334894D01*
Y-334926D01*
X383885D01*
Y-334959D01*
Y-334991D01*
X383917D01*
Y-335023D01*
X383950D01*
Y-335055D01*
Y-335087D01*
X383982D01*
Y-335120D01*
Y-335152D01*
X384014D01*
Y-335184D01*
Y-335217D01*
X384047D01*
Y-335249D01*
Y-335281D01*
X384079D01*
Y-335313D01*
Y-335346D01*
X384111D01*
Y-335378D01*
X384143D01*
Y-335410D01*
Y-335442D01*
X384175D01*
Y-335475D01*
Y-335507D01*
X384208D01*
Y-335539D01*
Y-335572D01*
X384240D01*
Y-335604D01*
Y-335636D01*
X384272D01*
Y-335668D01*
Y-335700D01*
Y-335733D01*
X384305D01*
Y-335765D01*
Y-335797D01*
X384337D01*
Y-335830D01*
Y-335862D01*
X384369D01*
Y-335894D01*
Y-335926D01*
X384401D01*
Y-335959D01*
Y-335991D01*
X384434D01*
Y-336023D01*
Y-336055D01*
X384466D01*
Y-336088D01*
Y-336120D01*
Y-336152D01*
X384498D01*
Y-336184D01*
Y-336217D01*
X384530D01*
Y-336249D01*
Y-336281D01*
X384563D01*
Y-336314D01*
Y-336346D01*
Y-336378D01*
X384595D01*
Y-336410D01*
Y-336442D01*
X384627D01*
Y-336475D01*
Y-336507D01*
Y-336539D01*
X384659D01*
Y-336572D01*
Y-336604D01*
X384692D01*
Y-336636D01*
Y-336668D01*
Y-336701D01*
X384724D01*
Y-336733D01*
Y-336765D01*
Y-336797D01*
X384756D01*
Y-336830D01*
Y-336862D01*
Y-336894D01*
X384788D01*
Y-336927D01*
Y-336959D01*
X384821D01*
Y-336991D01*
Y-337023D01*
Y-337055D01*
X384853D01*
Y-337088D01*
Y-337120D01*
Y-337152D01*
X384885D01*
Y-337185D01*
Y-337217D01*
Y-337249D01*
Y-337281D01*
X384917D01*
Y-337314D01*
Y-337346D01*
Y-337378D01*
X384950D01*
Y-337410D01*
Y-337443D01*
Y-337475D01*
X384982D01*
Y-337507D01*
Y-337539D01*
Y-337572D01*
Y-337604D01*
X385014D01*
Y-337636D01*
Y-337668D01*
Y-337701D01*
X385047D01*
Y-337733D01*
Y-337765D01*
Y-337797D01*
Y-337830D01*
X385079D01*
Y-337862D01*
Y-337894D01*
Y-337927D01*
Y-337959D01*
X385111D01*
Y-337991D01*
Y-338023D01*
Y-338056D01*
Y-338088D01*
X385143D01*
Y-338120D01*
Y-338152D01*
Y-338185D01*
Y-338217D01*
X385176D01*
Y-338249D01*
Y-338281D01*
Y-338314D01*
Y-338346D01*
Y-338378D01*
X385208D01*
Y-338410D01*
Y-338443D01*
Y-338475D01*
Y-338507D01*
X385240D01*
Y-338540D01*
Y-338572D01*
Y-338604D01*
Y-338636D01*
Y-338669D01*
Y-338701D01*
X385272D01*
Y-338733D01*
Y-338765D01*
Y-338798D01*
Y-338830D01*
Y-338862D01*
X385305D01*
Y-338894D01*
Y-338927D01*
Y-338959D01*
Y-338991D01*
Y-339023D01*
Y-339056D01*
X385337D01*
Y-339088D01*
Y-339120D01*
Y-339153D01*
Y-339185D01*
Y-339217D01*
Y-339249D01*
Y-339282D01*
X385369D01*
Y-339314D01*
Y-339346D01*
Y-339378D01*
Y-339411D01*
Y-339443D01*
Y-339475D01*
Y-339507D01*
Y-339540D01*
Y-339572D01*
X385402D01*
Y-339604D01*
Y-339636D01*
Y-339669D01*
Y-339701D01*
Y-339733D01*
Y-339766D01*
Y-339798D01*
Y-339830D01*
Y-339862D01*
X385434D01*
Y-339895D01*
Y-339927D01*
Y-339959D01*
Y-339991D01*
Y-340024D01*
Y-340056D01*
Y-340088D01*
Y-340120D01*
Y-340153D01*
Y-340185D01*
Y-340217D01*
Y-340249D01*
Y-340282D01*
Y-340314D01*
Y-340346D01*
Y-340378D01*
Y-340411D01*
X385466D01*
Y-340443D01*
Y-340475D01*
Y-340508D01*
Y-340540D01*
Y-340572D01*
Y-340604D01*
Y-340637D01*
Y-340669D01*
Y-340701D01*
Y-340733D01*
Y-340766D01*
X385853D01*
Y-340733D01*
Y-340701D01*
Y-340669D01*
Y-340637D01*
Y-340604D01*
Y-340572D01*
Y-340540D01*
Y-340508D01*
Y-340475D01*
Y-340443D01*
Y-340411D01*
Y-340378D01*
X385821D01*
Y-340346D01*
X385853D01*
Y-340314D01*
Y-340282D01*
Y-340249D01*
X385821D01*
Y-340217D01*
Y-340185D01*
Y-340153D01*
Y-340120D01*
Y-340088D01*
Y-340056D01*
Y-340024D01*
Y-339991D01*
Y-339959D01*
Y-339927D01*
Y-339895D01*
Y-339862D01*
Y-339830D01*
Y-339798D01*
X385789D01*
Y-339766D01*
Y-339733D01*
Y-339701D01*
Y-339669D01*
Y-339636D01*
Y-339604D01*
Y-339572D01*
Y-339540D01*
Y-339507D01*
Y-339475D01*
X385756D01*
Y-339443D01*
Y-339411D01*
Y-339378D01*
Y-339346D01*
Y-339314D01*
Y-339282D01*
Y-339249D01*
Y-339217D01*
X385724D01*
Y-339185D01*
Y-339153D01*
Y-339120D01*
Y-339088D01*
Y-339056D01*
Y-339023D01*
Y-338991D01*
X385692D01*
Y-338959D01*
Y-338927D01*
Y-338894D01*
Y-338862D01*
Y-338830D01*
Y-338798D01*
X385660D01*
Y-338765D01*
Y-338733D01*
Y-338701D01*
Y-338669D01*
Y-338636D01*
X385627D01*
Y-338604D01*
Y-338572D01*
Y-338540D01*
Y-338507D01*
Y-338475D01*
X385595D01*
Y-338443D01*
Y-338410D01*
Y-338378D01*
Y-338346D01*
Y-338314D01*
X385563D01*
Y-338281D01*
Y-338249D01*
Y-338217D01*
Y-338185D01*
Y-338152D01*
X385530D01*
Y-338120D01*
Y-338088D01*
Y-338056D01*
Y-338023D01*
X385498D01*
Y-337991D01*
Y-337959D01*
Y-337927D01*
Y-337894D01*
X385466D01*
Y-337862D01*
Y-337830D01*
Y-337797D01*
Y-337765D01*
X385434D01*
Y-337733D01*
Y-337701D01*
Y-337668D01*
Y-337636D01*
X385402D01*
Y-337604D01*
Y-337572D01*
Y-337539D01*
X385369D01*
Y-337507D01*
Y-337475D01*
Y-337443D01*
Y-337410D01*
X385337D01*
Y-337378D01*
Y-337346D01*
Y-337314D01*
X385305D01*
Y-337281D01*
Y-337249D01*
Y-337217D01*
Y-337185D01*
X385272D01*
Y-337152D01*
Y-337120D01*
Y-337088D01*
X385240D01*
Y-337055D01*
Y-337023D01*
Y-336991D01*
X385208D01*
Y-336959D01*
Y-336927D01*
Y-336894D01*
X385176D01*
Y-336862D01*
Y-336830D01*
Y-336797D01*
X385143D01*
Y-336765D01*
Y-336733D01*
Y-336701D01*
X385111D01*
Y-336668D01*
Y-336636D01*
X385079D01*
Y-336604D01*
Y-336572D01*
Y-336539D01*
X385047D01*
Y-336507D01*
Y-336475D01*
Y-336442D01*
X385014D01*
Y-336410D01*
Y-336378D01*
X384982D01*
Y-336346D01*
Y-336314D01*
Y-336281D01*
X384950D01*
Y-336249D01*
Y-336217D01*
X384917D01*
Y-336184D01*
Y-336152D01*
Y-336120D01*
X384885D01*
Y-336088D01*
Y-336055D01*
X384853D01*
Y-336023D01*
Y-335991D01*
X384821D01*
Y-335959D01*
Y-335926D01*
Y-335894D01*
X384788D01*
Y-335862D01*
Y-335830D01*
X384756D01*
Y-335797D01*
Y-335765D01*
X384724D01*
Y-335733D01*
Y-335700D01*
X384692D01*
Y-335668D01*
Y-335636D01*
Y-335604D01*
X384659D01*
Y-335572D01*
Y-335539D01*
X384627D01*
Y-335507D01*
Y-335475D01*
X384595D01*
Y-335442D01*
Y-335410D01*
X384563D01*
Y-335378D01*
Y-335346D01*
X384530D01*
Y-335313D01*
Y-335281D01*
X384498D01*
Y-335249D01*
Y-335217D01*
X384466D01*
Y-335184D01*
Y-335152D01*
X384434D01*
Y-335120D01*
Y-335087D01*
X384401D01*
Y-335055D01*
Y-335023D01*
X384369D01*
Y-334991D01*
X384337D01*
Y-334959D01*
Y-334926D01*
X384305D01*
Y-334894D01*
Y-334862D01*
X384272D01*
Y-334829D01*
Y-334797D01*
X384240D01*
Y-334765D01*
Y-334733D01*
X384208D01*
Y-334700D01*
X384175D01*
Y-334668D01*
Y-334636D01*
X384143D01*
Y-334604D01*
Y-334571D01*
X384111D01*
Y-334539D01*
X384079D01*
Y-334507D01*
Y-334474D01*
X384047D01*
Y-334442D01*
Y-334410D01*
X384014D01*
Y-334378D01*
X383982D01*
Y-334346D01*
Y-334313D01*
X383950D01*
Y-334281D01*
Y-334249D01*
X383917D01*
Y-334216D01*
X383885D01*
Y-334184D01*
Y-334152D01*
X383853D01*
Y-334120D01*
X383821D01*
Y-334087D01*
Y-334055D01*
X383788D01*
Y-334023D01*
X383756D01*
Y-333991D01*
Y-333958D01*
X383724D01*
Y-333926D01*
X383692D01*
Y-333894D01*
Y-333862D01*
X383659D01*
Y-333829D01*
X383627D01*
Y-333797D01*
Y-333765D01*
X383595D01*
Y-333733D01*
X383562D01*
Y-333700D01*
X383530D01*
Y-333668D01*
Y-333636D01*
X383498D01*
Y-333604D01*
X383466D01*
Y-333571D01*
Y-333539D01*
X383434D01*
Y-333507D01*
X383401D01*
Y-333474D01*
X383369D01*
Y-333442D01*
Y-333410D01*
X383337D01*
Y-333378D01*
X383304D01*
Y-333345D01*
X383272D01*
Y-333313D01*
X383240D01*
Y-333281D01*
Y-333249D01*
X383208D01*
Y-333216D01*
X383175D01*
Y-333184D01*
X383143D01*
Y-333152D01*
Y-333120D01*
X383111D01*
Y-333087D01*
X383079D01*
Y-333055D01*
X383046D01*
Y-333023D01*
X383014D01*
Y-332991D01*
X382982D01*
Y-332958D01*
Y-332926D01*
X382950D01*
Y-332894D01*
X382917D01*
Y-332861D01*
X382885D01*
Y-332829D01*
X382853D01*
Y-332797D01*
X382821D01*
Y-332765D01*
Y-332732D01*
X382788D01*
Y-332700D01*
X382756D01*
Y-332668D01*
X382724D01*
Y-332636D01*
X382692D01*
Y-332603D01*
X382659D01*
Y-332571D01*
X382627D01*
Y-332539D01*
X382595D01*
Y-332507D01*
X382562D01*
Y-332474D01*
Y-332442D01*
X382530D01*
Y-332410D01*
X382498D01*
Y-332378D01*
X382466D01*
Y-332345D01*
X382433D01*
Y-332313D01*
X382401D01*
Y-332281D01*
X382369D01*
Y-332248D01*
X382337D01*
Y-332216D01*
X382304D01*
Y-332184D01*
X382272D01*
Y-332152D01*
X382240D01*
Y-332119D01*
X382207D01*
Y-332087D01*
X382175D01*
Y-332055D01*
X382143D01*
Y-332023D01*
X382111D01*
Y-331990D01*
X382079D01*
Y-331958D01*
X382046D01*
Y-331926D01*
X382014D01*
Y-331894D01*
X381982D01*
Y-331861D01*
X381949D01*
Y-331829D01*
X381917D01*
Y-331797D01*
X381885D01*
Y-331765D01*
X381820D01*
Y-331732D01*
X381788D01*
Y-331700D01*
X381756D01*
Y-331668D01*
X381724D01*
Y-331635D01*
X381691D01*
Y-331603D01*
X381659D01*
Y-331571D01*
X381627D01*
Y-331539D01*
X381595D01*
Y-331506D01*
X381562D01*
Y-331474D01*
X381498D01*
Y-331442D01*
X381466D01*
Y-331410D01*
X381433D01*
Y-331377D01*
X381401D01*
Y-331345D01*
X381369D01*
Y-331313D01*
X381304D01*
Y-331281D01*
X381272D01*
Y-331248D01*
X381240D01*
Y-331216D01*
X381207D01*
Y-331184D01*
X381175D01*
Y-331152D01*
X381111D01*
Y-331119D01*
X381078D01*
Y-331087D01*
X381046D01*
Y-331055D01*
X380982D01*
Y-331023D01*
X380949D01*
Y-330990D01*
X380917D01*
Y-330958D01*
X380885D01*
Y-330926D01*
X380820D01*
Y-330893D01*
X380788D01*
Y-330861D01*
X380724D01*
Y-330829D01*
X380691D01*
Y-330797D01*
X380659D01*
Y-330764D01*
X380594D01*
Y-330732D01*
X380562D01*
Y-330700D01*
X380530D01*
Y-330668D01*
X380465D01*
Y-330635D01*
X380433D01*
Y-330603D01*
X380369D01*
Y-330571D01*
X380336D01*
Y-330539D01*
X380272D01*
Y-330506D01*
X380240D01*
Y-330474D01*
X380175D01*
Y-330442D01*
X380143D01*
Y-330410D01*
X380078D01*
Y-330377D01*
X380014D01*
Y-330345D01*
X379981D01*
Y-330313D01*
X379917D01*
Y-330280D01*
X379885D01*
Y-330248D01*
X379820D01*
Y-330216D01*
X379756D01*
Y-330184D01*
X379723D01*
Y-330152D01*
X379659D01*
Y-330119D01*
X379594D01*
Y-330087D01*
X379530D01*
Y-330055D01*
X379498D01*
Y-330022D01*
X379433D01*
Y-329990D01*
X379368D01*
Y-329958D01*
X379304D01*
Y-329926D01*
X379240D01*
Y-329893D01*
X379207D01*
Y-329861D01*
X379110D01*
Y-329829D01*
X379078D01*
Y-329797D01*
X379014D01*
Y-329764D01*
X378917D01*
Y-329732D01*
X378852D01*
Y-329700D01*
X378820D01*
Y-329667D01*
X378755D01*
Y-329635D01*
X378659D01*
Y-329603D01*
X378594D01*
Y-329571D01*
X378530D01*
Y-329538D01*
X378465D01*
Y-329506D01*
X378401D01*
Y-329474D01*
X378304D01*
Y-329442D01*
X378239D01*
Y-329410D01*
X378175D01*
Y-329377D01*
X378078D01*
Y-329345D01*
X378013D01*
Y-329313D01*
X377917D01*
Y-329280D01*
X377820D01*
Y-329248D01*
X377755D01*
Y-329216D01*
X377659D01*
Y-329184D01*
X377562D01*
Y-329151D01*
X377465D01*
Y-329119D01*
X377401D01*
Y-329087D01*
X377304D01*
Y-329055D01*
X377207D01*
Y-329022D01*
X377078D01*
Y-328990D01*
X376981D01*
Y-328958D01*
X376884D01*
Y-328925D01*
X376755D01*
Y-328893D01*
X376659D01*
Y-328861D01*
X376530D01*
Y-328829D01*
X376400D01*
Y-328797D01*
X376271D01*
Y-328764D01*
X376142D01*
Y-328732D01*
X375981D01*
Y-328700D01*
X375820D01*
Y-328667D01*
X375658D01*
Y-328635D01*
X375465D01*
Y-328603D01*
X375271D01*
Y-328571D01*
X375013D01*
Y-328538D01*
X374755D01*
Y-328506D01*
X374465D01*
Y-328474D01*
X373981D01*
Y-328442D01*
D02*
G37*
G36*
X369464Y-341249D02*
X369400D01*
Y-341282D01*
X369367D01*
Y-341249D01*
X365496D01*
Y-341282D01*
X365399D01*
Y-341314D01*
X365302D01*
Y-341346D01*
X365238D01*
Y-341379D01*
X365206D01*
Y-341411D01*
X365173D01*
Y-341443D01*
X365141D01*
Y-341475D01*
X365109D01*
Y-341508D01*
X365076D01*
Y-341540D01*
X365044D01*
Y-341572D01*
X365012D01*
Y-341604D01*
X364980D01*
Y-341637D01*
X364948D01*
Y-341669D01*
X364915D01*
Y-341701D01*
X364883D01*
Y-341734D01*
X364851D01*
Y-341766D01*
X364818D01*
Y-341798D01*
X364786D01*
Y-341830D01*
X364754D01*
Y-341863D01*
X364722D01*
Y-341895D01*
X364689D01*
Y-341927D01*
X364657D01*
Y-341959D01*
X364625D01*
Y-341992D01*
X364593D01*
Y-342024D01*
X364560D01*
Y-342056D01*
X364528D01*
Y-342088D01*
X364496D01*
Y-342121D01*
X364464D01*
Y-342153D01*
X364431D01*
Y-342185D01*
X364399D01*
Y-342217D01*
X364367D01*
Y-342250D01*
X364335D01*
Y-342282D01*
Y-342314D01*
X364302D01*
Y-342346D01*
Y-342379D01*
Y-342411D01*
Y-342443D01*
X364270D01*
Y-342476D01*
Y-342508D01*
Y-342540D01*
Y-342572D01*
Y-342604D01*
Y-342637D01*
Y-342669D01*
Y-342701D01*
Y-342734D01*
Y-342766D01*
Y-342798D01*
Y-342830D01*
Y-342863D01*
Y-342895D01*
Y-342927D01*
Y-342959D01*
Y-342992D01*
Y-343024D01*
Y-343056D01*
Y-343089D01*
Y-343121D01*
Y-343153D01*
Y-343185D01*
Y-343217D01*
Y-343250D01*
Y-343282D01*
Y-343314D01*
Y-343347D01*
Y-343379D01*
Y-343411D01*
Y-343443D01*
Y-343476D01*
Y-343508D01*
Y-343540D01*
Y-343572D01*
Y-343605D01*
Y-343637D01*
Y-343669D01*
Y-343701D01*
Y-343734D01*
Y-343766D01*
Y-343798D01*
Y-343830D01*
Y-343863D01*
Y-343895D01*
Y-343927D01*
Y-343959D01*
Y-343992D01*
Y-344024D01*
Y-344056D01*
Y-344089D01*
Y-344121D01*
Y-344153D01*
Y-344185D01*
Y-344218D01*
Y-344250D01*
Y-344282D01*
Y-344314D01*
Y-344347D01*
Y-344379D01*
Y-344411D01*
Y-344443D01*
Y-344476D01*
Y-344508D01*
Y-344540D01*
Y-344572D01*
Y-344605D01*
Y-344637D01*
Y-344669D01*
Y-344702D01*
Y-344734D01*
Y-344766D01*
Y-344798D01*
Y-344831D01*
Y-344863D01*
Y-344895D01*
Y-344927D01*
Y-344960D01*
Y-344992D01*
Y-345024D01*
Y-345056D01*
Y-345089D01*
Y-345121D01*
Y-345153D01*
Y-345185D01*
Y-345218D01*
Y-345250D01*
Y-345282D01*
Y-345315D01*
Y-345347D01*
Y-345379D01*
Y-345411D01*
Y-345444D01*
Y-345476D01*
Y-345508D01*
Y-345540D01*
Y-345573D01*
Y-345605D01*
Y-345637D01*
Y-345669D01*
Y-345702D01*
Y-345734D01*
Y-345766D01*
Y-345798D01*
Y-345831D01*
Y-345863D01*
Y-345895D01*
Y-345928D01*
Y-345960D01*
Y-345992D01*
Y-346024D01*
Y-346057D01*
Y-346089D01*
Y-346121D01*
Y-346153D01*
Y-346186D01*
Y-346218D01*
Y-346250D01*
Y-346282D01*
Y-346315D01*
Y-346347D01*
Y-346379D01*
Y-346411D01*
Y-346444D01*
Y-346476D01*
Y-346508D01*
Y-346540D01*
Y-346573D01*
Y-346605D01*
Y-346637D01*
Y-346670D01*
Y-346702D01*
Y-346734D01*
Y-346766D01*
Y-346799D01*
Y-346831D01*
Y-346863D01*
Y-346895D01*
Y-346928D01*
Y-346960D01*
Y-346992D01*
Y-347024D01*
Y-347057D01*
Y-347089D01*
Y-347121D01*
X364302D01*
Y-347153D01*
Y-347186D01*
Y-347218D01*
X364335D01*
Y-347250D01*
Y-347283D01*
X364367D01*
Y-347315D01*
X364399D01*
Y-347347D01*
X364431D01*
Y-347379D01*
X364464D01*
Y-347411D01*
X364496D01*
Y-347444D01*
X364528D01*
Y-347476D01*
X364560D01*
Y-347508D01*
X364593D01*
Y-347541D01*
X364625D01*
Y-347573D01*
X364657D01*
Y-347605D01*
X364689D01*
Y-347637D01*
X364722D01*
Y-347670D01*
X364754D01*
Y-347702D01*
X364786D01*
Y-347734D01*
X364818D01*
Y-347766D01*
X364851D01*
Y-347799D01*
X364883D01*
Y-347831D01*
X364915D01*
Y-347863D01*
X364948D01*
Y-347896D01*
X364980D01*
Y-347928D01*
X365012D01*
Y-347960D01*
X365044D01*
Y-347992D01*
X365076D01*
Y-348025D01*
X365109D01*
Y-348057D01*
X365141D01*
Y-348089D01*
X365173D01*
Y-348121D01*
X365206D01*
Y-348154D01*
X365238D01*
Y-348186D01*
X365270D01*
Y-348218D01*
X365335D01*
Y-348250D01*
X365431D01*
Y-348283D01*
X369529D01*
Y-348250D01*
X369561D01*
Y-348218D01*
X369593D01*
Y-348186D01*
X369625D01*
Y-348154D01*
Y-348121D01*
Y-348089D01*
Y-348057D01*
Y-348025D01*
Y-347992D01*
Y-347960D01*
Y-347928D01*
Y-347896D01*
Y-347863D01*
Y-347831D01*
Y-347799D01*
Y-347766D01*
Y-347734D01*
Y-347702D01*
Y-347670D01*
Y-347637D01*
Y-347605D01*
Y-347573D01*
Y-347541D01*
Y-347508D01*
Y-347476D01*
Y-347444D01*
Y-347411D01*
Y-347379D01*
Y-347347D01*
Y-347315D01*
Y-347283D01*
Y-347250D01*
Y-347218D01*
Y-347186D01*
Y-347153D01*
Y-347121D01*
Y-347089D01*
Y-347057D01*
Y-347024D01*
Y-346992D01*
Y-346960D01*
Y-346928D01*
Y-346895D01*
Y-346863D01*
Y-346831D01*
Y-346799D01*
Y-346766D01*
Y-346734D01*
Y-346702D01*
Y-346670D01*
X369593D01*
Y-346637D01*
X369561D01*
Y-346605D01*
X369496D01*
Y-346573D01*
X366141D01*
Y-346540D01*
X366077D01*
Y-346508D01*
Y-346476D01*
X366044D01*
Y-346444D01*
Y-346411D01*
Y-346379D01*
Y-346347D01*
Y-346315D01*
Y-346282D01*
Y-346250D01*
Y-346218D01*
Y-346186D01*
Y-346153D01*
Y-346121D01*
Y-346089D01*
Y-346057D01*
Y-346024D01*
Y-345992D01*
Y-345960D01*
Y-345928D01*
Y-345895D01*
Y-345863D01*
Y-345831D01*
Y-345798D01*
Y-345766D01*
Y-345734D01*
Y-345702D01*
Y-345669D01*
Y-345637D01*
Y-345605D01*
Y-345573D01*
Y-345540D01*
Y-345508D01*
Y-345476D01*
Y-345444D01*
Y-345411D01*
Y-345379D01*
Y-345347D01*
Y-345315D01*
Y-345282D01*
Y-345250D01*
Y-345218D01*
Y-345185D01*
Y-345153D01*
Y-345121D01*
Y-345089D01*
Y-345056D01*
Y-345024D01*
Y-344992D01*
Y-344960D01*
Y-344927D01*
Y-344895D01*
Y-344863D01*
Y-344831D01*
Y-344798D01*
Y-344766D01*
Y-344734D01*
Y-344702D01*
Y-344669D01*
Y-344637D01*
Y-344605D01*
Y-344572D01*
Y-344540D01*
Y-344508D01*
Y-344476D01*
Y-344443D01*
Y-344411D01*
Y-344379D01*
Y-344347D01*
Y-344314D01*
Y-344282D01*
Y-344250D01*
Y-344218D01*
Y-344185D01*
Y-344153D01*
Y-344121D01*
Y-344089D01*
Y-344056D01*
Y-344024D01*
Y-343992D01*
Y-343959D01*
Y-343927D01*
Y-343895D01*
Y-343863D01*
Y-343830D01*
Y-343798D01*
Y-343766D01*
Y-343734D01*
Y-343701D01*
Y-343669D01*
Y-343637D01*
Y-343605D01*
Y-343572D01*
Y-343540D01*
Y-343508D01*
Y-343476D01*
Y-343443D01*
Y-343411D01*
Y-343379D01*
Y-343347D01*
Y-343314D01*
Y-343282D01*
Y-343250D01*
Y-343217D01*
Y-343185D01*
Y-343153D01*
Y-343121D01*
Y-343089D01*
Y-343056D01*
X366077D01*
Y-343024D01*
X366109D01*
Y-342992D01*
X369303D01*
Y-342959D01*
X369335D01*
Y-342992D01*
X369464D01*
Y-342959D01*
X369561D01*
Y-342927D01*
X369593D01*
Y-342895D01*
X369625D01*
Y-342863D01*
Y-342830D01*
Y-342798D01*
Y-342766D01*
Y-342734D01*
Y-342701D01*
Y-342669D01*
Y-342637D01*
Y-342604D01*
Y-342572D01*
Y-342540D01*
Y-342508D01*
Y-342476D01*
Y-342443D01*
Y-342411D01*
Y-342379D01*
Y-342346D01*
Y-342314D01*
Y-342282D01*
Y-342250D01*
Y-342217D01*
Y-342185D01*
Y-342153D01*
Y-342121D01*
Y-342088D01*
Y-342056D01*
Y-342024D01*
Y-341992D01*
Y-341959D01*
Y-341927D01*
Y-341895D01*
Y-341863D01*
Y-341830D01*
Y-341798D01*
Y-341766D01*
Y-341734D01*
Y-341701D01*
Y-341669D01*
Y-341637D01*
Y-341604D01*
Y-341572D01*
Y-341540D01*
Y-341508D01*
Y-341475D01*
Y-341443D01*
Y-341411D01*
Y-341379D01*
Y-341346D01*
X369593D01*
Y-341314D01*
X369561D01*
Y-341282D01*
X369464D01*
Y-341249D01*
D02*
G37*
G36*
X375110D02*
X374658D01*
Y-341282D01*
X374626D01*
Y-341314D01*
X374594D01*
Y-341346D01*
X374562D01*
Y-341379D01*
X374529D01*
Y-341411D01*
X374497D01*
Y-341443D01*
X374465D01*
Y-341475D01*
X374432D01*
Y-341508D01*
X374400D01*
Y-341540D01*
X374368D01*
Y-341572D01*
X374336D01*
Y-341604D01*
X374303D01*
Y-341637D01*
X374271D01*
Y-341669D01*
X374239D01*
Y-341701D01*
X374207D01*
Y-341734D01*
X374174D01*
Y-341766D01*
X374142D01*
Y-341798D01*
X374110D01*
Y-341830D01*
X374078D01*
Y-341863D01*
X374045D01*
Y-341895D01*
X374013D01*
Y-341927D01*
X373981D01*
Y-341959D01*
X373949D01*
Y-341992D01*
X373916D01*
Y-342024D01*
X373884D01*
Y-342056D01*
X373852D01*
Y-342088D01*
X373819D01*
Y-342121D01*
X373787D01*
Y-342153D01*
X373755D01*
Y-342185D01*
X373723D01*
Y-342217D01*
X373690D01*
Y-342250D01*
X373658D01*
Y-342282D01*
X373626D01*
Y-342314D01*
X373594D01*
Y-342346D01*
X373561D01*
Y-342379D01*
X373529D01*
Y-342411D01*
X373497D01*
Y-342443D01*
X373465D01*
Y-342476D01*
X373432D01*
Y-342508D01*
X373400D01*
Y-342540D01*
X373368D01*
Y-342572D01*
X373336D01*
Y-342604D01*
X373303D01*
Y-342637D01*
X373271D01*
Y-342669D01*
X373239D01*
Y-342701D01*
X373206D01*
Y-342734D01*
X373174D01*
Y-342766D01*
X373142D01*
Y-342798D01*
X373110D01*
Y-342830D01*
X374562D01*
Y-342863D01*
Y-342895D01*
Y-342927D01*
Y-342959D01*
Y-342992D01*
Y-343024D01*
Y-343056D01*
Y-343089D01*
Y-343121D01*
Y-343153D01*
Y-343185D01*
Y-343217D01*
Y-343250D01*
Y-343282D01*
Y-343314D01*
Y-343347D01*
Y-343379D01*
Y-343411D01*
Y-343443D01*
Y-343476D01*
Y-343508D01*
Y-343540D01*
Y-343572D01*
Y-343605D01*
Y-343637D01*
Y-343669D01*
Y-343701D01*
Y-343734D01*
Y-343766D01*
Y-343798D01*
Y-343830D01*
Y-343863D01*
Y-343895D01*
Y-343927D01*
Y-343959D01*
Y-343992D01*
Y-344024D01*
Y-344056D01*
Y-344089D01*
Y-344121D01*
Y-344153D01*
Y-344185D01*
Y-344218D01*
Y-344250D01*
Y-344282D01*
Y-344314D01*
Y-344347D01*
Y-344379D01*
Y-344411D01*
Y-344443D01*
Y-344476D01*
Y-344508D01*
Y-344540D01*
Y-344572D01*
Y-344605D01*
X372206D01*
Y-344572D01*
Y-344540D01*
Y-344508D01*
Y-344476D01*
Y-344443D01*
Y-344411D01*
Y-344379D01*
Y-344347D01*
Y-344314D01*
Y-344282D01*
Y-344250D01*
Y-344218D01*
Y-344185D01*
Y-344153D01*
Y-344121D01*
Y-344089D01*
Y-344056D01*
Y-344024D01*
Y-343992D01*
Y-343959D01*
Y-343927D01*
Y-343895D01*
X372174D01*
Y-343927D01*
X372142D01*
Y-343959D01*
X372110D01*
Y-343992D01*
X372077D01*
Y-344024D01*
X372045D01*
Y-344056D01*
X372013D01*
Y-344089D01*
X371981D01*
Y-344121D01*
X371948D01*
Y-344153D01*
X371916D01*
Y-344185D01*
X371884D01*
Y-344218D01*
X371851D01*
Y-344250D01*
X371819D01*
Y-344282D01*
X371787D01*
Y-344314D01*
X371755D01*
Y-344347D01*
X371723D01*
Y-344379D01*
X371690D01*
Y-344411D01*
X371658D01*
Y-344443D01*
X371626D01*
Y-344476D01*
X371593D01*
Y-344508D01*
X371561D01*
Y-344540D01*
X371529D01*
Y-344572D01*
X371497D01*
Y-344605D01*
X371464D01*
Y-344637D01*
X371432D01*
Y-344669D01*
X371400D01*
Y-344702D01*
X371368D01*
Y-344734D01*
X371335D01*
Y-344766D01*
X371303D01*
Y-344798D01*
X371271D01*
Y-344831D01*
X371238D01*
Y-344863D01*
X371206D01*
Y-344895D01*
X371174D01*
Y-344927D01*
X371142D01*
Y-344960D01*
X371110D01*
Y-344992D01*
X371077D01*
Y-345024D01*
X371045D01*
Y-345056D01*
X371013D01*
Y-345089D01*
X370981D01*
Y-345121D01*
X370948D01*
Y-345153D01*
X370916D01*
Y-345185D01*
X370884D01*
Y-345218D01*
X370851D01*
Y-345250D01*
X370819D01*
Y-345282D01*
X370787D01*
Y-345315D01*
X370755D01*
Y-345347D01*
X370722D01*
Y-345379D01*
X370690D01*
Y-345411D01*
X370626D01*
Y-345444D01*
X370593D01*
Y-345476D01*
X370561D01*
Y-345508D01*
X370529D01*
Y-345540D01*
X370497D01*
Y-345573D01*
X370464D01*
Y-345605D01*
X370432D01*
Y-345637D01*
Y-345669D01*
Y-345702D01*
Y-345734D01*
Y-345766D01*
Y-345798D01*
Y-345831D01*
Y-345863D01*
Y-345895D01*
Y-345928D01*
Y-345960D01*
Y-345992D01*
Y-346024D01*
Y-346057D01*
Y-346089D01*
Y-346121D01*
Y-346153D01*
Y-346186D01*
Y-346218D01*
Y-346250D01*
Y-346282D01*
Y-346315D01*
Y-346347D01*
Y-346379D01*
Y-346411D01*
Y-346444D01*
Y-346476D01*
Y-346508D01*
Y-346540D01*
Y-346573D01*
Y-346605D01*
Y-346637D01*
Y-346670D01*
Y-346702D01*
Y-346734D01*
Y-346766D01*
Y-346799D01*
Y-346831D01*
Y-346863D01*
Y-346895D01*
Y-346928D01*
Y-346960D01*
Y-346992D01*
Y-347024D01*
Y-347057D01*
Y-347089D01*
Y-347121D01*
Y-347153D01*
Y-347186D01*
Y-347218D01*
Y-347250D01*
Y-347283D01*
Y-347315D01*
Y-347347D01*
Y-347379D01*
Y-347411D01*
Y-347444D01*
Y-347476D01*
Y-347508D01*
Y-347541D01*
Y-347573D01*
Y-347605D01*
Y-347637D01*
Y-347670D01*
Y-347702D01*
Y-347734D01*
Y-347766D01*
Y-347799D01*
Y-347831D01*
Y-347863D01*
Y-347896D01*
Y-347928D01*
Y-347960D01*
Y-347992D01*
Y-348025D01*
Y-348057D01*
Y-348089D01*
Y-348121D01*
Y-348154D01*
Y-348186D01*
X370464D01*
Y-348218D01*
X370497D01*
Y-348250D01*
X370561D01*
Y-348283D01*
X372077D01*
Y-348250D01*
X372142D01*
Y-348218D01*
X372174D01*
Y-348186D01*
Y-348154D01*
X372206D01*
Y-348121D01*
Y-348089D01*
Y-348057D01*
Y-348025D01*
Y-347992D01*
Y-347960D01*
Y-347928D01*
Y-347896D01*
Y-347863D01*
Y-347831D01*
Y-347799D01*
Y-347766D01*
Y-347734D01*
Y-347702D01*
Y-347670D01*
Y-347637D01*
Y-347605D01*
Y-347573D01*
Y-347541D01*
Y-347508D01*
Y-347476D01*
Y-347444D01*
Y-347411D01*
Y-347379D01*
Y-347347D01*
Y-347315D01*
Y-347283D01*
Y-347250D01*
Y-347218D01*
Y-347186D01*
Y-347153D01*
Y-347121D01*
Y-347089D01*
Y-347057D01*
Y-347024D01*
Y-346992D01*
Y-346960D01*
Y-346928D01*
Y-346895D01*
Y-346863D01*
Y-346831D01*
Y-346799D01*
Y-346766D01*
Y-346734D01*
Y-346702D01*
Y-346670D01*
Y-346637D01*
Y-346605D01*
Y-346573D01*
Y-346540D01*
Y-346508D01*
Y-346476D01*
Y-346444D01*
Y-346411D01*
Y-346379D01*
Y-346347D01*
Y-346315D01*
Y-346282D01*
Y-346250D01*
Y-346218D01*
X372239D01*
Y-346186D01*
Y-346153D01*
X372303D01*
Y-346121D01*
X374465D01*
Y-346153D01*
X374529D01*
Y-346186D01*
Y-346218D01*
X374562D01*
Y-346250D01*
Y-346282D01*
Y-346315D01*
Y-346347D01*
Y-346379D01*
Y-346411D01*
Y-346444D01*
Y-346476D01*
Y-346508D01*
Y-346540D01*
Y-346573D01*
Y-346605D01*
Y-346637D01*
Y-346670D01*
Y-346702D01*
Y-346734D01*
Y-346766D01*
Y-346799D01*
Y-346831D01*
Y-346863D01*
Y-346895D01*
Y-346928D01*
Y-346960D01*
Y-346992D01*
Y-347024D01*
Y-347057D01*
Y-347089D01*
Y-347121D01*
Y-347153D01*
Y-347186D01*
Y-347218D01*
Y-347250D01*
Y-347283D01*
Y-347315D01*
Y-347347D01*
Y-347379D01*
Y-347411D01*
Y-347444D01*
Y-347476D01*
Y-347508D01*
Y-347541D01*
Y-347573D01*
Y-347605D01*
Y-347637D01*
Y-347670D01*
Y-347702D01*
Y-347734D01*
Y-347766D01*
Y-347799D01*
Y-347831D01*
Y-347863D01*
Y-347896D01*
Y-347928D01*
Y-347960D01*
Y-347992D01*
Y-348025D01*
Y-348057D01*
Y-348089D01*
Y-348121D01*
Y-348154D01*
Y-348186D01*
X374594D01*
Y-348218D01*
X374626D01*
Y-348250D01*
X374691D01*
Y-348283D01*
X376207D01*
Y-348250D01*
X376271D01*
Y-348218D01*
X376304D01*
Y-348186D01*
Y-348154D01*
X376336D01*
Y-348121D01*
Y-348089D01*
Y-348057D01*
Y-348025D01*
Y-347992D01*
Y-347960D01*
Y-347928D01*
Y-347896D01*
Y-347863D01*
Y-347831D01*
Y-347799D01*
Y-347766D01*
Y-347734D01*
Y-347702D01*
Y-347670D01*
Y-347637D01*
Y-347605D01*
Y-347573D01*
Y-347541D01*
Y-347508D01*
Y-347476D01*
Y-347444D01*
Y-347411D01*
Y-347379D01*
Y-347347D01*
Y-347315D01*
Y-347283D01*
Y-347250D01*
Y-347218D01*
Y-347186D01*
Y-347153D01*
Y-347121D01*
Y-347089D01*
Y-347057D01*
Y-347024D01*
Y-346992D01*
Y-346960D01*
Y-346928D01*
Y-346895D01*
Y-346863D01*
Y-346831D01*
Y-346799D01*
Y-346766D01*
Y-346734D01*
Y-346702D01*
Y-346670D01*
Y-346637D01*
Y-346605D01*
Y-346573D01*
Y-346540D01*
Y-346508D01*
Y-346476D01*
Y-346444D01*
Y-346411D01*
Y-346379D01*
Y-346347D01*
Y-346315D01*
Y-346282D01*
Y-346250D01*
Y-346218D01*
Y-346186D01*
Y-346153D01*
Y-346121D01*
Y-346089D01*
Y-346057D01*
Y-346024D01*
Y-345992D01*
Y-345960D01*
Y-345928D01*
Y-345895D01*
Y-345863D01*
Y-345831D01*
Y-345798D01*
Y-345766D01*
Y-345734D01*
Y-345702D01*
Y-345669D01*
Y-345637D01*
Y-345605D01*
Y-345573D01*
Y-345540D01*
Y-345508D01*
Y-345476D01*
Y-345444D01*
Y-345411D01*
Y-345379D01*
Y-345347D01*
Y-345315D01*
Y-345282D01*
Y-345250D01*
Y-345218D01*
Y-345185D01*
Y-345153D01*
Y-345121D01*
Y-345089D01*
Y-345056D01*
Y-345024D01*
Y-344992D01*
Y-344960D01*
Y-344927D01*
Y-344895D01*
Y-344863D01*
Y-344831D01*
Y-344798D01*
Y-344766D01*
Y-344734D01*
Y-344702D01*
Y-344669D01*
Y-344637D01*
Y-344605D01*
Y-344572D01*
Y-344540D01*
Y-344508D01*
Y-344476D01*
Y-344443D01*
Y-344411D01*
Y-344379D01*
Y-344347D01*
Y-344314D01*
Y-344282D01*
Y-344250D01*
Y-344218D01*
Y-344185D01*
Y-344153D01*
Y-344121D01*
Y-344089D01*
Y-344056D01*
Y-344024D01*
Y-343992D01*
Y-343959D01*
Y-343927D01*
Y-343895D01*
Y-343863D01*
Y-343830D01*
Y-343798D01*
Y-343766D01*
Y-343734D01*
Y-343701D01*
Y-343669D01*
Y-343637D01*
Y-343605D01*
Y-343572D01*
Y-343540D01*
Y-343508D01*
Y-343476D01*
Y-343443D01*
Y-343411D01*
Y-343379D01*
Y-343347D01*
Y-343314D01*
Y-343282D01*
Y-343250D01*
Y-343217D01*
Y-343185D01*
Y-343153D01*
Y-343121D01*
Y-343089D01*
Y-343056D01*
Y-343024D01*
Y-342992D01*
Y-342959D01*
Y-342927D01*
Y-342895D01*
Y-342863D01*
Y-342830D01*
Y-342798D01*
Y-342766D01*
Y-342734D01*
Y-342701D01*
Y-342669D01*
Y-342637D01*
Y-342604D01*
Y-342572D01*
Y-342540D01*
Y-342508D01*
Y-342476D01*
X376304D01*
Y-342443D01*
Y-342411D01*
Y-342379D01*
Y-342346D01*
X376271D01*
Y-342314D01*
Y-342282D01*
Y-342250D01*
X376239D01*
Y-342217D01*
X376207D01*
Y-342185D01*
X376175D01*
Y-342153D01*
X376142D01*
Y-342121D01*
X376110D01*
Y-342088D01*
X376078D01*
Y-342056D01*
X376046D01*
Y-342024D01*
X376013D01*
Y-341992D01*
X375981D01*
Y-341959D01*
X375949D01*
Y-341927D01*
X375917D01*
Y-341895D01*
X375884D01*
Y-341863D01*
X375852D01*
Y-341830D01*
X375820D01*
Y-341798D01*
X375787D01*
Y-341766D01*
X375755D01*
Y-341734D01*
X375723D01*
Y-341701D01*
X375691D01*
Y-341669D01*
X375658D01*
Y-341637D01*
X375626D01*
Y-341604D01*
X375594D01*
Y-341572D01*
X375562D01*
Y-341540D01*
X375529D01*
Y-341508D01*
X375497D01*
Y-341475D01*
X375465D01*
Y-341443D01*
X375433D01*
Y-341411D01*
X375400D01*
Y-341379D01*
X375368D01*
Y-341346D01*
X375304D01*
Y-341314D01*
X375239D01*
Y-341282D01*
X375110D01*
Y-341249D01*
D02*
G37*
G36*
X372884Y-329797D02*
X372303D01*
Y-329829D01*
Y-329861D01*
Y-329893D01*
Y-329926D01*
Y-329958D01*
Y-329990D01*
Y-330022D01*
Y-330055D01*
Y-330087D01*
Y-330119D01*
Y-330152D01*
Y-330184D01*
Y-330216D01*
Y-330248D01*
Y-330280D01*
Y-330313D01*
Y-330345D01*
Y-330377D01*
Y-330410D01*
Y-330442D01*
Y-330474D01*
Y-330506D01*
Y-330539D01*
Y-330571D01*
Y-330603D01*
Y-330635D01*
Y-330668D01*
Y-330700D01*
Y-330732D01*
Y-330764D01*
Y-330797D01*
Y-330829D01*
Y-330861D01*
Y-330893D01*
Y-330926D01*
Y-330958D01*
Y-330990D01*
Y-331023D01*
Y-331055D01*
Y-331087D01*
Y-331119D01*
Y-331152D01*
Y-331184D01*
Y-331216D01*
Y-331248D01*
Y-331281D01*
Y-331313D01*
Y-331345D01*
Y-331377D01*
Y-331410D01*
Y-331442D01*
Y-331474D01*
Y-331506D01*
Y-331539D01*
Y-331571D01*
Y-331603D01*
Y-331635D01*
Y-331668D01*
Y-331700D01*
Y-331732D01*
Y-331765D01*
Y-331797D01*
Y-331829D01*
Y-331861D01*
Y-331894D01*
Y-331926D01*
Y-331958D01*
Y-331990D01*
Y-332023D01*
Y-332055D01*
Y-332087D01*
Y-332119D01*
Y-332152D01*
Y-332184D01*
Y-332216D01*
Y-332248D01*
Y-332281D01*
Y-332313D01*
Y-332345D01*
Y-332378D01*
Y-332410D01*
Y-332442D01*
Y-332474D01*
Y-332507D01*
Y-332539D01*
Y-332571D01*
Y-332603D01*
Y-332636D01*
Y-332668D01*
Y-332700D01*
Y-332732D01*
Y-332765D01*
Y-332797D01*
Y-332829D01*
Y-332861D01*
Y-332894D01*
Y-332926D01*
Y-332958D01*
Y-332991D01*
Y-333023D01*
Y-333055D01*
Y-333087D01*
Y-333120D01*
Y-333152D01*
Y-333184D01*
Y-333216D01*
Y-333249D01*
Y-333281D01*
Y-333313D01*
Y-333345D01*
Y-333378D01*
Y-333410D01*
Y-333442D01*
Y-333474D01*
Y-333507D01*
Y-333539D01*
Y-333571D01*
Y-333604D01*
Y-333636D01*
Y-333668D01*
Y-333700D01*
Y-333733D01*
Y-333765D01*
Y-333797D01*
Y-333829D01*
Y-333862D01*
Y-333894D01*
Y-333926D01*
Y-333958D01*
Y-333991D01*
Y-334023D01*
Y-334055D01*
Y-334087D01*
Y-334120D01*
Y-334152D01*
Y-334184D01*
Y-334216D01*
Y-334249D01*
Y-334281D01*
Y-334313D01*
Y-334346D01*
Y-334378D01*
Y-334410D01*
Y-334442D01*
Y-334474D01*
Y-334507D01*
Y-334539D01*
Y-334571D01*
Y-334604D01*
Y-334636D01*
Y-334668D01*
Y-334700D01*
Y-334733D01*
Y-334765D01*
Y-334797D01*
Y-334829D01*
Y-334862D01*
Y-334894D01*
Y-334926D01*
Y-334959D01*
Y-334991D01*
Y-335023D01*
Y-335055D01*
Y-335087D01*
Y-335120D01*
Y-335152D01*
Y-335184D01*
Y-335217D01*
Y-335249D01*
Y-335281D01*
Y-335313D01*
Y-335346D01*
Y-335378D01*
Y-335410D01*
Y-335442D01*
Y-335475D01*
Y-335507D01*
Y-335539D01*
Y-335572D01*
Y-335604D01*
Y-335636D01*
Y-335668D01*
Y-335700D01*
Y-335733D01*
Y-335765D01*
Y-335797D01*
Y-335830D01*
Y-335862D01*
Y-335894D01*
Y-335926D01*
Y-335959D01*
Y-335991D01*
Y-336023D01*
Y-336055D01*
Y-336088D01*
Y-336120D01*
Y-336152D01*
Y-336184D01*
Y-336217D01*
Y-336249D01*
Y-336281D01*
Y-336314D01*
Y-336346D01*
Y-336378D01*
Y-336410D01*
Y-336442D01*
Y-336475D01*
Y-336507D01*
Y-336539D01*
Y-336572D01*
Y-336604D01*
Y-336636D01*
Y-336668D01*
Y-336701D01*
Y-336733D01*
Y-336765D01*
Y-336797D01*
Y-336830D01*
Y-336862D01*
Y-336894D01*
Y-336927D01*
Y-336959D01*
Y-336991D01*
Y-337023D01*
Y-337055D01*
Y-337088D01*
Y-337120D01*
Y-337152D01*
Y-337185D01*
Y-337217D01*
Y-337249D01*
Y-337281D01*
Y-337314D01*
Y-337346D01*
Y-337378D01*
Y-337410D01*
Y-337443D01*
Y-337475D01*
Y-337507D01*
Y-337539D01*
Y-337572D01*
Y-337604D01*
Y-337636D01*
Y-337668D01*
Y-337701D01*
Y-337733D01*
Y-337765D01*
Y-337797D01*
Y-337830D01*
Y-337862D01*
Y-337894D01*
Y-337927D01*
Y-337959D01*
Y-337991D01*
Y-338023D01*
Y-338056D01*
Y-338088D01*
Y-338120D01*
Y-338152D01*
Y-338185D01*
Y-338217D01*
Y-338249D01*
Y-338281D01*
Y-338314D01*
Y-338346D01*
Y-338378D01*
Y-338410D01*
Y-338443D01*
Y-338475D01*
Y-338507D01*
Y-338540D01*
Y-338572D01*
Y-338604D01*
Y-338636D01*
Y-338669D01*
Y-338701D01*
Y-338733D01*
Y-338765D01*
Y-338798D01*
Y-338830D01*
Y-338862D01*
Y-338894D01*
Y-338927D01*
Y-338959D01*
Y-338991D01*
Y-339023D01*
Y-339056D01*
Y-339088D01*
Y-339120D01*
Y-339153D01*
Y-339185D01*
Y-339217D01*
Y-339249D01*
Y-339282D01*
Y-339314D01*
Y-339346D01*
Y-339378D01*
Y-339411D01*
Y-339443D01*
Y-339475D01*
Y-339507D01*
Y-339540D01*
Y-339572D01*
Y-339604D01*
Y-339636D01*
Y-339669D01*
Y-339701D01*
Y-339733D01*
Y-339766D01*
Y-339798D01*
Y-339830D01*
Y-339862D01*
Y-339895D01*
Y-339927D01*
Y-339959D01*
Y-339991D01*
Y-340024D01*
Y-340056D01*
Y-340088D01*
Y-340120D01*
Y-340153D01*
Y-340185D01*
Y-340217D01*
Y-340249D01*
Y-340282D01*
Y-340314D01*
Y-340346D01*
Y-340378D01*
Y-340411D01*
Y-340443D01*
Y-340475D01*
X372271D01*
Y-340508D01*
X372239D01*
Y-340540D01*
X372206D01*
Y-340572D01*
X372174D01*
Y-340604D01*
X372142D01*
Y-340637D01*
X372110D01*
Y-340669D01*
X372077D01*
Y-340701D01*
X372045D01*
Y-340733D01*
X372013D01*
Y-340766D01*
X371981D01*
Y-340798D01*
X371948D01*
Y-340830D01*
X371916D01*
Y-340862D01*
X371884D01*
Y-340895D01*
X371851D01*
Y-340927D01*
X371819D01*
Y-340959D01*
X371787D01*
Y-340991D01*
X371755D01*
Y-341024D01*
X371690D01*
Y-341056D01*
X371658D01*
Y-341088D01*
X371626D01*
Y-341121D01*
X371593D01*
Y-341153D01*
X371561D01*
Y-341185D01*
X371529D01*
Y-341217D01*
X371497D01*
Y-341249D01*
X371464D01*
Y-341282D01*
X371432D01*
Y-341314D01*
X371400D01*
Y-341346D01*
X371368D01*
Y-341379D01*
X371335D01*
Y-341411D01*
X371303D01*
Y-341443D01*
X371271D01*
Y-341475D01*
X371238D01*
Y-341508D01*
X371206D01*
Y-341540D01*
X371174D01*
Y-341572D01*
X371142D01*
Y-341604D01*
X371110D01*
Y-341637D01*
X371077D01*
Y-341669D01*
X371045D01*
Y-341701D01*
X371013D01*
Y-341734D01*
X370981D01*
Y-341766D01*
X370948D01*
Y-341798D01*
X370916D01*
Y-341830D01*
X370884D01*
Y-341863D01*
X370851D01*
Y-341895D01*
X370819D01*
Y-341927D01*
X370787D01*
Y-341959D01*
X370755D01*
Y-341992D01*
X370722D01*
Y-342024D01*
X370690D01*
Y-342056D01*
X370658D01*
Y-342088D01*
X370626D01*
Y-342121D01*
X370593D01*
Y-342153D01*
X370561D01*
Y-342185D01*
X370529D01*
Y-342217D01*
X370497D01*
Y-342250D01*
X370464D01*
Y-342282D01*
X370432D01*
Y-342314D01*
X370400D01*
Y-342346D01*
X370368D01*
Y-342379D01*
X370335D01*
Y-342411D01*
X370303D01*
Y-342443D01*
X370271D01*
Y-342476D01*
X370238D01*
Y-342508D01*
X370206D01*
Y-342540D01*
X370174D01*
Y-342572D01*
X370142D01*
Y-342604D01*
X370109D01*
Y-342637D01*
X370077D01*
Y-342669D01*
X370045D01*
Y-342701D01*
X370013D01*
Y-342734D01*
X369980D01*
Y-342766D01*
X369948D01*
Y-342798D01*
X369916D01*
Y-342830D01*
X369884D01*
Y-342863D01*
X369851D01*
Y-342895D01*
X369819D01*
Y-342927D01*
X369787D01*
Y-342959D01*
X369755D01*
Y-342992D01*
X369722D01*
Y-343024D01*
X369690D01*
Y-343056D01*
X369658D01*
Y-343089D01*
X369625D01*
Y-343121D01*
X369593D01*
Y-343153D01*
X369561D01*
Y-343185D01*
X369496D01*
Y-343217D01*
X369464D01*
Y-343250D01*
X369432D01*
Y-343282D01*
X369400D01*
Y-343314D01*
X369367D01*
Y-343347D01*
X369335D01*
Y-343379D01*
X369303D01*
Y-343411D01*
X369271D01*
Y-343443D01*
X369238D01*
Y-343476D01*
X369206D01*
Y-343508D01*
X369174D01*
Y-343540D01*
X369142D01*
Y-343572D01*
X369109D01*
Y-343605D01*
X369077D01*
Y-343637D01*
X369045D01*
Y-343669D01*
X369012D01*
Y-343701D01*
X368980D01*
Y-343734D01*
Y-343766D01*
X368948D01*
Y-343798D01*
X368916D01*
Y-343830D01*
Y-343863D01*
X368883D01*
Y-343895D01*
Y-343927D01*
X368851D01*
Y-343959D01*
Y-343992D01*
Y-344024D01*
Y-344056D01*
Y-344089D01*
Y-344121D01*
Y-344153D01*
Y-344185D01*
Y-344218D01*
Y-344250D01*
Y-344282D01*
Y-344314D01*
Y-344347D01*
Y-344379D01*
Y-344411D01*
Y-344443D01*
Y-344476D01*
Y-344508D01*
Y-344540D01*
Y-344572D01*
Y-344605D01*
Y-344637D01*
Y-344669D01*
Y-344702D01*
Y-344734D01*
Y-344766D01*
Y-344798D01*
Y-344831D01*
Y-344863D01*
Y-344895D01*
Y-344927D01*
Y-344960D01*
Y-344992D01*
Y-345024D01*
Y-345056D01*
Y-345089D01*
Y-345121D01*
Y-345153D01*
Y-345185D01*
Y-345218D01*
Y-345250D01*
Y-345282D01*
Y-345315D01*
Y-345347D01*
Y-345379D01*
X368883D01*
Y-345411D01*
X368916D01*
Y-345444D01*
Y-345476D01*
X368948D01*
Y-345508D01*
X368980D01*
Y-345540D01*
Y-345573D01*
X369012D01*
Y-345605D01*
X369045D01*
Y-345637D01*
X369077D01*
Y-345669D01*
X369109D01*
Y-345702D01*
X369142D01*
Y-345734D01*
X369174D01*
Y-345766D01*
X369206D01*
Y-345798D01*
X369238D01*
Y-345831D01*
X369271D01*
Y-345863D01*
X369335D01*
Y-345831D01*
X369367D01*
Y-345798D01*
X369400D01*
Y-345766D01*
X369432D01*
Y-345734D01*
X369464D01*
Y-345702D01*
X369496D01*
Y-345669D01*
X369529D01*
Y-345637D01*
X369561D01*
Y-345605D01*
X369593D01*
Y-345573D01*
X369625D01*
Y-345540D01*
X369658D01*
Y-345508D01*
X369690D01*
Y-345476D01*
X369722D01*
Y-345444D01*
X369755D01*
Y-345411D01*
X369787D01*
Y-345379D01*
X369819D01*
Y-345347D01*
X369851D01*
Y-345315D01*
X369884D01*
Y-345282D01*
X369916D01*
Y-345250D01*
X369948D01*
Y-345218D01*
X369980D01*
Y-345185D01*
X370013D01*
Y-345153D01*
X370045D01*
Y-345121D01*
X370077D01*
Y-345089D01*
X370142D01*
Y-345056D01*
X370174D01*
Y-345024D01*
X370206D01*
Y-344992D01*
X370238D01*
Y-344960D01*
X370271D01*
Y-344927D01*
X370303D01*
Y-344895D01*
X370335D01*
Y-344863D01*
X370368D01*
Y-344831D01*
X370400D01*
Y-344798D01*
X370432D01*
Y-344766D01*
X370464D01*
Y-344734D01*
X370497D01*
Y-344702D01*
X370529D01*
Y-344669D01*
X370561D01*
Y-344637D01*
X370593D01*
Y-344605D01*
X370626D01*
Y-344572D01*
X370658D01*
Y-344540D01*
X370690D01*
Y-344508D01*
X370722D01*
Y-344476D01*
X370755D01*
Y-344443D01*
X370787D01*
Y-344411D01*
X370819D01*
Y-344379D01*
X370851D01*
Y-344347D01*
X370884D01*
Y-344314D01*
X370916D01*
Y-344282D01*
X370948D01*
Y-344250D01*
X370981D01*
Y-344218D01*
X371013D01*
Y-344185D01*
X371045D01*
Y-344153D01*
X371077D01*
Y-344121D01*
X371110D01*
Y-344089D01*
X371142D01*
Y-344056D01*
X371174D01*
Y-344024D01*
X371206D01*
Y-343992D01*
X371238D01*
Y-343959D01*
X371271D01*
Y-343927D01*
X371303D01*
Y-343895D01*
X371335D01*
Y-343863D01*
X371368D01*
Y-343830D01*
X371400D01*
Y-343798D01*
X371432D01*
Y-343766D01*
X371464D01*
Y-343734D01*
X371497D01*
Y-343701D01*
X371529D01*
Y-343669D01*
X371561D01*
Y-343637D01*
X371593D01*
Y-343605D01*
X371626D01*
Y-343572D01*
X371658D01*
Y-343540D01*
X371690D01*
Y-343508D01*
X371723D01*
Y-343476D01*
X371755D01*
Y-343443D01*
X371787D01*
Y-343411D01*
X371819D01*
Y-343379D01*
X371851D01*
Y-343347D01*
X371884D01*
Y-343314D01*
X371916D01*
Y-343282D01*
X371948D01*
Y-343250D01*
X371981D01*
Y-343217D01*
X372013D01*
Y-343185D01*
X372045D01*
Y-343153D01*
X372077D01*
Y-343121D01*
X372110D01*
Y-343089D01*
X372142D01*
Y-343056D01*
X372174D01*
Y-343024D01*
X372206D01*
Y-342992D01*
X372239D01*
Y-342959D01*
X372271D01*
Y-342927D01*
X372303D01*
Y-342895D01*
X372335D01*
Y-342863D01*
X372368D01*
Y-342830D01*
X372400D01*
Y-342798D01*
X372432D01*
Y-342766D01*
X372464D01*
Y-342734D01*
X372497D01*
Y-342701D01*
X372529D01*
Y-342669D01*
X372561D01*
Y-342637D01*
X372593D01*
Y-342604D01*
X372626D01*
Y-342572D01*
X372658D01*
Y-342540D01*
X372690D01*
Y-342508D01*
X372723D01*
Y-342476D01*
X372755D01*
Y-342443D01*
X372787D01*
Y-342411D01*
X372819D01*
Y-342379D01*
X372884D01*
Y-342346D01*
X372916D01*
Y-342314D01*
X372948D01*
Y-342282D01*
X372981D01*
Y-342250D01*
X373013D01*
Y-342217D01*
X373045D01*
Y-342185D01*
X373078D01*
Y-342153D01*
X373110D01*
Y-342121D01*
X373142D01*
Y-342088D01*
X373174D01*
Y-342056D01*
X373206D01*
Y-342024D01*
X373239D01*
Y-341992D01*
X373271D01*
Y-341959D01*
X373303D01*
Y-341927D01*
X373336D01*
Y-341895D01*
X373368D01*
Y-341863D01*
X373400D01*
Y-341830D01*
X373432D01*
Y-341798D01*
X373465D01*
Y-341766D01*
X373497D01*
Y-341734D01*
X373529D01*
Y-341701D01*
X373561D01*
Y-341669D01*
X373594D01*
Y-341637D01*
X373626D01*
Y-341604D01*
X373658D01*
Y-341572D01*
X373690D01*
Y-341540D01*
X373723D01*
Y-341508D01*
X373755D01*
Y-341475D01*
X373787D01*
Y-341443D01*
X373819D01*
Y-341411D01*
X373852D01*
Y-341379D01*
Y-341346D01*
X373884D01*
Y-341314D01*
X373916D01*
Y-341282D01*
Y-341249D01*
X373949D01*
Y-341217D01*
Y-341185D01*
X373981D01*
Y-341153D01*
Y-341121D01*
X374013D01*
Y-341088D01*
Y-341056D01*
Y-341024D01*
Y-340991D01*
X374045D01*
Y-340959D01*
Y-340927D01*
Y-340895D01*
Y-340862D01*
Y-340830D01*
Y-340798D01*
Y-340766D01*
Y-340733D01*
Y-340701D01*
Y-340669D01*
Y-340637D01*
Y-340604D01*
Y-340572D01*
Y-340540D01*
Y-340508D01*
Y-340475D01*
Y-340443D01*
Y-340411D01*
Y-340378D01*
Y-340346D01*
Y-340314D01*
Y-340282D01*
Y-340249D01*
Y-340217D01*
Y-340185D01*
Y-340153D01*
Y-340120D01*
Y-340088D01*
Y-340056D01*
Y-340024D01*
Y-339991D01*
Y-339959D01*
Y-339927D01*
Y-339895D01*
Y-339862D01*
Y-339830D01*
Y-339798D01*
Y-339766D01*
Y-339733D01*
Y-339701D01*
Y-339669D01*
Y-339636D01*
Y-339604D01*
Y-339572D01*
Y-339540D01*
Y-339507D01*
Y-339475D01*
Y-339443D01*
Y-339411D01*
Y-339378D01*
Y-339346D01*
Y-339314D01*
Y-339282D01*
Y-339249D01*
Y-339217D01*
Y-339185D01*
Y-339153D01*
Y-339120D01*
Y-339088D01*
Y-339056D01*
Y-339023D01*
Y-338991D01*
Y-338959D01*
Y-338927D01*
Y-338894D01*
Y-338862D01*
Y-338830D01*
Y-338798D01*
Y-338765D01*
Y-338733D01*
Y-338701D01*
Y-338669D01*
Y-338636D01*
Y-338604D01*
Y-338572D01*
Y-338540D01*
Y-338507D01*
Y-338475D01*
Y-338443D01*
Y-338410D01*
Y-338378D01*
Y-338346D01*
Y-338314D01*
Y-338281D01*
Y-338249D01*
Y-338217D01*
Y-338185D01*
Y-338152D01*
Y-338120D01*
Y-338088D01*
Y-338056D01*
Y-338023D01*
Y-337991D01*
Y-337959D01*
Y-337927D01*
Y-337894D01*
Y-337862D01*
Y-337830D01*
Y-337797D01*
Y-337765D01*
Y-337733D01*
Y-337701D01*
Y-337668D01*
Y-337636D01*
Y-337604D01*
Y-337572D01*
Y-337539D01*
Y-337507D01*
Y-337475D01*
Y-337443D01*
Y-337410D01*
Y-337378D01*
Y-337346D01*
Y-337314D01*
Y-337281D01*
Y-337249D01*
Y-337217D01*
Y-337185D01*
Y-337152D01*
Y-337120D01*
Y-337088D01*
Y-337055D01*
Y-337023D01*
Y-336991D01*
Y-336959D01*
Y-336927D01*
Y-336894D01*
Y-336862D01*
Y-336830D01*
Y-336797D01*
Y-336765D01*
Y-336733D01*
Y-336701D01*
Y-336668D01*
Y-336636D01*
Y-336604D01*
Y-336572D01*
Y-336539D01*
Y-336507D01*
Y-336475D01*
Y-336442D01*
Y-336410D01*
Y-336378D01*
Y-336346D01*
Y-336314D01*
Y-336281D01*
Y-336249D01*
Y-336217D01*
Y-336184D01*
Y-336152D01*
Y-336120D01*
Y-336088D01*
Y-336055D01*
Y-336023D01*
Y-335991D01*
Y-335959D01*
Y-335926D01*
Y-335894D01*
Y-335862D01*
Y-335830D01*
Y-335797D01*
Y-335765D01*
Y-335733D01*
Y-335700D01*
Y-335668D01*
Y-335636D01*
Y-335604D01*
Y-335572D01*
Y-335539D01*
Y-335507D01*
Y-335475D01*
Y-335442D01*
Y-335410D01*
Y-335378D01*
Y-335346D01*
Y-335313D01*
Y-335281D01*
Y-335249D01*
Y-335217D01*
Y-335184D01*
Y-335152D01*
Y-335120D01*
Y-335087D01*
Y-335055D01*
Y-335023D01*
Y-334991D01*
Y-334959D01*
Y-334926D01*
Y-334894D01*
Y-334862D01*
Y-334829D01*
Y-334797D01*
Y-334765D01*
Y-334733D01*
Y-334700D01*
Y-334668D01*
Y-334636D01*
Y-334604D01*
Y-334571D01*
Y-334539D01*
Y-334507D01*
Y-334474D01*
Y-334442D01*
Y-334410D01*
Y-334378D01*
Y-334346D01*
Y-334313D01*
Y-334281D01*
Y-334249D01*
Y-334216D01*
Y-334184D01*
Y-334152D01*
Y-334120D01*
Y-334087D01*
Y-334055D01*
Y-334023D01*
Y-333991D01*
Y-333958D01*
Y-333926D01*
Y-333894D01*
Y-333862D01*
Y-333829D01*
Y-333797D01*
Y-333765D01*
Y-333733D01*
Y-333700D01*
Y-333668D01*
Y-333636D01*
Y-333604D01*
Y-333571D01*
Y-333539D01*
Y-333507D01*
Y-333474D01*
Y-333442D01*
Y-333410D01*
Y-333378D01*
Y-333345D01*
Y-333313D01*
Y-333281D01*
Y-333249D01*
Y-333216D01*
Y-333184D01*
Y-333152D01*
Y-333120D01*
Y-333087D01*
Y-333055D01*
Y-333023D01*
Y-332991D01*
Y-332958D01*
Y-332926D01*
Y-332894D01*
Y-332861D01*
Y-332829D01*
Y-332797D01*
Y-332765D01*
Y-332732D01*
Y-332700D01*
Y-332668D01*
Y-332636D01*
Y-332603D01*
Y-332571D01*
Y-332539D01*
Y-332507D01*
Y-332474D01*
Y-332442D01*
Y-332410D01*
Y-332378D01*
Y-332345D01*
Y-332313D01*
Y-332281D01*
Y-332248D01*
Y-332216D01*
Y-332184D01*
Y-332152D01*
Y-332119D01*
Y-332087D01*
Y-332055D01*
Y-332023D01*
Y-331990D01*
Y-331958D01*
Y-331926D01*
Y-331894D01*
Y-331861D01*
Y-331829D01*
Y-331797D01*
Y-331765D01*
Y-331732D01*
Y-331700D01*
Y-331668D01*
Y-331635D01*
Y-331603D01*
Y-331571D01*
Y-331539D01*
Y-331506D01*
Y-331474D01*
Y-331442D01*
Y-331410D01*
Y-331377D01*
Y-331345D01*
Y-331313D01*
Y-331281D01*
Y-331248D01*
Y-331216D01*
Y-331184D01*
Y-331152D01*
Y-331119D01*
Y-331087D01*
Y-331055D01*
Y-331023D01*
Y-330990D01*
Y-330958D01*
X374013D01*
Y-330926D01*
Y-330893D01*
Y-330861D01*
Y-330829D01*
X373981D01*
Y-330797D01*
Y-330764D01*
X373949D01*
Y-330732D01*
X373916D01*
Y-330700D01*
X373884D01*
Y-330668D01*
X373852D01*
Y-330635D01*
X373819D01*
Y-330603D01*
X373787D01*
Y-330571D01*
X373755D01*
Y-330539D01*
X373723D01*
Y-330506D01*
X373690D01*
Y-330474D01*
X373658D01*
Y-330442D01*
X373626D01*
Y-330410D01*
X373594D01*
Y-330377D01*
X373561D01*
Y-330345D01*
X373529D01*
Y-330313D01*
X373497D01*
Y-330280D01*
X373465D01*
Y-330248D01*
X373432D01*
Y-330216D01*
X373400D01*
Y-330184D01*
X373368D01*
Y-330152D01*
X373336D01*
Y-330119D01*
X373303D01*
Y-330087D01*
X373271D01*
Y-330055D01*
X373239D01*
Y-330022D01*
X373206D01*
Y-329990D01*
X373174D01*
Y-329958D01*
X373142D01*
Y-329926D01*
X373110D01*
Y-329893D01*
X373078D01*
Y-329861D01*
X373013D01*
Y-329829D01*
X372884D01*
Y-329797D01*
D02*
G37*
G36*
X388499Y-341249D02*
X384047D01*
Y-341282D01*
X383982D01*
Y-341314D01*
X383950D01*
Y-341346D01*
X383917D01*
Y-341379D01*
X383885D01*
Y-341411D01*
Y-341443D01*
Y-341475D01*
Y-341508D01*
Y-341540D01*
Y-341572D01*
Y-341604D01*
Y-341637D01*
Y-341669D01*
Y-341701D01*
Y-341734D01*
Y-341766D01*
Y-341798D01*
Y-341830D01*
Y-341863D01*
Y-341895D01*
Y-341927D01*
Y-341959D01*
Y-341992D01*
Y-342024D01*
Y-342056D01*
Y-342088D01*
Y-342121D01*
Y-342153D01*
Y-342185D01*
Y-342217D01*
Y-342250D01*
Y-342282D01*
Y-342314D01*
Y-342346D01*
Y-342379D01*
Y-342411D01*
Y-342443D01*
Y-342476D01*
Y-342508D01*
Y-342540D01*
Y-342572D01*
Y-342604D01*
Y-342637D01*
Y-342669D01*
Y-342701D01*
Y-342734D01*
Y-342766D01*
Y-342798D01*
Y-342830D01*
Y-342863D01*
Y-342895D01*
Y-342927D01*
Y-342959D01*
Y-342992D01*
Y-343024D01*
Y-343056D01*
Y-343089D01*
Y-343121D01*
Y-343153D01*
Y-343185D01*
Y-343217D01*
Y-343250D01*
Y-343282D01*
Y-343314D01*
Y-343347D01*
Y-343379D01*
Y-343411D01*
Y-343443D01*
Y-343476D01*
Y-343508D01*
Y-343540D01*
Y-343572D01*
Y-343605D01*
Y-343637D01*
Y-343669D01*
Y-343701D01*
Y-343734D01*
Y-343766D01*
Y-343798D01*
Y-343830D01*
Y-343863D01*
Y-343895D01*
Y-343927D01*
Y-343959D01*
Y-343992D01*
Y-344024D01*
Y-344056D01*
Y-344089D01*
Y-344121D01*
Y-344153D01*
Y-344185D01*
Y-344218D01*
Y-344250D01*
Y-344282D01*
Y-344314D01*
Y-344347D01*
Y-344379D01*
Y-344411D01*
Y-344443D01*
Y-344476D01*
Y-344508D01*
Y-344540D01*
Y-344572D01*
Y-344605D01*
Y-344637D01*
Y-344669D01*
Y-344702D01*
Y-344734D01*
Y-344766D01*
Y-344798D01*
Y-344831D01*
Y-344863D01*
Y-344895D01*
Y-344927D01*
Y-344960D01*
Y-344992D01*
Y-345024D01*
Y-345056D01*
Y-345089D01*
Y-345121D01*
Y-345153D01*
Y-345185D01*
Y-345218D01*
Y-345250D01*
Y-345282D01*
Y-345315D01*
Y-345347D01*
Y-345379D01*
Y-345411D01*
Y-345444D01*
Y-345476D01*
Y-345508D01*
Y-345540D01*
Y-345573D01*
Y-345605D01*
Y-345637D01*
Y-345669D01*
Y-345702D01*
Y-345734D01*
Y-345766D01*
Y-345798D01*
Y-345831D01*
Y-345863D01*
Y-345895D01*
Y-345928D01*
Y-345960D01*
Y-345992D01*
Y-346024D01*
Y-346057D01*
Y-346089D01*
Y-346121D01*
Y-346153D01*
Y-346186D01*
Y-346218D01*
Y-346250D01*
Y-346282D01*
Y-346315D01*
Y-346347D01*
Y-346379D01*
Y-346411D01*
Y-346444D01*
Y-346476D01*
Y-346508D01*
Y-346540D01*
Y-346573D01*
Y-346605D01*
Y-346637D01*
Y-346670D01*
Y-346702D01*
Y-346734D01*
Y-346766D01*
Y-346799D01*
Y-346831D01*
Y-346863D01*
Y-346895D01*
Y-346928D01*
Y-346960D01*
Y-346992D01*
Y-347024D01*
Y-347057D01*
Y-347089D01*
Y-347121D01*
Y-347153D01*
Y-347186D01*
Y-347218D01*
Y-347250D01*
Y-347283D01*
Y-347315D01*
Y-347347D01*
Y-347379D01*
Y-347411D01*
Y-347444D01*
Y-347476D01*
Y-347508D01*
Y-347541D01*
Y-347573D01*
Y-347605D01*
Y-347637D01*
Y-347670D01*
Y-347702D01*
Y-347734D01*
Y-347766D01*
Y-347799D01*
Y-347831D01*
Y-347863D01*
Y-347896D01*
Y-347928D01*
Y-347960D01*
Y-347992D01*
Y-348025D01*
Y-348057D01*
Y-348089D01*
Y-348121D01*
Y-348154D01*
Y-348186D01*
X383917D01*
Y-348218D01*
X383950D01*
Y-348250D01*
X383982D01*
Y-348283D01*
X388595D01*
Y-348250D01*
X388724D01*
Y-348218D01*
X388789D01*
Y-348186D01*
X388821D01*
Y-348154D01*
X388854D01*
Y-348121D01*
X388886D01*
Y-348089D01*
X388918D01*
Y-348057D01*
X388950D01*
Y-348025D01*
X388983D01*
Y-347992D01*
X389015D01*
Y-347960D01*
X389047D01*
Y-347928D01*
X389079D01*
Y-347896D01*
X389112D01*
Y-347863D01*
X389144D01*
Y-347831D01*
X389176D01*
Y-347799D01*
X389208D01*
Y-347766D01*
X389241D01*
Y-347734D01*
X389273D01*
Y-347702D01*
X389305D01*
Y-347670D01*
X389337D01*
Y-347637D01*
X389370D01*
Y-347605D01*
X389402D01*
Y-347573D01*
X389434D01*
Y-347541D01*
X389466D01*
Y-347508D01*
X389499D01*
Y-347476D01*
X389531D01*
Y-347444D01*
X389563D01*
Y-347411D01*
X389596D01*
Y-347379D01*
X389628D01*
Y-347347D01*
X389660D01*
Y-347315D01*
X389692D01*
Y-347283D01*
X389724D01*
Y-347250D01*
Y-347218D01*
Y-347186D01*
X389757D01*
Y-347153D01*
Y-347121D01*
Y-347089D01*
Y-347057D01*
X389789D01*
Y-347024D01*
Y-346992D01*
Y-346960D01*
Y-346928D01*
Y-346895D01*
Y-346863D01*
Y-346831D01*
Y-346799D01*
Y-346766D01*
Y-346734D01*
Y-346702D01*
Y-346670D01*
Y-346637D01*
Y-346605D01*
Y-346573D01*
Y-346540D01*
Y-346508D01*
Y-346476D01*
Y-346444D01*
Y-346411D01*
Y-346379D01*
Y-346347D01*
Y-346315D01*
Y-346282D01*
Y-346250D01*
Y-346218D01*
Y-346186D01*
Y-346153D01*
Y-346121D01*
Y-346089D01*
Y-346057D01*
Y-346024D01*
Y-345992D01*
Y-345960D01*
Y-345928D01*
Y-345895D01*
Y-345863D01*
Y-345831D01*
Y-345798D01*
Y-345766D01*
Y-345734D01*
Y-345702D01*
Y-345669D01*
Y-345637D01*
Y-345605D01*
Y-345573D01*
Y-345540D01*
Y-345508D01*
Y-345476D01*
Y-345444D01*
Y-345411D01*
Y-345379D01*
Y-345347D01*
Y-345315D01*
Y-345282D01*
Y-345250D01*
Y-345218D01*
Y-345185D01*
Y-345153D01*
Y-345121D01*
Y-345089D01*
Y-345056D01*
Y-345024D01*
Y-344992D01*
Y-344960D01*
Y-344927D01*
Y-344895D01*
Y-344863D01*
Y-344831D01*
Y-344798D01*
Y-344766D01*
Y-344734D01*
Y-344702D01*
Y-344669D01*
Y-344637D01*
Y-344605D01*
Y-344572D01*
Y-344540D01*
Y-344508D01*
Y-344476D01*
Y-344443D01*
Y-344411D01*
Y-344379D01*
Y-344347D01*
Y-344314D01*
Y-344282D01*
Y-344250D01*
Y-344218D01*
Y-344185D01*
Y-344153D01*
Y-344121D01*
Y-344089D01*
Y-344056D01*
Y-344024D01*
Y-343992D01*
Y-343959D01*
Y-343927D01*
Y-343895D01*
Y-343863D01*
Y-343830D01*
Y-343798D01*
Y-343766D01*
Y-343734D01*
Y-343701D01*
Y-343669D01*
Y-343637D01*
Y-343605D01*
Y-343572D01*
Y-343540D01*
Y-343508D01*
Y-343476D01*
Y-343443D01*
Y-343411D01*
Y-343379D01*
Y-343347D01*
Y-343314D01*
Y-343282D01*
Y-343250D01*
Y-343217D01*
Y-343185D01*
Y-343153D01*
Y-343121D01*
Y-343089D01*
Y-343056D01*
Y-343024D01*
Y-342992D01*
Y-342959D01*
Y-342927D01*
Y-342895D01*
Y-342863D01*
Y-342830D01*
Y-342798D01*
Y-342766D01*
Y-342734D01*
Y-342701D01*
Y-342669D01*
Y-342637D01*
Y-342604D01*
Y-342572D01*
Y-342540D01*
Y-342508D01*
Y-342476D01*
X389757D01*
Y-342443D01*
Y-342411D01*
Y-342379D01*
Y-342346D01*
X389724D01*
Y-342314D01*
Y-342282D01*
X389692D01*
Y-342250D01*
X389660D01*
Y-342217D01*
X389628D01*
Y-342185D01*
X389596D01*
Y-342153D01*
X389563D01*
Y-342121D01*
X389531D01*
Y-342088D01*
X389499D01*
Y-342056D01*
X389466D01*
Y-342024D01*
X389434D01*
Y-341992D01*
X389402D01*
Y-341959D01*
X389370D01*
Y-341927D01*
X389337D01*
Y-341895D01*
X389305D01*
Y-341863D01*
X389273D01*
Y-341830D01*
X389241D01*
Y-341798D01*
X389208D01*
Y-341766D01*
X389176D01*
Y-341734D01*
X389144D01*
Y-341701D01*
X389112D01*
Y-341669D01*
X389079D01*
Y-341637D01*
X389047D01*
Y-341604D01*
X389015D01*
Y-341572D01*
X388983D01*
Y-341540D01*
X388950D01*
Y-341508D01*
X388918D01*
Y-341475D01*
X388886D01*
Y-341443D01*
X388854D01*
Y-341411D01*
X388821D01*
Y-341379D01*
X388789D01*
Y-341346D01*
X388757D01*
Y-341314D01*
X388660D01*
Y-341282D01*
X388499D01*
Y-341249D01*
D02*
G37*
G36*
X381627D02*
X377175D01*
Y-341282D01*
X377110D01*
Y-341314D01*
X377078D01*
Y-341346D01*
X377046D01*
Y-341379D01*
Y-341411D01*
Y-341443D01*
X377013D01*
Y-341475D01*
Y-341508D01*
Y-341540D01*
Y-341572D01*
Y-341604D01*
Y-341637D01*
Y-341669D01*
Y-341701D01*
Y-341734D01*
Y-341766D01*
Y-341798D01*
Y-341830D01*
Y-341863D01*
Y-341895D01*
Y-341927D01*
Y-341959D01*
Y-341992D01*
Y-342024D01*
Y-342056D01*
Y-342088D01*
Y-342121D01*
Y-342153D01*
Y-342185D01*
Y-342217D01*
Y-342250D01*
Y-342282D01*
Y-342314D01*
Y-342346D01*
Y-342379D01*
Y-342411D01*
Y-342443D01*
Y-342476D01*
Y-342508D01*
Y-342540D01*
Y-342572D01*
Y-342604D01*
Y-342637D01*
Y-342669D01*
Y-342701D01*
Y-342734D01*
Y-342766D01*
Y-342798D01*
Y-342830D01*
Y-342863D01*
Y-342895D01*
Y-342927D01*
Y-342959D01*
Y-342992D01*
Y-343024D01*
Y-343056D01*
Y-343089D01*
Y-343121D01*
Y-343153D01*
Y-343185D01*
Y-343217D01*
Y-343250D01*
Y-343282D01*
Y-343314D01*
Y-343347D01*
Y-343379D01*
Y-343411D01*
Y-343443D01*
Y-343476D01*
Y-343508D01*
Y-343540D01*
Y-343572D01*
Y-343605D01*
Y-343637D01*
Y-343669D01*
Y-343701D01*
Y-343734D01*
Y-343766D01*
Y-343798D01*
Y-343830D01*
Y-343863D01*
Y-343895D01*
Y-343927D01*
Y-343959D01*
Y-343992D01*
Y-344024D01*
Y-344056D01*
Y-344089D01*
Y-344121D01*
Y-344153D01*
Y-344185D01*
Y-344218D01*
Y-344250D01*
Y-344282D01*
Y-344314D01*
Y-344347D01*
Y-344379D01*
Y-344411D01*
Y-344443D01*
Y-344476D01*
Y-344508D01*
Y-344540D01*
Y-344572D01*
Y-344605D01*
Y-344637D01*
Y-344669D01*
Y-344702D01*
Y-344734D01*
Y-344766D01*
Y-344798D01*
Y-344831D01*
Y-344863D01*
Y-344895D01*
Y-344927D01*
Y-344960D01*
Y-344992D01*
Y-345024D01*
Y-345056D01*
Y-345089D01*
Y-345121D01*
Y-345153D01*
Y-345185D01*
Y-345218D01*
Y-345250D01*
Y-345282D01*
Y-345315D01*
Y-345347D01*
Y-345379D01*
Y-345411D01*
Y-345444D01*
Y-345476D01*
Y-345508D01*
Y-345540D01*
Y-345573D01*
Y-345605D01*
Y-345637D01*
Y-345669D01*
Y-345702D01*
Y-345734D01*
Y-345766D01*
Y-345798D01*
Y-345831D01*
Y-345863D01*
Y-345895D01*
Y-345928D01*
Y-345960D01*
Y-345992D01*
Y-346024D01*
Y-346057D01*
Y-346089D01*
Y-346121D01*
Y-346153D01*
Y-346186D01*
Y-346218D01*
Y-346250D01*
Y-346282D01*
Y-346315D01*
Y-346347D01*
Y-346379D01*
Y-346411D01*
Y-346444D01*
Y-346476D01*
Y-346508D01*
Y-346540D01*
Y-346573D01*
Y-346605D01*
Y-346637D01*
Y-346670D01*
Y-346702D01*
Y-346734D01*
Y-346766D01*
Y-346799D01*
Y-346831D01*
Y-346863D01*
Y-346895D01*
Y-346928D01*
Y-346960D01*
Y-346992D01*
Y-347024D01*
Y-347057D01*
Y-347089D01*
Y-347121D01*
Y-347153D01*
Y-347186D01*
Y-347218D01*
Y-347250D01*
Y-347283D01*
Y-347315D01*
Y-347347D01*
Y-347379D01*
Y-347411D01*
Y-347444D01*
Y-347476D01*
Y-347508D01*
Y-347541D01*
Y-347573D01*
Y-347605D01*
Y-347637D01*
Y-347670D01*
Y-347702D01*
Y-347734D01*
Y-347766D01*
Y-347799D01*
Y-347831D01*
Y-347863D01*
Y-347896D01*
Y-347928D01*
Y-347960D01*
Y-347992D01*
Y-348025D01*
Y-348057D01*
X377046D01*
Y-348089D01*
X377013D01*
Y-348121D01*
X377046D01*
Y-348154D01*
Y-348186D01*
Y-348218D01*
X377078D01*
Y-348250D01*
X377143D01*
Y-348283D01*
X378723D01*
Y-348250D01*
X378755D01*
Y-348218D01*
X378788D01*
Y-348186D01*
Y-348154D01*
Y-348121D01*
X378820D01*
Y-348089D01*
Y-348057D01*
Y-348025D01*
Y-347992D01*
Y-347960D01*
Y-347928D01*
Y-347896D01*
Y-347863D01*
Y-347831D01*
Y-347799D01*
Y-347766D01*
Y-347734D01*
Y-347702D01*
Y-347670D01*
Y-347637D01*
Y-347605D01*
Y-347573D01*
Y-347541D01*
Y-347508D01*
Y-347476D01*
Y-347444D01*
Y-347411D01*
Y-347379D01*
Y-347347D01*
Y-347315D01*
Y-347283D01*
Y-347250D01*
Y-347218D01*
Y-347186D01*
Y-347153D01*
Y-347121D01*
Y-347089D01*
Y-347057D01*
Y-347024D01*
Y-346992D01*
Y-346960D01*
Y-346928D01*
Y-346895D01*
Y-346863D01*
Y-346831D01*
Y-346799D01*
Y-346766D01*
Y-346734D01*
Y-346702D01*
Y-346670D01*
Y-346637D01*
Y-346605D01*
Y-346573D01*
Y-346540D01*
Y-346508D01*
Y-346476D01*
Y-346444D01*
Y-346411D01*
Y-346379D01*
X378788D01*
Y-346347D01*
X378820D01*
Y-346315D01*
Y-346282D01*
Y-346250D01*
Y-346218D01*
Y-346186D01*
X380046D01*
Y-346218D01*
Y-346250D01*
X380078D01*
Y-346282D01*
Y-346315D01*
X380111D01*
Y-346347D01*
X380143D01*
Y-346379D01*
Y-346411D01*
X380175D01*
Y-346444D01*
Y-346476D01*
X380207D01*
Y-346508D01*
X380240D01*
Y-346540D01*
Y-346573D01*
X380272D01*
Y-346605D01*
Y-346637D01*
X380304D01*
Y-346670D01*
Y-346702D01*
X380336D01*
Y-346734D01*
X380369D01*
Y-346766D01*
Y-346799D01*
X380401D01*
Y-346831D01*
Y-346863D01*
X380433D01*
Y-346895D01*
X380465D01*
Y-346928D01*
Y-346960D01*
X380498D01*
Y-346992D01*
Y-347024D01*
X380530D01*
Y-347057D01*
X380562D01*
Y-347089D01*
Y-347121D01*
X380594D01*
Y-347153D01*
Y-347186D01*
X380627D01*
Y-347218D01*
Y-347250D01*
X380659D01*
Y-347283D01*
X380691D01*
Y-347315D01*
Y-347347D01*
X380724D01*
Y-347379D01*
Y-347411D01*
X380756D01*
Y-347444D01*
X380788D01*
Y-347476D01*
Y-347508D01*
X380820D01*
Y-347541D01*
Y-347573D01*
X380853D01*
Y-347605D01*
X380885D01*
Y-347637D01*
Y-347670D01*
X380917D01*
Y-347702D01*
Y-347734D01*
X380949D01*
Y-347766D01*
X380982D01*
Y-347799D01*
Y-347831D01*
X381014D01*
Y-347863D01*
Y-347896D01*
X381046D01*
Y-347928D01*
Y-347960D01*
X381078D01*
Y-347992D01*
X381111D01*
Y-348025D01*
Y-348057D01*
X381143D01*
Y-348089D01*
Y-348121D01*
X381175D01*
Y-348154D01*
X381207D01*
Y-348186D01*
X381240D01*
Y-348218D01*
X381272D01*
Y-348250D01*
X381336D01*
Y-348283D01*
X383143D01*
Y-348250D01*
X383175D01*
Y-348218D01*
Y-348186D01*
Y-348154D01*
Y-348121D01*
X383143D01*
Y-348089D01*
X383111D01*
Y-348057D01*
Y-348025D01*
X383079D01*
Y-347992D01*
Y-347960D01*
X383046D01*
Y-347928D01*
X383014D01*
Y-347896D01*
Y-347863D01*
X382982D01*
Y-347831D01*
Y-347799D01*
X382950D01*
Y-347766D01*
X382917D01*
Y-347734D01*
Y-347702D01*
X382885D01*
Y-347670D01*
Y-347637D01*
X382853D01*
Y-347605D01*
X382821D01*
Y-347573D01*
Y-347541D01*
X382788D01*
Y-347508D01*
Y-347476D01*
X382756D01*
Y-347444D01*
X382724D01*
Y-347411D01*
Y-347379D01*
X382692D01*
Y-347347D01*
Y-347315D01*
X382659D01*
Y-347283D01*
X382627D01*
Y-347250D01*
Y-347218D01*
X382595D01*
Y-347186D01*
Y-347153D01*
X382562D01*
Y-347121D01*
X382530D01*
Y-347089D01*
Y-347057D01*
X382498D01*
Y-347024D01*
Y-346992D01*
X382466D01*
Y-346960D01*
X382433D01*
Y-346928D01*
Y-346895D01*
X382401D01*
Y-346863D01*
Y-346831D01*
X382369D01*
Y-346799D01*
X382337D01*
Y-346766D01*
Y-346734D01*
X382304D01*
Y-346702D01*
Y-346670D01*
X382272D01*
Y-346637D01*
X382240D01*
Y-346605D01*
Y-346573D01*
X382207D01*
Y-346540D01*
Y-346508D01*
X382175D01*
Y-346476D01*
X382143D01*
Y-346444D01*
Y-346411D01*
X382111D01*
Y-346379D01*
Y-346347D01*
X382079D01*
Y-346315D01*
Y-346282D01*
X382046D01*
Y-346250D01*
X382014D01*
Y-346218D01*
Y-346186D01*
X381982D01*
Y-346153D01*
Y-346121D01*
X381949D01*
Y-346089D01*
X381917D01*
Y-346057D01*
Y-346024D01*
X381949D01*
Y-345992D01*
X381982D01*
Y-345960D01*
X382014D01*
Y-345928D01*
X382046D01*
Y-345895D01*
X382079D01*
Y-345863D01*
X382111D01*
Y-345831D01*
X382143D01*
Y-345798D01*
X382175D01*
Y-345766D01*
X382207D01*
Y-345734D01*
X382240D01*
Y-345702D01*
X382272D01*
Y-345669D01*
X382304D01*
Y-345637D01*
X382337D01*
Y-345605D01*
X382369D01*
Y-345573D01*
X382401D01*
Y-345540D01*
X382433D01*
Y-345508D01*
X382466D01*
Y-345476D01*
X382498D01*
Y-345444D01*
X382530D01*
Y-345411D01*
X382562D01*
Y-345379D01*
X382595D01*
Y-345347D01*
X382627D01*
Y-345315D01*
X382659D01*
Y-345282D01*
Y-345250D01*
X382692D01*
Y-345218D01*
X382724D01*
Y-345185D01*
X382756D01*
Y-345153D01*
X382788D01*
Y-345121D01*
X382821D01*
Y-345089D01*
X382853D01*
Y-345056D01*
Y-345024D01*
X382885D01*
Y-344992D01*
Y-344960D01*
X382917D01*
Y-344927D01*
Y-344895D01*
Y-344863D01*
Y-344831D01*
Y-344798D01*
Y-344766D01*
Y-344734D01*
Y-344702D01*
Y-344669D01*
Y-344637D01*
Y-344605D01*
Y-344572D01*
Y-344540D01*
Y-344508D01*
Y-344476D01*
Y-344443D01*
Y-344411D01*
Y-344379D01*
Y-344347D01*
Y-344314D01*
Y-344282D01*
Y-344250D01*
Y-344218D01*
Y-344185D01*
Y-344153D01*
Y-344121D01*
Y-344089D01*
Y-344056D01*
Y-344024D01*
Y-343992D01*
Y-343959D01*
Y-343927D01*
Y-343895D01*
Y-343863D01*
Y-343830D01*
Y-343798D01*
Y-343766D01*
Y-343734D01*
Y-343701D01*
Y-343669D01*
Y-343637D01*
Y-343605D01*
Y-343572D01*
Y-343540D01*
Y-343508D01*
Y-343476D01*
Y-343443D01*
Y-343411D01*
Y-343379D01*
Y-343347D01*
Y-343314D01*
Y-343282D01*
Y-343250D01*
Y-343217D01*
Y-343185D01*
Y-343153D01*
Y-343121D01*
Y-343089D01*
Y-343056D01*
Y-343024D01*
Y-342992D01*
Y-342959D01*
Y-342927D01*
Y-342895D01*
Y-342863D01*
Y-342830D01*
Y-342798D01*
Y-342766D01*
Y-342734D01*
Y-342701D01*
Y-342669D01*
Y-342637D01*
Y-342604D01*
Y-342572D01*
Y-342540D01*
Y-342508D01*
Y-342476D01*
Y-342443D01*
Y-342411D01*
X382885D01*
Y-342379D01*
Y-342346D01*
Y-342314D01*
X382853D01*
Y-342282D01*
Y-342250D01*
X382821D01*
Y-342217D01*
X382788D01*
Y-342185D01*
X382756D01*
Y-342153D01*
X382724D01*
Y-342121D01*
X382692D01*
Y-342088D01*
X382659D01*
Y-342056D01*
X382627D01*
Y-342024D01*
X382595D01*
Y-341992D01*
X382562D01*
Y-341959D01*
X382530D01*
Y-341927D01*
X382498D01*
Y-341895D01*
X382466D01*
Y-341863D01*
X382433D01*
Y-341830D01*
X382401D01*
Y-341798D01*
X382369D01*
Y-341766D01*
X382337D01*
Y-341734D01*
X382304D01*
Y-341701D01*
X382272D01*
Y-341669D01*
X382240D01*
Y-341637D01*
X382207D01*
Y-341604D01*
X382175D01*
Y-341572D01*
X382143D01*
Y-341540D01*
X382111D01*
Y-341508D01*
X382079D01*
Y-341475D01*
X382046D01*
Y-341443D01*
X382014D01*
Y-341411D01*
X381982D01*
Y-341379D01*
X381949D01*
Y-341346D01*
X381885D01*
Y-341314D01*
X381788D01*
Y-341282D01*
X381627D01*
Y-341249D01*
D02*
G37*
G36*
X361302Y-341282D02*
X360915D01*
Y-341314D01*
Y-341346D01*
Y-341379D01*
Y-341411D01*
Y-341443D01*
Y-341475D01*
Y-341508D01*
Y-341540D01*
Y-341572D01*
Y-341604D01*
Y-341637D01*
X360947D01*
Y-341669D01*
Y-341701D01*
Y-341734D01*
Y-341766D01*
Y-341798D01*
Y-341830D01*
Y-341863D01*
Y-341895D01*
Y-341927D01*
Y-341959D01*
Y-341992D01*
X360979D01*
Y-342024D01*
X360947D01*
Y-342056D01*
X360979D01*
Y-342088D01*
Y-342121D01*
Y-342153D01*
Y-342185D01*
Y-342217D01*
Y-342250D01*
Y-342282D01*
Y-342314D01*
Y-342346D01*
Y-342379D01*
X361012D01*
Y-342411D01*
Y-342443D01*
Y-342476D01*
Y-342508D01*
Y-342540D01*
Y-342572D01*
Y-342604D01*
Y-342637D01*
X361044D01*
Y-342669D01*
Y-342701D01*
Y-342734D01*
Y-342766D01*
Y-342798D01*
Y-342830D01*
Y-342863D01*
X361076D01*
Y-342895D01*
Y-342927D01*
Y-342959D01*
Y-342992D01*
Y-343024D01*
Y-343056D01*
X361108D01*
Y-343089D01*
Y-343121D01*
Y-343153D01*
Y-343185D01*
Y-343217D01*
X361141D01*
Y-343250D01*
Y-343282D01*
Y-343314D01*
Y-343347D01*
Y-343379D01*
X361173D01*
Y-343411D01*
Y-343443D01*
Y-343476D01*
Y-343508D01*
Y-343540D01*
X361205D01*
Y-343572D01*
Y-343605D01*
Y-343637D01*
Y-343669D01*
Y-343701D01*
X361237D01*
Y-343734D01*
Y-343766D01*
Y-343798D01*
Y-343830D01*
X361270D01*
Y-343863D01*
Y-343895D01*
Y-343927D01*
Y-343959D01*
X361302D01*
Y-343992D01*
Y-344024D01*
Y-344056D01*
Y-344089D01*
X361334D01*
Y-344121D01*
Y-344153D01*
Y-344185D01*
Y-344218D01*
X361366D01*
Y-344250D01*
Y-344282D01*
Y-344314D01*
X361399D01*
Y-344347D01*
Y-344379D01*
Y-344411D01*
Y-344443D01*
X361431D01*
Y-344476D01*
Y-344508D01*
Y-344540D01*
X361463D01*
Y-344572D01*
Y-344605D01*
Y-344637D01*
X361495D01*
Y-344669D01*
Y-344702D01*
Y-344734D01*
X361528D01*
Y-344766D01*
Y-344798D01*
Y-344831D01*
X361560D01*
Y-344863D01*
Y-344895D01*
Y-344927D01*
X361592D01*
Y-344960D01*
Y-344992D01*
Y-345024D01*
X361625D01*
Y-345056D01*
Y-345089D01*
Y-345121D01*
X361657D01*
Y-345153D01*
Y-345185D01*
Y-345218D01*
X361689D01*
Y-345250D01*
Y-345282D01*
Y-345315D01*
X361721D01*
Y-345347D01*
Y-345379D01*
X361754D01*
Y-345411D01*
Y-345444D01*
Y-345476D01*
X361786D01*
Y-345508D01*
Y-345540D01*
X361818D01*
Y-345573D01*
Y-345605D01*
Y-345637D01*
X361850D01*
Y-345669D01*
Y-345702D01*
X361883D01*
Y-345734D01*
Y-345766D01*
Y-345798D01*
X361915D01*
Y-345831D01*
Y-345863D01*
X361947D01*
Y-345895D01*
Y-345928D01*
X361979D01*
Y-345960D01*
Y-345992D01*
Y-346024D01*
X362012D01*
Y-346057D01*
Y-346089D01*
X362044D01*
Y-346121D01*
Y-346153D01*
X362076D01*
Y-346186D01*
Y-346218D01*
X362108D01*
Y-346250D01*
Y-346282D01*
X362141D01*
Y-346315D01*
Y-346347D01*
X362173D01*
Y-346379D01*
Y-346411D01*
X362205D01*
Y-346444D01*
Y-346476D01*
X362238D01*
Y-346508D01*
Y-346540D01*
X362270D01*
Y-346573D01*
Y-346605D01*
X362302D01*
Y-346637D01*
Y-346670D01*
X362334D01*
Y-346702D01*
Y-346734D01*
X362367D01*
Y-346766D01*
Y-346799D01*
X362399D01*
Y-346831D01*
Y-346863D01*
X362431D01*
Y-346895D01*
X362463D01*
Y-346928D01*
Y-346960D01*
X362496D01*
Y-346992D01*
Y-347024D01*
X362528D01*
Y-347057D01*
Y-347089D01*
X362560D01*
Y-347121D01*
Y-347153D01*
X362592D01*
Y-347186D01*
X362625D01*
Y-347218D01*
Y-347250D01*
X362657D01*
Y-347283D01*
Y-347315D01*
X362689D01*
Y-347347D01*
Y-347379D01*
X362721D01*
Y-347411D01*
X362754D01*
Y-347444D01*
Y-347476D01*
X362786D01*
Y-347508D01*
X362818D01*
Y-347541D01*
Y-347573D01*
X362850D01*
Y-347605D01*
Y-347637D01*
X362883D01*
Y-347670D01*
X362915D01*
Y-347702D01*
Y-347734D01*
X362947D01*
Y-347766D01*
X362980D01*
Y-347799D01*
Y-347831D01*
X363012D01*
Y-347863D01*
X363044D01*
Y-347896D01*
Y-347928D01*
X363076D01*
Y-347960D01*
X363109D01*
Y-347992D01*
Y-348025D01*
X363141D01*
Y-348057D01*
X363173D01*
Y-348089D01*
X363205D01*
Y-348121D01*
Y-348154D01*
X363238D01*
Y-348186D01*
X363270D01*
Y-348218D01*
Y-348250D01*
X363302D01*
Y-348283D01*
X363334D01*
Y-348315D01*
X363367D01*
Y-348347D01*
Y-348379D01*
X363399D01*
Y-348412D01*
X363431D01*
Y-348444D01*
X363463D01*
Y-348476D01*
Y-348508D01*
X363496D01*
Y-348541D01*
X363528D01*
Y-348573D01*
X363560D01*
Y-348605D01*
X363593D01*
Y-348638D01*
Y-348670D01*
X363625D01*
Y-348702D01*
X363657D01*
Y-348734D01*
X363689D01*
Y-348766D01*
X363721D01*
Y-348799D01*
Y-348831D01*
X363754D01*
Y-348863D01*
X363786D01*
Y-348896D01*
X363818D01*
Y-348928D01*
X363851D01*
Y-348960D01*
Y-348992D01*
X363883D01*
Y-349025D01*
X363915D01*
Y-349057D01*
X363947D01*
Y-349089D01*
X363980D01*
Y-349121D01*
X364012D01*
Y-349154D01*
X364044D01*
Y-349186D01*
X364076D01*
Y-349218D01*
Y-349251D01*
X364109D01*
Y-349283D01*
X364141D01*
Y-349315D01*
X364173D01*
Y-349347D01*
X364206D01*
Y-349379D01*
X364238D01*
Y-349412D01*
X364270D01*
Y-349444D01*
X364302D01*
Y-349476D01*
X364335D01*
Y-349509D01*
X364367D01*
Y-349541D01*
X364399D01*
Y-349573D01*
X364431D01*
Y-349605D01*
X364464D01*
Y-349638D01*
X364496D01*
Y-349670D01*
X364528D01*
Y-349702D01*
X364560D01*
Y-349734D01*
X364593D01*
Y-349767D01*
X364625D01*
Y-349799D01*
X364657D01*
Y-349831D01*
X364689D01*
Y-349863D01*
X364722D01*
Y-349896D01*
X364754D01*
Y-349928D01*
X364786D01*
Y-349960D01*
X364818D01*
Y-349992D01*
X364851D01*
Y-350025D01*
X364883D01*
Y-350057D01*
X364915D01*
Y-350089D01*
X364948D01*
Y-350121D01*
X364980D01*
Y-350154D01*
X365012D01*
Y-350186D01*
X365044D01*
Y-350218D01*
X365109D01*
Y-350251D01*
X365141D01*
Y-350283D01*
X365173D01*
Y-350315D01*
X365206D01*
Y-350347D01*
X365238D01*
Y-350380D01*
X365270D01*
Y-350412D01*
X365302D01*
Y-350444D01*
X365367D01*
Y-350476D01*
X365399D01*
Y-350509D01*
X365431D01*
Y-350541D01*
X365464D01*
Y-350573D01*
X365496D01*
Y-350606D01*
X365561D01*
Y-350638D01*
X365593D01*
Y-350670D01*
X365625D01*
Y-350702D01*
X365657D01*
Y-350734D01*
X365722D01*
Y-350767D01*
X365754D01*
Y-350799D01*
X365786D01*
Y-350831D01*
X365851D01*
Y-350864D01*
X365883D01*
Y-350896D01*
X365915D01*
Y-350928D01*
X365980D01*
Y-350960D01*
X366012D01*
Y-350993D01*
X366044D01*
Y-351025D01*
X366109D01*
Y-351057D01*
X366141D01*
Y-351089D01*
X366206D01*
Y-351122D01*
X366238D01*
Y-351154D01*
X366270D01*
Y-351186D01*
X366335D01*
Y-351218D01*
X366367D01*
Y-351251D01*
X366431D01*
Y-351283D01*
X366464D01*
Y-351315D01*
X366528D01*
Y-351347D01*
X366561D01*
Y-351380D01*
X366625D01*
Y-351412D01*
X366657D01*
Y-351444D01*
X366722D01*
Y-351477D01*
X366786D01*
Y-351509D01*
X366819D01*
Y-351541D01*
X366883D01*
Y-351573D01*
X366915D01*
Y-351606D01*
X366980D01*
Y-351638D01*
X367044D01*
Y-351670D01*
X367077D01*
Y-351702D01*
X367141D01*
Y-351735D01*
X367206D01*
Y-351767D01*
X367270D01*
Y-351799D01*
X367303D01*
Y-351831D01*
X367367D01*
Y-351864D01*
X367432D01*
Y-351896D01*
X367496D01*
Y-351928D01*
X367561D01*
Y-351960D01*
X367625D01*
Y-351993D01*
X367690D01*
Y-352025D01*
X367754D01*
Y-352057D01*
X367819D01*
Y-352090D01*
X367883D01*
Y-352122D01*
X367948D01*
Y-352154D01*
X368012D01*
Y-352186D01*
X368077D01*
Y-352219D01*
X368141D01*
Y-352251D01*
X368206D01*
Y-352283D01*
X368270D01*
Y-352315D01*
X368367D01*
Y-352348D01*
X368432D01*
Y-352380D01*
X368496D01*
Y-352412D01*
X368593D01*
Y-352444D01*
X368658D01*
Y-352477D01*
X368754D01*
Y-352509D01*
X368819D01*
Y-352541D01*
X368916D01*
Y-352573D01*
X368980D01*
Y-352606D01*
X369077D01*
Y-352638D01*
X369174D01*
Y-352670D01*
X369271D01*
Y-352702D01*
X369335D01*
Y-352735D01*
X369432D01*
Y-352767D01*
X369529D01*
Y-352799D01*
X369658D01*
Y-352832D01*
X369755D01*
Y-352864D01*
X369851D01*
Y-352896D01*
X369980D01*
Y-352928D01*
X370077D01*
Y-352961D01*
X370206D01*
Y-352993D01*
X370335D01*
Y-353025D01*
X370464D01*
Y-353057D01*
X370593D01*
Y-353090D01*
X370755D01*
Y-353122D01*
X370884D01*
Y-353154D01*
X371045D01*
Y-353186D01*
X371238D01*
Y-353219D01*
X371432D01*
Y-353251D01*
X371658D01*
Y-353283D01*
X371884D01*
Y-353315D01*
X372206D01*
Y-353348D01*
X372593D01*
Y-353380D01*
X374142D01*
Y-353348D01*
X374562D01*
Y-353315D01*
X374852D01*
Y-353283D01*
X375110D01*
Y-353251D01*
X375336D01*
Y-353219D01*
X375529D01*
Y-353186D01*
X375691D01*
Y-353154D01*
X375884D01*
Y-353122D01*
X376013D01*
Y-353090D01*
X376142D01*
Y-353057D01*
X376304D01*
Y-353025D01*
X376433D01*
Y-352993D01*
X376562D01*
Y-352961D01*
X376691D01*
Y-352928D01*
X376788D01*
Y-352896D01*
X376917D01*
Y-352864D01*
X377013D01*
Y-352832D01*
X377110D01*
Y-352799D01*
X377207D01*
Y-352767D01*
X377304D01*
Y-352735D01*
X377401D01*
Y-352702D01*
X377497D01*
Y-352670D01*
X377594D01*
Y-352638D01*
X377691D01*
Y-352606D01*
X377788D01*
Y-352573D01*
X377852D01*
Y-352541D01*
X377949D01*
Y-352509D01*
X378013D01*
Y-352477D01*
X378110D01*
Y-352444D01*
X378175D01*
Y-352412D01*
X378272D01*
Y-352380D01*
X378336D01*
Y-352348D01*
X378401D01*
Y-352315D01*
X378497D01*
Y-352283D01*
X378562D01*
Y-352251D01*
X378626D01*
Y-352219D01*
X378691D01*
Y-352186D01*
X378755D01*
Y-352154D01*
X378820D01*
Y-352122D01*
X378885D01*
Y-352090D01*
X378949D01*
Y-352057D01*
X379014D01*
Y-352025D01*
X379078D01*
Y-351993D01*
X379143D01*
Y-351960D01*
X379207D01*
Y-351928D01*
X379272D01*
Y-351896D01*
X379336D01*
Y-351864D01*
X379401D01*
Y-351831D01*
X379433D01*
Y-351799D01*
X379498D01*
Y-351767D01*
X379562D01*
Y-351735D01*
X379627D01*
Y-351702D01*
X379659D01*
Y-351670D01*
X379723D01*
Y-351638D01*
X379788D01*
Y-351606D01*
X379820D01*
Y-351573D01*
X379885D01*
Y-351541D01*
X379949D01*
Y-351509D01*
X379981D01*
Y-351477D01*
X380046D01*
Y-351444D01*
X380078D01*
Y-351412D01*
X380143D01*
Y-351380D01*
X380207D01*
Y-351347D01*
X380240D01*
Y-351315D01*
X380304D01*
Y-351283D01*
X380336D01*
Y-351251D01*
X380401D01*
Y-351218D01*
X380433D01*
Y-351186D01*
X380465D01*
Y-351154D01*
X380530D01*
Y-351122D01*
X380562D01*
Y-351089D01*
X380627D01*
Y-351057D01*
X380659D01*
Y-351025D01*
X380724D01*
Y-350993D01*
X380756D01*
Y-350960D01*
X380788D01*
Y-350928D01*
X380853D01*
Y-350896D01*
X380885D01*
Y-350864D01*
X380917D01*
Y-350831D01*
X380982D01*
Y-350799D01*
X381014D01*
Y-350767D01*
X381046D01*
Y-350734D01*
X381078D01*
Y-350702D01*
X381143D01*
Y-350670D01*
X381175D01*
Y-350638D01*
X381207D01*
Y-350606D01*
X381240D01*
Y-350573D01*
X381304D01*
Y-350541D01*
X381336D01*
Y-350509D01*
X381369D01*
Y-350476D01*
X381401D01*
Y-350444D01*
X381433D01*
Y-350412D01*
X381498D01*
Y-350380D01*
X381530D01*
Y-350347D01*
X381562D01*
Y-350315D01*
X381595D01*
Y-350283D01*
X381627D01*
Y-350251D01*
X381659D01*
Y-350218D01*
X381691D01*
Y-350186D01*
X381756D01*
Y-350154D01*
X381788D01*
Y-350121D01*
X381820D01*
Y-350089D01*
X381853D01*
Y-350057D01*
X381885D01*
Y-350025D01*
X381917D01*
Y-349992D01*
X381949D01*
Y-349960D01*
X381982D01*
Y-349928D01*
X382014D01*
Y-349896D01*
X382046D01*
Y-349863D01*
X382079D01*
Y-349831D01*
X382111D01*
Y-349799D01*
X382143D01*
Y-349767D01*
X382175D01*
Y-349734D01*
X382207D01*
Y-349702D01*
X382240D01*
Y-349670D01*
X382272D01*
Y-349638D01*
X382304D01*
Y-349605D01*
X382337D01*
Y-349573D01*
X382369D01*
Y-349541D01*
X382401D01*
Y-349509D01*
X382433D01*
Y-349476D01*
X382466D01*
Y-349444D01*
X382498D01*
Y-349412D01*
X382530D01*
Y-349379D01*
X382562D01*
Y-349347D01*
X382595D01*
Y-349315D01*
X382627D01*
Y-349283D01*
X382659D01*
Y-349251D01*
Y-349218D01*
X382692D01*
Y-349186D01*
X382724D01*
Y-349154D01*
X382756D01*
Y-349121D01*
X382788D01*
Y-349089D01*
X382821D01*
Y-349057D01*
X382853D01*
Y-349025D01*
X382885D01*
Y-348992D01*
Y-348960D01*
X382917D01*
Y-348928D01*
X382401D01*
Y-348960D01*
X382369D01*
Y-348992D01*
X382337D01*
Y-349025D01*
Y-349057D01*
X382304D01*
Y-349089D01*
X382272D01*
Y-349121D01*
X382240D01*
Y-349154D01*
X382207D01*
Y-349186D01*
X382175D01*
Y-349218D01*
X382143D01*
Y-349251D01*
X382111D01*
Y-349283D01*
X382079D01*
Y-349315D01*
X382046D01*
Y-349347D01*
X382014D01*
Y-349379D01*
X381982D01*
Y-349412D01*
X381949D01*
Y-349444D01*
X381917D01*
Y-349476D01*
X381885D01*
Y-349509D01*
X381853D01*
Y-349541D01*
X381820D01*
Y-349573D01*
X381788D01*
Y-349605D01*
X381756D01*
Y-349638D01*
X381724D01*
Y-349670D01*
X381691D01*
Y-349702D01*
X381659D01*
Y-349734D01*
X381627D01*
Y-349767D01*
X381595D01*
Y-349799D01*
X381562D01*
Y-349831D01*
X381530D01*
Y-349863D01*
X381466D01*
Y-349896D01*
X381433D01*
Y-349928D01*
X381401D01*
Y-349960D01*
X381369D01*
Y-349992D01*
X381336D01*
Y-350025D01*
X381304D01*
Y-350057D01*
X381272D01*
Y-350089D01*
X381207D01*
Y-350121D01*
X381175D01*
Y-350154D01*
X381143D01*
Y-350186D01*
X381111D01*
Y-350218D01*
X381078D01*
Y-350251D01*
X381014D01*
Y-350283D01*
X380982D01*
Y-350315D01*
X380949D01*
Y-350347D01*
X380917D01*
Y-350380D01*
X380853D01*
Y-350412D01*
X380820D01*
Y-350444D01*
X380788D01*
Y-350476D01*
X380756D01*
Y-350509D01*
X380691D01*
Y-350541D01*
X380659D01*
Y-350573D01*
X380627D01*
Y-350606D01*
X380562D01*
Y-350638D01*
X380530D01*
Y-350670D01*
X380498D01*
Y-350702D01*
X380433D01*
Y-350734D01*
X380401D01*
Y-350767D01*
X380336D01*
Y-350799D01*
X380304D01*
Y-350831D01*
X380272D01*
Y-350864D01*
X380207D01*
Y-350896D01*
X380175D01*
Y-350928D01*
X380111D01*
Y-350960D01*
X380078D01*
Y-350993D01*
X380014D01*
Y-351025D01*
X379981D01*
Y-351057D01*
X379917D01*
Y-351089D01*
X379885D01*
Y-351122D01*
X379820D01*
Y-351154D01*
X379756D01*
Y-351186D01*
X379723D01*
Y-351218D01*
X379659D01*
Y-351251D01*
X379594D01*
Y-351283D01*
X379562D01*
Y-351315D01*
X379498D01*
Y-351347D01*
X379433D01*
Y-351380D01*
X379401D01*
Y-351412D01*
X379336D01*
Y-351444D01*
X379272D01*
Y-351477D01*
X379207D01*
Y-351509D01*
X379175D01*
Y-351541D01*
X379110D01*
Y-351573D01*
X379046D01*
Y-351606D01*
X378981D01*
Y-351638D01*
X378917D01*
Y-351670D01*
X378852D01*
Y-351702D01*
X378788D01*
Y-351735D01*
X378723D01*
Y-351767D01*
X378659D01*
Y-351799D01*
X378594D01*
Y-351831D01*
X378530D01*
Y-351864D01*
X378465D01*
Y-351896D01*
X378401D01*
Y-351928D01*
X378336D01*
Y-351960D01*
X378239D01*
Y-351993D01*
X378175D01*
Y-352025D01*
X378078D01*
Y-352057D01*
X378013D01*
Y-352090D01*
X377949D01*
Y-352122D01*
X377852D01*
Y-352154D01*
X377788D01*
Y-352186D01*
X377691D01*
Y-352219D01*
X377594D01*
Y-352251D01*
X377530D01*
Y-352283D01*
X377433D01*
Y-352315D01*
X377336D01*
Y-352348D01*
X377239D01*
Y-352380D01*
X377143D01*
Y-352412D01*
X377046D01*
Y-352444D01*
X376949D01*
Y-352477D01*
X376852D01*
Y-352509D01*
X376723D01*
Y-352541D01*
X376626D01*
Y-352573D01*
X376497D01*
Y-352606D01*
X376368D01*
Y-352638D01*
X376239D01*
Y-352670D01*
X376110D01*
Y-352702D01*
X375949D01*
Y-352735D01*
X375820D01*
Y-352767D01*
X375658D01*
Y-352799D01*
X375465D01*
Y-352832D01*
X375271D01*
Y-352864D01*
X375045D01*
Y-352896D01*
X374852D01*
Y-352928D01*
X374465D01*
Y-352961D01*
X374110D01*
Y-352993D01*
X374078D01*
Y-352961D01*
X374013D01*
Y-352993D01*
X372755D01*
Y-352961D01*
X372271D01*
Y-352928D01*
X371981D01*
Y-352896D01*
X371723D01*
Y-352864D01*
X371497D01*
Y-352832D01*
X371303D01*
Y-352799D01*
X371110D01*
Y-352767D01*
X370948D01*
Y-352735D01*
X370787D01*
Y-352702D01*
X370658D01*
Y-352670D01*
X370529D01*
Y-352638D01*
X370400D01*
Y-352606D01*
X370271D01*
Y-352573D01*
X370142D01*
Y-352541D01*
X370045D01*
Y-352509D01*
X369916D01*
Y-352477D01*
X369819D01*
Y-352444D01*
X369722D01*
Y-352412D01*
X369625D01*
Y-352380D01*
X369529D01*
Y-352348D01*
X369432D01*
Y-352315D01*
X369335D01*
Y-352283D01*
X369238D01*
Y-352251D01*
X369142D01*
Y-352219D01*
X369077D01*
Y-352186D01*
X368980D01*
Y-352154D01*
X368916D01*
Y-352122D01*
X368819D01*
Y-352090D01*
X368754D01*
Y-352057D01*
X368658D01*
Y-352025D01*
X368593D01*
Y-351993D01*
X368529D01*
Y-351960D01*
X368464D01*
Y-351928D01*
X368367D01*
Y-351896D01*
X368303D01*
Y-351864D01*
X368238D01*
Y-351831D01*
X368174D01*
Y-351799D01*
X368109D01*
Y-351767D01*
X368045D01*
Y-351735D01*
X367980D01*
Y-351702D01*
X367916D01*
Y-351670D01*
X367851D01*
Y-351638D01*
X367787D01*
Y-351606D01*
X367722D01*
Y-351573D01*
X367657D01*
Y-351541D01*
X367593D01*
Y-351509D01*
X367561D01*
Y-351477D01*
X367496D01*
Y-351444D01*
X367432D01*
Y-351412D01*
X367367D01*
Y-351380D01*
X367303D01*
Y-351347D01*
X367270D01*
Y-351315D01*
X367206D01*
Y-351283D01*
X367141D01*
Y-351251D01*
X367109D01*
Y-351218D01*
X367044D01*
Y-351186D01*
X367012D01*
Y-351154D01*
X366948D01*
Y-351122D01*
X366883D01*
Y-351089D01*
X366851D01*
Y-351057D01*
X366786D01*
Y-351025D01*
X366754D01*
Y-350993D01*
X366690D01*
Y-350960D01*
X366657D01*
Y-350928D01*
X366593D01*
Y-350896D01*
X366561D01*
Y-350864D01*
X366496D01*
Y-350831D01*
X366464D01*
Y-350799D01*
X366399D01*
Y-350767D01*
X366367D01*
Y-350734D01*
X366335D01*
Y-350702D01*
X366270D01*
Y-350670D01*
X366238D01*
Y-350638D01*
X366206D01*
Y-350606D01*
X366141D01*
Y-350573D01*
X366109D01*
Y-350541D01*
X366077D01*
Y-350509D01*
X366012D01*
Y-350476D01*
X365980D01*
Y-350444D01*
X365948D01*
Y-350412D01*
X365883D01*
Y-350380D01*
X365851D01*
Y-350347D01*
X365819D01*
Y-350315D01*
X365786D01*
Y-350283D01*
X365722D01*
Y-350251D01*
X365689D01*
Y-350218D01*
X365657D01*
Y-350186D01*
X365625D01*
Y-350154D01*
X365593D01*
Y-350121D01*
X365528D01*
Y-350089D01*
X365496D01*
Y-350057D01*
X365464D01*
Y-350025D01*
X365431D01*
Y-349992D01*
X365399D01*
Y-349960D01*
X365367D01*
Y-349928D01*
X365335D01*
Y-349896D01*
X365270D01*
Y-349863D01*
X365238D01*
Y-349831D01*
X365206D01*
Y-349799D01*
X365173D01*
Y-349767D01*
X365141D01*
Y-349734D01*
X365109D01*
Y-349702D01*
X365076D01*
Y-349670D01*
X365044D01*
Y-349638D01*
X365012D01*
Y-349605D01*
X364980D01*
Y-349573D01*
X364948D01*
Y-349541D01*
X364915D01*
Y-349509D01*
X364883D01*
Y-349476D01*
X364851D01*
Y-349444D01*
X364818D01*
Y-349412D01*
X364786D01*
Y-349379D01*
X364754D01*
Y-349347D01*
X364722D01*
Y-349315D01*
X364689D01*
Y-349283D01*
X364657D01*
Y-349251D01*
X364625D01*
Y-349218D01*
X364593D01*
Y-349186D01*
X364560D01*
Y-349154D01*
X364528D01*
Y-349121D01*
X364496D01*
Y-349089D01*
X364464D01*
Y-349057D01*
X364431D01*
Y-349025D01*
X364399D01*
Y-348992D01*
Y-348960D01*
X364367D01*
Y-348928D01*
X364335D01*
Y-348896D01*
X364302D01*
Y-348863D01*
X364270D01*
Y-348831D01*
X364238D01*
Y-348799D01*
X364206D01*
Y-348766D01*
X364173D01*
Y-348734D01*
Y-348702D01*
X364141D01*
Y-348670D01*
X364109D01*
Y-348638D01*
X364076D01*
Y-348605D01*
X364044D01*
Y-348573D01*
X364012D01*
Y-348541D01*
Y-348508D01*
X363980D01*
Y-348476D01*
X363947D01*
Y-348444D01*
X363915D01*
Y-348412D01*
X363883D01*
Y-348379D01*
Y-348347D01*
X363851D01*
Y-348315D01*
X363818D01*
Y-348283D01*
X363786D01*
Y-348250D01*
Y-348218D01*
X363754D01*
Y-348186D01*
X363721D01*
Y-348154D01*
X363689D01*
Y-348121D01*
Y-348089D01*
X363657D01*
Y-348057D01*
X363625D01*
Y-348025D01*
X363593D01*
Y-347992D01*
Y-347960D01*
X363560D01*
Y-347928D01*
X363528D01*
Y-347896D01*
X363496D01*
Y-347863D01*
Y-347831D01*
X363463D01*
Y-347799D01*
X363431D01*
Y-347766D01*
Y-347734D01*
X363399D01*
Y-347702D01*
X363367D01*
Y-347670D01*
Y-347637D01*
X363334D01*
Y-347605D01*
X363302D01*
Y-347573D01*
Y-347541D01*
X363270D01*
Y-347508D01*
X363238D01*
Y-347476D01*
Y-347444D01*
X363205D01*
Y-347411D01*
X363173D01*
Y-347379D01*
Y-347347D01*
X363141D01*
Y-347315D01*
Y-347283D01*
X363109D01*
Y-347250D01*
X363076D01*
Y-347218D01*
Y-347186D01*
X363044D01*
Y-347153D01*
X363012D01*
Y-347121D01*
Y-347089D01*
X362980D01*
Y-347057D01*
Y-347024D01*
X362947D01*
Y-346992D01*
Y-346960D01*
X362915D01*
Y-346928D01*
X362883D01*
Y-346895D01*
Y-346863D01*
X362850D01*
Y-346831D01*
Y-346799D01*
X362818D01*
Y-346766D01*
Y-346734D01*
X362786D01*
Y-346702D01*
X362754D01*
Y-346670D01*
Y-346637D01*
X362721D01*
Y-346605D01*
Y-346573D01*
X362689D01*
Y-346540D01*
Y-346508D01*
X362657D01*
Y-346476D01*
Y-346444D01*
X362625D01*
Y-346411D01*
Y-346379D01*
X362592D01*
Y-346347D01*
Y-346315D01*
X362560D01*
Y-346282D01*
Y-346250D01*
X362528D01*
Y-346218D01*
Y-346186D01*
X362496D01*
Y-346153D01*
Y-346121D01*
X362463D01*
Y-346089D01*
Y-346057D01*
X362431D01*
Y-346024D01*
Y-345992D01*
X362399D01*
Y-345960D01*
Y-345928D01*
X362367D01*
Y-345895D01*
Y-345863D01*
Y-345831D01*
X362334D01*
Y-345798D01*
Y-345766D01*
X362302D01*
Y-345734D01*
Y-345702D01*
X362270D01*
Y-345669D01*
Y-345637D01*
Y-345605D01*
X362238D01*
Y-345573D01*
Y-345540D01*
X362205D01*
Y-345508D01*
Y-345476D01*
X362173D01*
Y-345444D01*
Y-345411D01*
Y-345379D01*
X362141D01*
Y-345347D01*
Y-345315D01*
X362108D01*
Y-345282D01*
Y-345250D01*
Y-345218D01*
X362076D01*
Y-345185D01*
Y-345153D01*
Y-345121D01*
X362044D01*
Y-345089D01*
Y-345056D01*
X362012D01*
Y-345024D01*
Y-344992D01*
Y-344960D01*
X361979D01*
Y-344927D01*
Y-344895D01*
Y-344863D01*
X361947D01*
Y-344831D01*
Y-344798D01*
Y-344766D01*
X361915D01*
Y-344734D01*
Y-344702D01*
Y-344669D01*
X361883D01*
Y-344637D01*
Y-344605D01*
Y-344572D01*
X361850D01*
Y-344540D01*
Y-344508D01*
Y-344476D01*
X361818D01*
Y-344443D01*
Y-344411D01*
Y-344379D01*
X361786D01*
Y-344347D01*
Y-344314D01*
Y-344282D01*
Y-344250D01*
X361754D01*
Y-344218D01*
Y-344185D01*
Y-344153D01*
X361721D01*
Y-344121D01*
Y-344089D01*
Y-344056D01*
Y-344024D01*
X361689D01*
Y-343992D01*
Y-343959D01*
Y-343927D01*
Y-343895D01*
X361657D01*
Y-343863D01*
Y-343830D01*
Y-343798D01*
Y-343766D01*
X361625D01*
Y-343734D01*
Y-343701D01*
Y-343669D01*
Y-343637D01*
X361592D01*
Y-343605D01*
Y-343572D01*
Y-343540D01*
Y-343508D01*
Y-343476D01*
X361560D01*
Y-343443D01*
Y-343411D01*
Y-343379D01*
Y-343347D01*
Y-343314D01*
X361528D01*
Y-343282D01*
Y-343250D01*
Y-343217D01*
Y-343185D01*
Y-343153D01*
X361495D01*
Y-343121D01*
Y-343089D01*
Y-343056D01*
Y-343024D01*
Y-342992D01*
X361463D01*
Y-342959D01*
Y-342927D01*
Y-342895D01*
Y-342863D01*
Y-342830D01*
Y-342798D01*
X361431D01*
Y-342766D01*
Y-342734D01*
Y-342701D01*
Y-342669D01*
Y-342637D01*
Y-342604D01*
Y-342572D01*
X361399D01*
Y-342540D01*
Y-342508D01*
Y-342476D01*
Y-342443D01*
Y-342411D01*
Y-342379D01*
Y-342346D01*
Y-342314D01*
X361366D01*
Y-342282D01*
Y-342250D01*
Y-342217D01*
Y-342185D01*
Y-342153D01*
Y-342121D01*
Y-342088D01*
Y-342056D01*
Y-342024D01*
Y-341992D01*
X361334D01*
Y-341959D01*
Y-341927D01*
Y-341895D01*
Y-341863D01*
Y-341830D01*
Y-341798D01*
Y-341766D01*
Y-341734D01*
Y-341701D01*
Y-341669D01*
Y-341637D01*
Y-341604D01*
Y-341572D01*
Y-341540D01*
Y-341508D01*
Y-341475D01*
X361302D01*
Y-341443D01*
Y-341411D01*
Y-341379D01*
Y-341346D01*
Y-341314D01*
Y-341282D01*
D02*
G37*
%LPD*%
G36*
X387950Y-342992D02*
X388015D01*
Y-343024D01*
Y-343056D01*
Y-343089D01*
Y-343121D01*
Y-343153D01*
Y-343185D01*
Y-343217D01*
Y-343250D01*
Y-343282D01*
Y-343314D01*
Y-343347D01*
Y-343379D01*
Y-343411D01*
Y-343443D01*
Y-343476D01*
Y-343508D01*
Y-343540D01*
Y-343572D01*
Y-343605D01*
Y-343637D01*
Y-343669D01*
Y-343701D01*
Y-343734D01*
Y-343766D01*
Y-343798D01*
Y-343830D01*
Y-343863D01*
Y-343895D01*
Y-343927D01*
Y-343959D01*
Y-343992D01*
Y-344024D01*
Y-344056D01*
Y-344089D01*
Y-344121D01*
Y-344153D01*
Y-344185D01*
Y-344218D01*
Y-344250D01*
Y-344282D01*
Y-344314D01*
Y-344347D01*
Y-344379D01*
Y-344411D01*
Y-344443D01*
Y-344476D01*
Y-344508D01*
Y-344540D01*
Y-344572D01*
Y-344605D01*
Y-344637D01*
Y-344669D01*
Y-344702D01*
Y-344734D01*
Y-344766D01*
Y-344798D01*
Y-344831D01*
Y-344863D01*
Y-344895D01*
Y-344927D01*
Y-344960D01*
Y-344992D01*
Y-345024D01*
Y-345056D01*
Y-345089D01*
Y-345121D01*
Y-345153D01*
Y-345185D01*
Y-345218D01*
Y-345250D01*
Y-345282D01*
Y-345315D01*
Y-345347D01*
Y-345379D01*
Y-345411D01*
Y-345444D01*
Y-345476D01*
Y-345508D01*
Y-345540D01*
Y-345573D01*
Y-345605D01*
Y-345637D01*
Y-345669D01*
Y-345702D01*
Y-345734D01*
Y-345766D01*
Y-345798D01*
Y-345831D01*
Y-345863D01*
Y-345895D01*
Y-345928D01*
Y-345960D01*
Y-345992D01*
Y-346024D01*
Y-346057D01*
Y-346089D01*
Y-346121D01*
Y-346153D01*
Y-346186D01*
Y-346218D01*
Y-346250D01*
Y-346282D01*
Y-346315D01*
Y-346347D01*
Y-346379D01*
Y-346411D01*
Y-346444D01*
Y-346476D01*
Y-346508D01*
Y-346540D01*
Y-346573D01*
X385660D01*
Y-346540D01*
Y-346508D01*
Y-346476D01*
Y-346444D01*
Y-346411D01*
Y-346379D01*
Y-346347D01*
Y-346315D01*
Y-346282D01*
Y-346250D01*
Y-346218D01*
Y-346186D01*
Y-346153D01*
Y-346121D01*
Y-346089D01*
Y-346057D01*
Y-346024D01*
Y-345992D01*
Y-345960D01*
Y-345928D01*
Y-345895D01*
Y-345863D01*
Y-345831D01*
Y-345798D01*
Y-345766D01*
Y-345734D01*
Y-345702D01*
Y-345669D01*
Y-345637D01*
Y-345605D01*
Y-345573D01*
Y-345540D01*
Y-345508D01*
Y-345476D01*
Y-345444D01*
Y-345411D01*
Y-345379D01*
Y-345347D01*
Y-345315D01*
Y-345282D01*
Y-345250D01*
Y-345218D01*
Y-345185D01*
Y-345153D01*
Y-345121D01*
Y-345089D01*
Y-345056D01*
Y-345024D01*
Y-344992D01*
Y-344960D01*
Y-344927D01*
Y-344895D01*
Y-344863D01*
Y-344831D01*
Y-344798D01*
Y-344766D01*
Y-344734D01*
Y-344702D01*
Y-344669D01*
Y-344637D01*
Y-344605D01*
Y-344572D01*
Y-344540D01*
Y-344508D01*
Y-344476D01*
Y-344443D01*
Y-344411D01*
Y-344379D01*
Y-344347D01*
Y-344314D01*
Y-344282D01*
Y-344250D01*
Y-344218D01*
Y-344185D01*
Y-344153D01*
Y-344121D01*
Y-344089D01*
Y-344056D01*
Y-344024D01*
Y-343992D01*
Y-343959D01*
Y-343927D01*
Y-343895D01*
Y-343863D01*
Y-343830D01*
Y-343798D01*
Y-343766D01*
Y-343734D01*
Y-343701D01*
Y-343669D01*
Y-343637D01*
Y-343605D01*
Y-343572D01*
Y-343540D01*
Y-343508D01*
Y-343476D01*
Y-343443D01*
Y-343411D01*
Y-343379D01*
Y-343347D01*
Y-343314D01*
Y-343282D01*
Y-343250D01*
Y-343217D01*
Y-343185D01*
Y-343153D01*
Y-343121D01*
Y-343089D01*
Y-343056D01*
Y-343024D01*
Y-342992D01*
X385692D01*
Y-342959D01*
X385724D01*
Y-342992D01*
X387821D01*
Y-342959D01*
X387853D01*
Y-342992D01*
X387918D01*
Y-342959D01*
X387950D01*
Y-342992D01*
D02*
G37*
G36*
X381143Y-342927D02*
Y-342959D01*
Y-342992D01*
Y-343024D01*
Y-343056D01*
Y-343089D01*
Y-343121D01*
Y-343153D01*
Y-343185D01*
Y-343217D01*
Y-343250D01*
Y-343282D01*
Y-343314D01*
Y-343347D01*
Y-343379D01*
Y-343411D01*
Y-343443D01*
Y-343476D01*
Y-343508D01*
Y-343540D01*
Y-343572D01*
Y-343605D01*
Y-343637D01*
Y-343669D01*
Y-343701D01*
Y-343734D01*
Y-343766D01*
Y-343798D01*
Y-343830D01*
Y-343863D01*
Y-343895D01*
Y-343927D01*
Y-343959D01*
Y-343992D01*
Y-344024D01*
Y-344056D01*
Y-344089D01*
Y-344121D01*
Y-344153D01*
Y-344185D01*
Y-344218D01*
Y-344250D01*
Y-344282D01*
Y-344314D01*
Y-344347D01*
Y-344379D01*
Y-344411D01*
Y-344443D01*
Y-344476D01*
Y-344508D01*
Y-344540D01*
Y-344572D01*
Y-344605D01*
X378723D01*
Y-344572D01*
Y-344540D01*
Y-344508D01*
Y-344476D01*
Y-344443D01*
Y-344411D01*
Y-344379D01*
Y-344347D01*
Y-344314D01*
Y-344282D01*
Y-344250D01*
Y-344218D01*
Y-344185D01*
Y-344153D01*
Y-344121D01*
Y-344089D01*
Y-344056D01*
Y-344024D01*
Y-343992D01*
Y-343959D01*
Y-343927D01*
Y-343895D01*
Y-343863D01*
Y-343830D01*
Y-343798D01*
Y-343766D01*
Y-343734D01*
Y-343701D01*
Y-343669D01*
Y-343637D01*
Y-343605D01*
Y-343572D01*
Y-343540D01*
Y-343508D01*
Y-343476D01*
Y-343443D01*
Y-343411D01*
Y-343379D01*
Y-343347D01*
Y-343314D01*
Y-343282D01*
Y-343250D01*
Y-343217D01*
Y-343185D01*
Y-343153D01*
Y-343121D01*
Y-343089D01*
Y-343056D01*
Y-343024D01*
Y-342992D01*
Y-342959D01*
Y-342927D01*
Y-342895D01*
X381143D01*
Y-342927D01*
D02*
G37*
D12*
X268922Y-392732D02*
G03*
X268428Y-391417I-2000J-0D01*
G01*
X218189Y-393476D02*
G03*
X217391Y-391877I-2000J-0D01*
G01*
X159134Y-404100D02*
Y-391118D01*
X155035Y-389506D02*
X156116Y-388425D01*
X155197Y-389669D02*
X156441Y-388425D01*
X152964Y-389506D02*
X155035D01*
X151260Y-404100D02*
Y-391210D01*
X155197Y-404100D02*
Y-389669D01*
X561811Y-292520D02*
X562598Y-291732D01*
Y-286614D01*
X551884Y-291732D02*
X553543D01*
X558661Y-286614D01*
X564665Y-284547D02*
Y-281496D01*
X562598Y-286614D02*
X564665Y-284547D01*
X558661Y-286614D02*
Y-279528D01*
X559744Y-278445D01*
X562205D01*
X588976Y-302756D02*
X589291Y-303071D01*
Y-316535D02*
Y-303071D01*
X579291Y-303386D02*
X579528Y-303150D01*
X579291Y-316535D02*
Y-303386D01*
X106299Y-263632D02*
Y-254331D01*
X90041Y-238072D02*
X106299Y-254331D01*
X78772Y-238072D02*
X90041D01*
X156116Y-388425D02*
X156441D01*
X151260Y-391210D02*
X152964Y-389506D01*
X163006Y-404035D02*
Y-390730D01*
Y-404035D02*
X163071Y-404100D01*
X268922Y-401057D02*
Y-392732D01*
Y-392732D01*
X268922D02*
X268922D01*
X281201Y-404080D02*
Y-390009D01*
X251378D02*
X253223Y-391854D01*
X241811Y-404100D02*
Y-397250D01*
X218189Y-393476D02*
Y-393476D01*
X226002Y-404039D02*
Y-390783D01*
X218189Y-393476D02*
X218189D01*
Y-404100D02*
Y-393476D01*
X206213Y-403935D02*
Y-391498D01*
X174882Y-404100D02*
Y-390659D01*
X251456Y-390009D02*
X255217D01*
X251378D02*
X251456D01*
X267204D02*
X268428Y-391417D01*
X216162Y-390947D02*
X217391Y-391877D01*
X281181Y-404100D02*
X281201Y-404080D01*
X235144Y-390416D02*
X240536D01*
X235230Y-390502D02*
X236624D01*
X235144Y-390416D02*
X235230Y-390502D01*
X241707Y-397146D02*
X241811Y-397250D01*
X240536Y-390416D02*
X241707Y-391587D01*
X268922Y-401057D02*
X269291Y-401427D01*
X226002Y-390783D02*
X226063Y-390722D01*
X257111Y-401057D02*
Y-391904D01*
X206213Y-403935D02*
X206378Y-404100D01*
X255217Y-390009D02*
X257111Y-391904D01*
X253223Y-401107D02*
X253543Y-401427D01*
X253223Y-401107D02*
Y-391854D01*
X205315Y-390600D02*
X206213Y-391498D01*
X236624Y-390502D02*
X237795Y-391673D01*
X241707Y-401402D02*
X241732Y-401427D01*
X241707Y-401402D02*
Y-397146D01*
X237795Y-401427D02*
Y-391673D01*
X174882Y-390659D02*
X174941Y-390600D01*
X202441D02*
X205315D01*
X257111Y-401057D02*
X257480Y-401427D01*
X241707Y-397146D02*
Y-391587D01*
X89567Y-90797D02*
X89961Y-90403D01*
X88976Y-90797D02*
X89567D01*
X114075Y-73769D02*
X114458Y-73386D01*
X118166D02*
X118908Y-72644D01*
X122877D02*
X123031Y-72490D01*
X118908Y-72644D02*
X122877D01*
X114458Y-73386D02*
X118166D01*
X123031Y-72490D02*
X131693D01*
X269653Y-112222D02*
X274555D01*
X276280Y-113946D02*
X279528D01*
X269488Y-112057D02*
Y-106348D01*
X269685Y-106151D01*
X274555Y-112222D02*
X276280Y-113946D01*
X269488Y-112057D02*
X269653Y-112222D01*
X78740Y-238041D02*
X78772Y-238072D01*
X131693Y-72490D02*
X131890Y-72687D01*
X178740Y-401427D02*
Y-389222D01*
X98425Y-92568D02*
X98819Y-92175D01*
X104528D01*
X106299Y-263632D02*
X110709D01*
X89961Y-90403D02*
X94488D01*
X95587Y-91502D01*
X97358D02*
X98425Y-92568D01*
X95587Y-91502D02*
X97358D01*
X83661Y-85482D02*
Y-75639D01*
Y-85482D02*
X88976Y-90797D01*
X74036Y-73671D02*
X81693D01*
X83661Y-75639D01*
X91634Y-73769D02*
X114075D01*
X91536Y-73671D02*
X91634Y-73769D01*
X179921Y-388041D02*
X182677D01*
X178819Y-404100D02*
X179126Y-403793D01*
X178740Y-389222D02*
X179921Y-388041D01*
X690534Y-294457D02*
X694033D01*
X695199Y-293290D01*
X694033Y-292124D01*
X695199Y-290958D01*
X694033Y-289791D01*
X690534D01*
Y-287459D02*
X694033D01*
X695199Y-286293D01*
X694033Y-285126D01*
X695199Y-283960D01*
X694033Y-282794D01*
X690534D01*
Y-280461D02*
X694033D01*
X695199Y-279295D01*
X694033Y-278129D01*
X695199Y-276962D01*
X694033Y-275796D01*
X690534D01*
X695199Y-273464D02*
X694033D01*
Y-272297D01*
X695199D01*
Y-273464D01*
X689367Y-266466D02*
X690534D01*
Y-267632D01*
Y-265299D01*
Y-266466D01*
X694033D01*
X695199Y-265299D01*
Y-261801D02*
Y-259468D01*
Y-260634D01*
X690534D01*
Y-261801D01*
X695199Y-255969D02*
X690534D01*
Y-254803D01*
X691700Y-253637D01*
X695199D01*
X691700D01*
X690534Y-252470D01*
X691700Y-251304D01*
X695199D01*
Y-248971D02*
Y-246639D01*
Y-247805D01*
X690534D01*
Y-248971D01*
X695199Y-243140D02*
X690534D01*
Y-239641D01*
X691700Y-238475D01*
X695199D01*
X697532Y-233810D02*
Y-232643D01*
X696365Y-231477D01*
X690534D01*
Y-234976D01*
X691700Y-236142D01*
X694033D01*
X695199Y-234976D01*
Y-231477D01*
X690534Y-224479D02*
Y-227978D01*
X691700Y-229145D01*
X694033D01*
X695199Y-227978D01*
Y-224479D01*
X690534Y-220980D02*
Y-218648D01*
X691700Y-217482D01*
X695199D01*
Y-220980D01*
X694033Y-222147D01*
X692866Y-220980D01*
Y-217482D01*
X690534Y-215149D02*
X695199D01*
X692866D01*
X691700Y-213983D01*
X690534Y-212816D01*
Y-211650D01*
X688201Y-203486D02*
X695199D01*
Y-206985D01*
X694033Y-208151D01*
X691700D01*
X690534Y-206985D01*
Y-203486D01*
X695199Y-201153D02*
X694033D01*
Y-199987D01*
X695199D01*
Y-201153D01*
X690534Y-190657D02*
Y-194156D01*
X691700Y-195322D01*
X694033D01*
X695199Y-194156D01*
Y-190657D01*
Y-187158D02*
Y-184825D01*
X694033Y-183659D01*
X691700D01*
X690534Y-184825D01*
Y-187158D01*
X691700Y-188324D01*
X694033D01*
X695199Y-187158D01*
Y-181327D02*
X690534D01*
Y-180160D01*
X691700Y-178994D01*
X695199D01*
X691700D01*
X690534Y-177828D01*
X691700Y-176661D01*
X695199D01*
D14*
X72013Y-123031D02*
X82480D01*
X234646Y-122835D02*
Y-121260D01*
Y-124409D02*
Y-122835D01*
X256398Y-111501D02*
X256897Y-112001D01*
X256398Y-111501D02*
Y-104724D01*
X664961Y-325984D02*
X667126D01*
X669882Y-323228D01*
X234646Y-124409D02*
X240945Y-130709D01*
X242618D01*
X232785Y-119399D02*
X234646Y-121260D01*
X227756Y-119399D02*
X232785D01*
X256897Y-112001D02*
X256988Y-112092D01*
Y-115354D02*
Y-112092D01*
X243348Y-108268D02*
X244664Y-106952D01*
X239764Y-108268D02*
X243348D01*
X609428Y-92499D02*
X609449Y-92520D01*
X609407D02*
X609428Y-92499D01*
X610236Y-93307D02*
X614567D01*
X609449Y-92520D02*
X610236Y-93307D01*
X609449Y-92520D02*
X609449D01*
X609055D02*
X609407D01*
X629134Y-102756D02*
X629724Y-102165D01*
Y-99606D01*
X629331Y-86268D02*
X631814Y-83784D01*
X629331Y-86614D02*
Y-86268D01*
X628998Y-90239D02*
X629101Y-90137D01*
X628998Y-93307D02*
Y-90239D01*
X616535Y-84646D02*
X617126Y-85236D01*
Y-90158D02*
Y-85236D01*
X616929Y-100000D02*
X617126Y-99803D01*
Y-96457D01*
X571260Y-93307D02*
X581693D01*
X569291Y-91339D02*
X571260Y-93307D01*
X584252Y-99604D02*
X584763Y-100116D01*
X584252Y-99604D02*
Y-96457D01*
X585646Y-88764D02*
X588189Y-86221D01*
X588976D01*
X584252Y-90158D02*
X584630Y-89780D01*
Y-89350D01*
X585216Y-88764D01*
X585646D01*
X600136Y-87795D02*
X600394D01*
X597244Y-90687D02*
X600136Y-87795D01*
X666929Y-98032D02*
X667717Y-97244D01*
Y-94488D01*
X662539Y-107066D02*
X662683Y-107210D01*
Y-110630D02*
Y-107210D01*
X695140Y-64910D02*
X696762Y-63288D01*
X695140Y-66142D02*
Y-64910D01*
X685716Y-22157D02*
X685827Y-22268D01*
Y-25886D02*
Y-22268D01*
X679517Y-26553D02*
X679528Y-26563D01*
Y-29921D02*
Y-26563D01*
X693915Y-33393D02*
X694095Y-33573D01*
Y-36492D02*
Y-33573D01*
X686614Y-33557D02*
X686728Y-33442D01*
X686614Y-36356D02*
Y-33557D01*
X675591Y-73026D02*
X675926Y-72691D01*
X675591Y-76614D02*
Y-73026D01*
X660719Y-75726D02*
X662598Y-77606D01*
Y-79370D02*
Y-77606D01*
X688091Y-61319D02*
X688976Y-62205D01*
X694095D01*
X693926Y-53150D02*
X693977Y-53201D01*
X685433Y-53150D02*
X693926D01*
X688091Y-61319D02*
Y-58723D01*
X676378Y-83858D02*
X681102D01*
X567691Y-109449D02*
X569092Y-108048D01*
X565748Y-109449D02*
X567691D01*
X546386Y-109024D02*
X546417Y-109055D01*
X550394D01*
X547244Y-144488D02*
X548681Y-143051D01*
Y-137008D01*
X524409Y-135827D02*
X529921Y-141339D01*
X532520D01*
X531801Y-127495D02*
X531890Y-127584D01*
Y-133858D02*
Y-127584D01*
X573524Y-147244D02*
X576772Y-150492D01*
X562598Y-147244D02*
X573524D01*
X558681Y-143327D02*
X562598Y-147244D01*
X558681Y-143327D02*
Y-137008D01*
X608563Y-236122D02*
Y-232283D01*
Y-236122D02*
X608661Y-236221D01*
X572441Y-227165D02*
X574016D01*
X570866D02*
X572441D01*
X567717Y-224016D02*
X570866Y-227165D01*
X574016D02*
X575840Y-225341D01*
X560236Y-201279D02*
X566142D01*
X639764Y-283858D02*
Y-278482D01*
X640293Y-277953D01*
X554724Y-294882D02*
X557087Y-292520D01*
X558137D01*
X561811D02*
X562205Y-292913D01*
X565354D01*
X582874Y-294291D02*
X584252Y-295669D01*
X581496Y-292913D02*
X582874Y-294291D01*
X672047Y-250000D02*
X673228Y-251181D01*
X672047Y-250000D02*
Y-242126D01*
X667717D02*
X678996Y-230847D01*
X679921D01*
X675197Y-242126D02*
X679921Y-237402D01*
Y-235846D01*
X638189Y-220866D02*
X638583Y-221260D01*
Y-233071D02*
Y-221260D01*
Y-233071D02*
X641358Y-235846D01*
X658661D01*
X650394Y-216142D02*
Y-210236D01*
X646457Y-220079D02*
X650394Y-216142D01*
X642913Y-220079D02*
X646457D01*
X640551Y-222441D02*
X642913Y-220079D01*
X640551Y-231890D02*
Y-222441D01*
Y-231890D02*
X642126Y-233465D01*
X651968D01*
X654587Y-230847D01*
X658661D01*
X652106Y-225847D02*
X658661D01*
X650394Y-227559D02*
X652106Y-225847D01*
X650000Y-231102D02*
X650394Y-230709D01*
Y-227559D01*
X643701Y-228512D02*
X646434Y-231245D01*
X643701Y-228512D02*
Y-227323D01*
X602362Y-229823D02*
Y-227953D01*
Y-229823D02*
X604823Y-232283D01*
X549298Y-191988D02*
X553839Y-196528D01*
Y-200394D02*
Y-196528D01*
X683858Y-301969D02*
Y-298538D01*
X683716D02*
X683858D01*
X672047Y-307500D02*
X680709D01*
Y-306299D01*
X672047Y-302500D02*
X680709D01*
Y-301969D01*
X643307Y-297638D02*
X650787D01*
X637795D02*
X643307D01*
X650787D02*
Y-297500D01*
X634862Y-236437D02*
X637008Y-238583D01*
X634862Y-236437D02*
Y-233858D01*
X626161Y-233465D02*
X626555Y-233858D01*
X619882Y-233465D02*
X626161D01*
X608661Y-242126D02*
Y-241316D01*
X610249Y-239728D01*
X610285Y-239764D02*
X614961D01*
X610249Y-239728D02*
X610285Y-239764D01*
X618898D02*
X619882Y-238779D01*
Y-233465D01*
X612795Y-232283D02*
X613976Y-233465D01*
X608563Y-232283D02*
X612795D01*
X590551Y-242520D02*
X590748Y-242717D01*
X599213D01*
Y-236811D02*
Y-231594D01*
X586537Y-234843D02*
X587290D01*
X589848Y-237402D01*
X592829D02*
X594488Y-235742D01*
Y-231398D01*
X546850Y-213779D02*
X553543Y-220473D01*
Y-221391D02*
Y-220473D01*
X548819Y-196063D02*
X550098Y-197343D01*
Y-200394D02*
Y-197343D01*
X566142Y-201279D02*
X566240D01*
X554724Y-207874D02*
X555512D01*
X557480Y-209842D01*
Y-211024D02*
Y-209842D01*
Y-211024D02*
X559585Y-213128D01*
X562598D01*
X549213Y-207874D02*
X552854Y-211516D01*
X554724D01*
X564567Y-205512D02*
X566142D01*
X567323Y-206693D01*
Y-208268D02*
Y-206693D01*
Y-208268D02*
X571216Y-212161D01*
X573379D01*
X564567Y-209055D02*
X570232Y-214720D01*
X573379D01*
X554724Y-215256D02*
X555475Y-216006D01*
X562598D01*
X563128Y-216535D01*
X568898D01*
X569641Y-217279D01*
X573379D01*
X566142Y-197244D02*
X569291Y-194095D01*
X566142Y-197933D02*
Y-197244D01*
X565846Y-197638D02*
X566142Y-197933D01*
X560236Y-197638D02*
X565846D01*
X553839Y-200394D02*
X555020Y-201575D01*
X560236D01*
X566240Y-201279D02*
X570866Y-205906D01*
Y-208661D02*
Y-205906D01*
Y-208661D02*
X571806Y-209602D01*
X573379D01*
X580958Y-199357D02*
X581496Y-198819D01*
X580958Y-203992D02*
Y-199357D01*
X573622Y-198819D02*
X575840Y-201037D01*
Y-203992D02*
Y-201037D01*
X564961Y-226772D02*
X567717Y-224016D01*
X555250Y-226772D02*
X564961D01*
X553543Y-225065D02*
X555250Y-226772D01*
X564876Y-220079D02*
X567717D01*
X563301Y-221654D02*
X564876Y-220079D01*
X567717D02*
X567957Y-219838D01*
X573379D01*
X575840Y-225341D02*
Y-222889D01*
X583517Y-220685D02*
X588793Y-215409D01*
X583517Y-222889D02*
Y-220685D01*
X577559Y-289567D02*
X577658D01*
X581791Y-285433D01*
X545128Y-280872D02*
X546079Y-279921D01*
X548561D01*
X544909Y-287437D02*
X547306Y-285039D01*
X548228D01*
X545276Y-294094D02*
X547638Y-291732D01*
X548116D01*
X544488Y-265748D02*
X544685Y-265945D01*
X548327D01*
X594095Y-287486D02*
Y-285335D01*
X591732Y-289848D02*
X594095Y-287486D01*
X575394Y-291732D02*
X577559Y-289567D01*
X569488Y-287283D02*
X569548Y-287223D01*
X569488Y-291732D02*
Y-287283D01*
X594179Y-292829D02*
X595276Y-291732D01*
X591732Y-292829D02*
X594179D01*
X581496Y-289862D02*
X581595Y-289764D01*
X581496Y-292913D02*
Y-289862D01*
X584252Y-295669D02*
X597441D01*
X611024Y-293307D02*
X612598Y-291732D01*
X607874Y-293307D02*
X611024D01*
X607874Y-297244D02*
X614350D01*
X615531Y-296063D01*
X603346Y-295669D02*
X604921Y-297244D01*
X607874D01*
X627165Y-296063D02*
X627559Y-296457D01*
X623839Y-296063D02*
X627165D01*
X572342Y-279291D02*
X577618Y-274016D01*
X572342Y-281496D02*
Y-279291D01*
X488583Y-132283D02*
X489961Y-130905D01*
Y-128593D01*
X505669Y-130551D02*
X506299Y-129921D01*
X505669Y-133465D02*
Y-130551D01*
X498081Y-125394D02*
X499701D01*
X501630Y-127323D01*
X502756D01*
X506197D02*
X506207Y-127333D01*
X502756Y-127323D02*
X506197D01*
X498782Y-119488D02*
X501669Y-116601D01*
X498081Y-119488D02*
X498782D01*
X501357Y-116289D02*
X501669Y-116601D01*
X497835Y-116289D02*
X501357D01*
X500309Y-105737D02*
X500313Y-105734D01*
X500309Y-109843D02*
Y-105737D01*
X476772Y-123622D02*
X476968Y-123425D01*
X479872D01*
X470472Y-123622D02*
X470472Y-123622D01*
X473622D01*
X335483Y-244859D02*
X337070D01*
X338362Y-243567D01*
X338525D01*
X343149Y-225168D02*
X348915D01*
X343144Y-225173D02*
X343149Y-225168D01*
X343492Y-215325D02*
X348915D01*
X343444Y-215373D02*
X343492Y-215325D01*
X431889Y-298089D02*
Y-294306D01*
X432283Y-293912D01*
Y-293750D01*
X343009Y-264538D02*
X348915D01*
X342944Y-264473D02*
X343009Y-264538D01*
X332971Y-225168D02*
X332976Y-225173D01*
X338444D01*
X348747Y-205651D02*
X348915Y-205483D01*
X343403Y-205651D02*
X348747D01*
X343222Y-254695D02*
X348915D01*
X343144Y-254773D02*
X343222Y-254695D01*
X431928Y-316492D02*
Y-311189D01*
X432144Y-310973D01*
X332971Y-215325D02*
X338792D01*
X338844Y-215273D01*
X332971Y-264538D02*
X338379D01*
X338444Y-264473D01*
X344026Y-244867D02*
X346325D01*
X342906Y-243747D02*
X344026Y-244867D01*
X342744Y-243747D02*
X342906D01*
X332971Y-205483D02*
X338734D01*
X338744Y-205473D01*
X335840Y-254673D02*
X338344D01*
X335826Y-254687D02*
X335840Y-254673D01*
X332971Y-254695D02*
X332979Y-254687D01*
X335826D01*
X338344Y-254673D02*
X338444Y-254773D01*
X639658Y-320283D02*
Y-314672D01*
X639750Y-314581D01*
X639567Y-320374D02*
X639658Y-320283D01*
X658532Y-320208D02*
Y-314696D01*
X658647Y-314581D01*
X658268Y-320473D02*
X658532Y-320208D01*
X509496Y-345229D02*
X515008D01*
X509405Y-345138D02*
X509496Y-345229D01*
X515008D02*
X515099Y-345321D01*
X509173Y-330177D02*
X510172Y-329179D01*
X515198D01*
X509011Y-330177D02*
X509173D01*
X71850Y-151575D02*
Y-147638D01*
Y-151575D02*
X76772Y-156496D01*
X81004D01*
X75787Y-127756D02*
X75787Y-127756D01*
X75787Y-131890D02*
Y-127756D01*
X87590Y-126960D02*
X88566Y-125984D01*
X94193D01*
X76772Y-135827D02*
Y-132874D01*
X75787Y-131890D02*
X76772Y-132874D01*
X671654Y-16142D02*
X671654Y-16142D01*
X89567Y-98277D02*
X89567Y-98277D01*
X98425Y-98080D02*
X98425Y-98080D01*
X87590Y-126977D02*
Y-126960D01*
X85827Y-128740D02*
X87590Y-126977D01*
X75984Y-127953D02*
X78740D01*
X75787Y-127756D02*
X75984Y-127953D01*
X79528Y-128740D02*
X82677D01*
X78740Y-127953D02*
X79528Y-128740D01*
X82677D02*
X85827D01*
X634252Y-314729D02*
X634449Y-314926D01*
X634252Y-314729D02*
Y-314567D01*
X634449Y-320374D02*
Y-314926D01*
X653150Y-320473D02*
Y-314567D01*
X509489Y-350537D02*
X515001D01*
X515099Y-350439D01*
X509391Y-350636D02*
X509489Y-350537D01*
X509160Y-335675D02*
X510537Y-334297D01*
X515198D01*
X508997Y-335675D02*
X509160D01*
X71029Y-122047D02*
X72013Y-123031D01*
X70866Y-122047D02*
X71029D01*
X82677Y-175197D02*
X86614D01*
X82677Y-175197D02*
X82677Y-175197D01*
X75787Y-232283D02*
Y-227362D01*
X72835Y-215551D02*
X73503Y-216220D01*
X68898Y-221654D02*
X68996D01*
X73503Y-217146D01*
Y-216220D01*
X69587Y-215551D02*
X72835D01*
X64139Y-221457D02*
X64336Y-221654D01*
X63976Y-221457D02*
X64139D01*
X64336Y-221654D02*
X68898D01*
X75787Y-227362D02*
X75787Y-227362D01*
X82677Y-227362D02*
X86614D01*
X63976Y-275590D02*
X68701D01*
X68898Y-275787D01*
X68996D01*
X73819Y-270965D01*
X72835Y-267717D02*
X73819Y-268701D01*
Y-270965D02*
Y-268701D01*
X69587Y-267717D02*
X72835D01*
X75787Y-285433D02*
Y-281496D01*
X83661D02*
X87598D01*
X82677Y-329724D02*
X87598D01*
X82677Y-335630D02*
X87598D01*
X74803Y-339567D02*
Y-335630D01*
X67716Y-329724D02*
X67913Y-329921D01*
X62992Y-329724D02*
X67716D01*
X68012Y-329921D02*
X69579Y-328354D01*
Y-328256D01*
X71850Y-325984D01*
Y-322436D01*
X67913Y-329921D02*
X68012D01*
X71265Y-321850D02*
X71850Y-322436D01*
X68602Y-321850D02*
X71265D01*
X71850Y-165650D02*
Y-162987D01*
X67913Y-169488D02*
X68012D01*
X71850Y-165650D01*
X68602Y-162402D02*
X71265D01*
X71850Y-162987D01*
X74803Y-179134D02*
Y-175197D01*
X63976Y-179134D02*
Y-170276D01*
X64764Y-169488D02*
X67913D01*
X63976Y-170276D02*
X64764Y-169488D01*
X26575Y-283465D02*
X26737D01*
X27131Y-283071D02*
X30709D01*
X26737Y-283465D02*
X27131Y-283071D01*
X30512Y-170438D02*
X30709Y-170635D01*
X30512Y-170438D02*
Y-170276D01*
X30709Y-175394D02*
Y-170635D01*
X-23507Y-241027D02*
X-18881D01*
X-23622Y-241142D02*
X-23507Y-241027D01*
X-18881D02*
X-18406Y-240551D01*
X-23507Y-346571D02*
X-18684D01*
X-23622Y-346457D02*
X-23507Y-346571D01*
X-18684D02*
X-18406Y-346850D01*
X-23524Y-294193D02*
X-18504D01*
X-18406Y-294094D01*
X-23622Y-294291D02*
X-23524Y-294193D01*
X-23622Y-187992D02*
X-23524Y-187894D01*
X-18504D02*
X-18406Y-187795D01*
X-23524Y-187894D02*
X-18504D01*
X-23524Y-114075D02*
X-18504D01*
X-18406Y-113976D01*
X-23622Y-114173D02*
X-23524Y-114075D01*
X-23622Y-70866D02*
X-23524Y-70768D01*
X-18504D02*
X-18406Y-70669D01*
X-23524Y-70768D02*
X-18504D01*
X82677Y-135827D02*
X85630Y-132874D01*
Y-131890D01*
X85630D01*
X89567Y-127953D02*
X94193D01*
X85630Y-131890D02*
X89567Y-127953D01*
X86614Y-123031D02*
X87598Y-124016D01*
X94193D01*
X82480Y-123031D02*
X82677Y-123228D01*
X82874Y-123031D02*
X86614D01*
X82677Y-123228D02*
X82874Y-123031D01*
D19*
X451181Y-324852D02*
G03*
X451613Y-323809I-1043J1043D01*
G01*
X439187Y-321492D02*
G03*
X439186Y-321493I3360J-3360D01*
G01*
X447244Y-324852D02*
G03*
X447676Y-323809I-1043J1043D01*
G01*
X441339Y-321309D02*
G03*
X440551Y-323210I1901J-1901D01*
G01*
X459487Y-322093D02*
G03*
X460630Y-324852I3902J0D01*
G01*
X439370Y-321309D02*
G03*
X439802Y-320266I-1043J1043D01*
G01*
X453582Y-323995D02*
G03*
X453937Y-324852I1212J0D01*
G01*
X457480D02*
G03*
X457519Y-324758I-94J94D01*
G01*
X441339Y-321309D02*
G03*
X441771Y-320265I-1044J1044D01*
G01*
X431938Y-322836D02*
G03*
X431102Y-324852I2016J-2016D01*
G01*
X439186Y-321493D02*
G03*
X437795Y-324852I3361J-3359D01*
G01*
X445288Y-322478D02*
G03*
X445708Y-321463I-1015J1015D01*
G01*
X445288Y-322478D02*
G03*
X444488Y-324408I1930J-1930D01*
G01*
X434252Y-322490D02*
G03*
X435865Y-318595I-3894J3894D01*
G01*
X434252Y-322490D02*
G03*
X433858Y-323440I950J-950D01*
G01*
X433071Y-321702D02*
G03*
X433897Y-319708I-1995J1995D01*
G01*
X441771Y-306387D02*
G03*
X442126Y-306742I355J0D01*
G01*
X439370D02*
G03*
X439802Y-306310I0J432D01*
G01*
X453582Y-306387D02*
G03*
X453937Y-306742I355J0D01*
G01*
X451181D02*
G03*
X451613Y-306310I0J432D01*
G01*
X229921Y-388679D02*
G03*
X229331Y-387253I-2016J0D01*
G01*
X246328Y-386993D02*
G03*
X246293Y-387066I432J-252D01*
G01*
X246144Y-387379D02*
G03*
X246227Y-387239I-384J320D01*
G01*
X246143Y-387382D02*
G03*
X245669Y-388680I1543J-1298D01*
G01*
X249606Y-387729D02*
G03*
X249410Y-387253I-672J0D01*
G01*
X233858Y-392616D02*
G03*
X233268Y-391191I-2016J0D01*
G01*
X232480Y-389290D02*
G03*
X233268Y-391191I2688J0D01*
G01*
X435865Y-306386D02*
G03*
X436221Y-306742I355J0D01*
G01*
X212795Y-387253D02*
G03*
X210236Y-393432I6178J-6178D01*
G01*
X215945Y-387253D02*
G03*
X214173Y-391531I4277J-4277D01*
G01*
X433465Y-306742D02*
G03*
X433897Y-306309I0J433D01*
G01*
X262006Y-387255D02*
G03*
X261417Y-388680I1428J-1424D01*
G01*
X447676Y-306386D02*
G03*
X448032Y-306742I355J0D01*
G01*
X265354Y-387729D02*
G03*
X265158Y-387253I-672J0D01*
G01*
X445276Y-306742D02*
G03*
X445708Y-306309I0J433D01*
G01*
X249641Y-403994D02*
G03*
X249685Y-404100I150J0D01*
G01*
X248741Y-401821D02*
G03*
X249685Y-404100I3223J0D01*
G01*
X232741Y-401213D02*
G03*
X233937Y-404100I4083J0D01*
G01*
X229041Y-401785D02*
G03*
X230000Y-404100I3274J0D01*
G01*
X213341Y-401901D02*
G03*
X214252Y-404100I3110J0D01*
G01*
X440551Y-324852D02*
Y-323210D01*
X459487Y-322093D02*
Y-316492D01*
X453582Y-323995D02*
Y-316492D01*
X447676Y-323809D02*
Y-316492D01*
X439186Y-321493D02*
X439187Y-321492D01*
X444488Y-324408D02*
X444488Y-324411D01*
X451613Y-323809D02*
Y-316492D01*
X444488Y-324852D02*
Y-324411D01*
X433858Y-324852D02*
Y-323440D01*
X457519Y-324758D02*
Y-316492D01*
X439187Y-321492D02*
X439370Y-321309D01*
X431938Y-322836D02*
X433071Y-321702D01*
X433897Y-319708D02*
Y-316492D01*
X435865Y-318595D02*
Y-316492D01*
X439802Y-306310D02*
Y-300548D01*
X441771Y-306387D02*
Y-300548D01*
X453582Y-306387D02*
Y-300548D01*
X451613Y-306310D02*
Y-300548D01*
X451644Y-300579D01*
X445708Y-321463D02*
Y-316492D01*
X441771Y-320265D02*
Y-316492D01*
X229921Y-401427D02*
Y-388679D01*
X246328Y-386993D02*
X246338Y-386976D01*
X246227Y-387239D02*
X246293Y-387066D01*
X246143Y-387382D02*
X246144Y-387379D01*
X245669Y-401427D02*
Y-388680D01*
X249606Y-401427D02*
Y-387729D01*
X246338Y-386976D02*
X246339Y-386975D01*
X233858Y-401427D02*
Y-392616D01*
X232480Y-389290D02*
Y-387253D01*
X439802Y-320266D02*
Y-316492D01*
X435865Y-306386D02*
Y-300548D01*
X210236Y-401427D02*
Y-393432D01*
X433897Y-306309D02*
Y-300548D01*
X214173Y-401427D02*
Y-391531D01*
X261417Y-401427D02*
Y-388680D01*
X447676Y-306386D02*
Y-300548D01*
X265354Y-401427D02*
Y-387729D01*
X445708Y-306309D02*
Y-300548D01*
X245748Y-404100D02*
X246041Y-403807D01*
X245541Y-403893D02*
X245748Y-404100D01*
X264641Y-403308D02*
X265433Y-404100D01*
X261496D02*
X262241Y-403355D01*
D24*
X199898Y-119399D02*
G03*
X199803Y-119439I0J-134D01*
G01*
X264354Y-399013D02*
G03*
X265354Y-401427I3414J0D01*
G01*
X199804Y-114517D02*
G03*
X199803Y-114517I285J-286D01*
G01*
X200088Y-114399D02*
G03*
X199804Y-114517I0J-403D01*
G01*
X670538Y-78609D02*
Y-74409D01*
Y-78609D02*
X671260Y-79331D01*
X678407Y-47577D02*
X681004D01*
X676772Y-49213D02*
X678407Y-47577D01*
X676772Y-51575D02*
Y-49213D01*
X668438Y-78609D02*
Y-74409D01*
X667717Y-79331D02*
X668438Y-78609D01*
X676772Y-57087D02*
Y-54331D01*
X678407Y-58723D02*
X681004D01*
X676772Y-57087D02*
X678407Y-58723D01*
X670388Y-87402D02*
X671273Y-88287D01*
X677570Y-89764D02*
X678353D01*
X671273Y-88287D02*
X672750Y-89764D01*
X674570D01*
Y-88826D01*
X675870D01*
Y-89764D02*
Y-88826D01*
Y-89764D02*
X677570D01*
X687521Y-68110D02*
X689466Y-66165D01*
X681398Y-68110D02*
X687521D01*
X681004Y-67716D02*
X681398Y-68110D01*
X678051Y-67716D02*
Y-67526D01*
X679647Y-65931D02*
X679739D01*
X680082Y-65587D01*
X678051Y-67526D02*
X679647Y-65931D01*
X680082Y-65587D02*
Y-64183D01*
X82284Y-111221D02*
X83268Y-110236D01*
X82284Y-112992D02*
Y-111221D01*
X80709Y-114567D02*
X82284Y-112992D01*
X74803Y-114567D02*
X80709D01*
X72047Y-111811D02*
X74803Y-114567D01*
X70866Y-111811D02*
X72047D01*
X69291Y-110236D02*
X70866Y-111811D01*
X79387Y-105653D02*
X84079D01*
X76575Y-108465D02*
X79387Y-105653D01*
X76575Y-110236D02*
Y-108465D01*
X66142Y-113779D02*
Y-110236D01*
X62986Y-112803D02*
X63963Y-113779D01*
X66142D01*
X62499Y-117255D02*
X62960Y-117717D01*
X66142D01*
X69291Y-113779D02*
X69291Y-113779D01*
X69291Y-117717D02*
Y-113779D01*
Y-117717D02*
X85039D01*
X89370Y-122047D01*
X94193D01*
X83268Y-110236D02*
X88189Y-115157D01*
Y-116929D02*
Y-115157D01*
Y-116929D02*
X91339Y-120079D01*
X94193D01*
X141780Y-347244D02*
X141981Y-347043D01*
X134744Y-347244D02*
X141780D01*
X142520Y-342913D02*
X142520Y-342913D01*
X134744Y-342913D02*
X142520D01*
X276969Y-399280D02*
Y-371816D01*
X198392Y-366842D02*
X225503D01*
X230478Y-371816D01*
X276969D01*
X196701Y-370523D02*
X223624D01*
X225394Y-372293D01*
X131398Y-348721D02*
Y-347244D01*
Y-348721D02*
X133465Y-350787D01*
X160236D01*
X166929Y-357480D01*
Y-370866D02*
Y-357480D01*
Y-370866D02*
X173474Y-377411D01*
X178543D01*
X164961Y-371654D02*
X173622Y-380315D01*
X164961Y-371654D02*
Y-357480D01*
X160630Y-353150D02*
X164961Y-357480D01*
X123228Y-353150D02*
X160630D01*
X119685Y-349606D02*
X123228Y-353150D01*
X103150Y-349606D02*
X119685D01*
X131398Y-347244D02*
Y-342913D01*
X679921Y-217717D02*
X680709Y-216929D01*
X679921Y-220847D02*
Y-217717D01*
X672047Y-216929D02*
X674016Y-218898D01*
X671654Y-217323D02*
X672047Y-216929D01*
X382283Y-140157D02*
X389370D01*
X392968Y-136559D01*
X409900D01*
X381890Y-137402D02*
X388189D01*
X402719Y-122872D01*
Y-112334D01*
X421260Y-111024D02*
X423677Y-108606D01*
X427221D01*
X435827Y-100000D01*
X553543D01*
X421260Y-112559D02*
Y-111024D01*
X421122Y-112697D02*
X421260Y-112559D01*
X443946Y-132480D02*
X447835Y-128592D01*
X436614Y-132480D02*
X443946D01*
X555512Y-218504D02*
X558661Y-221654D01*
X559533D01*
X472835Y-177559D02*
X474016Y-176378D01*
X468504Y-177559D02*
X472835D01*
X467332Y-176387D02*
X468504Y-177559D01*
X467332Y-176387D02*
Y-168449D01*
X460186Y-175247D02*
X461427Y-174006D01*
Y-168449D01*
X460186Y-175448D02*
Y-175247D01*
X618644Y-102362D02*
X620959Y-100047D01*
X611417Y-102362D02*
X618644D01*
X610236Y-101181D02*
X611417Y-102362D01*
X608071Y-101181D02*
X610236D01*
X601745Y-98398D02*
Y-98051D01*
Y-98398D02*
X604528Y-101181D01*
X618504Y-81890D02*
X618898Y-82284D01*
X611811Y-81890D02*
X618504D01*
X602100Y-85802D02*
X604921Y-88623D01*
X599279Y-82981D02*
X602100Y-85802D01*
X606012Y-81890D01*
X608268D01*
X578168Y-80778D02*
X578237Y-80709D01*
X581693D01*
X590945Y-83854D02*
Y-81890D01*
Y-88189D02*
Y-83854D01*
X587800Y-80709D02*
X590945Y-83854D01*
X585236Y-80709D02*
X587800D01*
X585774Y-103543D02*
X588372Y-100945D01*
X583858Y-103543D02*
X585774D01*
X581102Y-106299D02*
X583858Y-103543D01*
X577559Y-106299D02*
X581102D01*
X571850Y-104134D02*
Y-100394D01*
Y-104134D02*
X574016Y-106299D01*
X234646Y-122835D02*
X235039Y-122441D01*
X237500D01*
X238189Y-118898D02*
Y-116142D01*
Y-118898D02*
X240453Y-121161D01*
Y-122441D02*
Y-121161D01*
X235728Y-116142D02*
X238189D01*
X235039Y-116831D02*
X235728Y-116142D01*
X242323Y-113878D02*
X242618Y-114173D01*
X235039Y-113878D02*
X242323D01*
X259350Y-118504D02*
X259842Y-118996D01*
X255118Y-118504D02*
X259350D01*
Y-104724D02*
X259842Y-105217D01*
Y-118996D02*
Y-105217D01*
Y-124803D02*
Y-121949D01*
X180118Y-120079D02*
X181496D01*
X169488Y-109449D02*
X180118Y-120079D01*
X165157Y-105118D02*
X169488Y-109449D01*
X158858Y-105118D02*
X165157D01*
X154527Y-109449D02*
X158858Y-105118D01*
X161496Y-120079D02*
X163583Y-117992D01*
Y-109449D01*
X148622Y-117205D02*
X151496Y-120079D01*
X148622Y-117205D02*
Y-109449D01*
X360173Y-272426D02*
X360236Y-272490D01*
X348876Y-272426D02*
X360173D01*
X325984Y-272441D02*
X325999Y-272426D01*
X332932D01*
X435827Y-103543D02*
X436713Y-104429D01*
Y-111024D02*
Y-104429D01*
X402719Y-112334D02*
X404422Y-110630D01*
X406693D01*
X419055D02*
X421122Y-112697D01*
X409646Y-110630D02*
X419055D01*
X409646D02*
X409730Y-110714D01*
Y-115810D02*
Y-110714D01*
Y-119764D02*
X409842Y-119876D01*
Y-126969D02*
Y-119876D01*
Y-136502D02*
X409900Y-136559D01*
X409842Y-136502D02*
Y-132874D01*
X430056Y-136909D02*
X430492Y-136473D01*
X426122Y-136909D02*
X430056D01*
X414567Y-137402D02*
X415059Y-136909D01*
X421122D01*
X436614Y-136614D02*
Y-132480D01*
Y-126575D02*
Y-120866D01*
X439665Y-111024D02*
X443307D01*
X436614Y-116912D02*
X436713Y-116814D01*
Y-111024D01*
X435039Y-112697D02*
X436713Y-111024D01*
X426122Y-112697D02*
X435039D01*
X553543Y-100000D02*
X569685Y-83858D01*
X577953D01*
X664966Y-316582D02*
X665800Y-315748D01*
X669882D01*
X683456Y-323228D02*
X684243Y-322441D01*
X675787Y-323228D02*
X683456D01*
X675787Y-315748D02*
X684243D01*
X688327Y-315878D02*
X692037D01*
X688197Y-315748D02*
X688327Y-315878D01*
X688197Y-322441D02*
X692126D01*
X265158Y-124803D02*
X269488Y-129134D01*
X259842Y-124803D02*
X265158D01*
X269488Y-129134D02*
X274676Y-123946D01*
X269488Y-129134D02*
X269488D01*
X257087Y-127559D02*
X259842Y-124803D01*
X250787Y-115354D02*
X254035D01*
X250000Y-116142D02*
X250787Y-115354D01*
X250000Y-118701D02*
Y-116142D01*
X254921Y-118701D02*
X255118Y-118504D01*
X251575Y-118701D02*
X254921D01*
X252448Y-123819D02*
X254376Y-125747D01*
X251575Y-123819D02*
X252448D01*
X257087Y-129035D02*
Y-127559D01*
X255413Y-130709D02*
X257087Y-129035D01*
X250000Y-128248D02*
X252461Y-130709D01*
X250000Y-128248D02*
Y-123819D01*
X241250Y-126247D02*
X242060D01*
X245276Y-123031D01*
X245571Y-130709D02*
X246063Y-130217D01*
Y-127953D01*
X246850Y-127165D01*
Y-123819D01*
X238189Y-116142D02*
X242102D01*
X244661Y-118701D01*
X245276D01*
X242618Y-114075D02*
X243687Y-113006D01*
Y-112915D02*
X244214Y-112387D01*
X244305D02*
X245669Y-111024D01*
X242618Y-114173D02*
Y-114075D01*
X243687Y-113006D02*
Y-112915D01*
X244214Y-112387D02*
X244305D01*
X245669Y-111024D02*
X246063D01*
X245571Y-114173D02*
X246850Y-115453D01*
Y-118701D02*
Y-115453D01*
X248425Y-129134D02*
Y-123819D01*
X241077Y-118805D02*
X243532Y-121260D01*
X245276D01*
X251575D02*
X255512D01*
X253712Y-109191D02*
X253713Y-109190D01*
X250394Y-109191D02*
X253712D01*
X253581Y-112069D02*
X253690Y-111960D01*
X250394Y-112069D02*
X253581D01*
X250394Y-113386D02*
Y-112069D01*
X248425Y-115354D02*
X250394Y-113386D01*
X248425Y-118701D02*
Y-115354D01*
X266535Y-122441D02*
X267717Y-123622D01*
X266535Y-122441D02*
Y-118898D01*
X279479D02*
X279528Y-118947D01*
X271654Y-118898D02*
X279479D01*
X271654Y-122835D02*
X271654Y-122835D01*
X271654Y-122835D02*
Y-118898D01*
X267323Y-132677D02*
Y-132087D01*
X264370Y-129134D02*
X267323Y-132087D01*
X274676Y-123946D02*
X279528D01*
X272047Y-131496D02*
X274597Y-128946D01*
X279528D01*
X227756Y-114399D02*
X229302D01*
X234252Y-109449D01*
X228824Y-104850D02*
X232242Y-108268D01*
X234252D01*
X130315Y-25591D02*
X195276Y-90551D01*
X285039D01*
X305118Y-110630D01*
X319685D01*
X129134Y-19685D02*
X197244Y-87795D01*
X285433D01*
X306299Y-108661D01*
X320472D01*
X577953Y-83858D02*
X582480Y-88386D01*
Y-90158D02*
Y-88386D01*
X604921Y-89764D02*
Y-88623D01*
X602146Y-98051D02*
X604921Y-95276D01*
X601745Y-98051D02*
X602146D01*
X619998Y-89845D02*
Y-84291D01*
X619685Y-90158D02*
X619998Y-89845D01*
X618898Y-83191D02*
Y-82284D01*
Y-83191D02*
X619998Y-84291D01*
X619998D01*
X612205Y-87008D02*
X612205D01*
X615354Y-90158D01*
X608465Y-89764D02*
X610236D01*
X612205Y-91732D01*
X614567D01*
X608465Y-95276D02*
X608858Y-94882D01*
X614567D01*
X619685Y-98774D02*
X620959Y-100047D01*
X619685Y-98774D02*
Y-96457D01*
X612598Y-100000D02*
Y-98425D01*
X614567Y-96457D01*
X622835Y-95669D02*
X624016D01*
X622047Y-94882D02*
X622835Y-95669D01*
X619685Y-94882D02*
X622047D01*
X624016Y-95669D02*
X626181Y-97835D01*
Y-99606D02*
Y-97835D01*
X623228Y-93307D02*
X626120D01*
X619685D02*
X623228D01*
X625787Y-87205D02*
Y-86614D01*
X621260Y-91732D02*
X625787Y-87205D01*
X619685Y-91732D02*
X621260D01*
X598992Y-83268D02*
X599279Y-82981D01*
X594095Y-83268D02*
X598992D01*
X595732Y-77103D02*
X597227D01*
X590945Y-81890D02*
X595732Y-77103D01*
X588779Y-88189D02*
X590945D01*
X586811Y-90158D02*
X588779Y-88189D01*
X594095Y-90551D02*
Y-86811D01*
X592520Y-90551D02*
X594095D01*
X591339Y-91732D02*
X592520Y-90551D01*
X586811Y-91732D02*
X591339D01*
X601725Y-98032D02*
X601745Y-98051D01*
X596260Y-98032D02*
X601725D01*
X586811Y-99383D02*
X588372Y-100945D01*
X586811Y-99383D02*
Y-96457D01*
X589567Y-94882D02*
X592717Y-98032D01*
X586811Y-94882D02*
X589567D01*
X567323Y-94095D02*
X571850Y-98622D01*
Y-100394D02*
Y-98622D01*
X568504Y-88189D02*
X572244D01*
X575787D02*
X579331Y-91732D01*
X581693D01*
X579921Y-101969D02*
X581693Y-100197D01*
Y-96457D01*
X575394Y-100394D02*
X576772D01*
X578740Y-98425D01*
Y-96063D01*
X579921Y-94882D01*
X581693D01*
X596986Y-93307D02*
X597244Y-93565D01*
X592520Y-93307D02*
X596986D01*
X586811D02*
X592520D01*
X671654Y-100094D02*
X672441Y-100882D01*
X671654Y-100094D02*
Y-94488D01*
X672047Y-94095D01*
X681102D01*
X665664Y-108746D02*
X667717Y-106693D01*
X665664Y-110630D02*
Y-108746D01*
X672141Y-106693D02*
X672441Y-106992D01*
X667717Y-106693D02*
X672141D01*
X696457Y-51332D02*
X696577Y-51453D01*
X696457Y-51332D02*
Y-48228D01*
X694291Y-44685D02*
X696457D01*
X691400Y-47577D02*
X694291Y-44685D01*
X689862Y-47577D02*
X691400D01*
X675591Y-42520D02*
X676772Y-41339D01*
X678543D01*
X682087D02*
X684547Y-43799D01*
Y-47577D02*
Y-43799D01*
X679517Y-37023D02*
X679528Y-37013D01*
Y-33858D01*
X681201D02*
X685827Y-29232D01*
X679528Y-33858D02*
X681201D01*
X686319Y-43553D02*
Y-39530D01*
Y-47577D02*
Y-43553D01*
X693959Y-39234D02*
X694095Y-39370D01*
X686614Y-39234D02*
X693959D01*
X686319Y-39530D02*
X686614Y-39234D01*
X683127Y-66209D02*
X684547Y-64789D01*
Y-58723D01*
X686319Y-62303D02*
X689466Y-65450D01*
Y-66165D02*
Y-65450D01*
Y-66165D02*
X689490Y-66142D01*
X692262D01*
X680082Y-64183D02*
X682776Y-61490D01*
Y-58723D01*
X662598Y-82835D02*
X662638Y-82874D01*
X667717D01*
X672795D02*
X675591Y-80079D01*
X671260Y-82874D02*
X672795D01*
X686319Y-62303D02*
Y-58723D01*
X678353Y-89764D02*
X678367Y-89750D01*
X680329D02*
X681102Y-88976D01*
X678367Y-89750D02*
X680329D01*
X680631Y-91064D02*
X681102Y-91535D01*
X672212Y-91064D02*
X680631D01*
X669088Y-87940D02*
X672212Y-91064D01*
X670388Y-87402D02*
Y-83746D01*
X671260Y-82874D01*
X669088Y-87940D02*
Y-84246D01*
X667717Y-82874D02*
X669088Y-84246D01*
X538583Y-111811D02*
X539370Y-111024D01*
X544882D01*
X548681Y-114823D01*
Y-115748D02*
Y-114823D01*
X539233Y-115729D02*
X539252Y-115748D01*
X543681D01*
X559842Y-109449D02*
X562598D01*
X558681Y-110610D02*
X559842Y-109449D01*
X558681Y-115748D02*
Y-110610D01*
X553681Y-115748D02*
Y-109055D01*
X553543D02*
X553681D01*
X535984Y-135276D02*
X537402Y-133858D01*
X535984Y-141339D02*
Y-135276D01*
X539327Y-141339D02*
X539900Y-140766D01*
X535984Y-141339D02*
X539327D01*
X539900Y-140766D02*
X539923D01*
X543681Y-137008D01*
X571555Y-145276D02*
X576772Y-140059D01*
X564173Y-145276D02*
X571555D01*
X562598Y-143701D02*
X564173Y-145276D01*
X562598Y-143701D02*
Y-134252D01*
X559842Y-131496D02*
X562598Y-134252D01*
X555118Y-131496D02*
X559842D01*
X568110D02*
X568898Y-132283D01*
X553681Y-132933D02*
X555118Y-131496D01*
X553681Y-137008D02*
Y-132933D01*
X678354Y-292500D02*
X678441Y-292586D01*
X672047Y-292500D02*
X678354D01*
X678090Y-297500D02*
X678346Y-297244D01*
X672047Y-297500D02*
X678090D01*
X637795Y-287402D02*
X644676D01*
X674016Y-222835D02*
Y-218898D01*
Y-222835D02*
X677028Y-225847D01*
X679921D01*
X660630Y-251181D02*
X666535Y-245276D01*
X667717D01*
X643701Y-223858D02*
X645512Y-222047D01*
X650394D01*
X657461D02*
X658661Y-220847D01*
X650394Y-222047D02*
X657461D01*
X650394Y-220866D02*
X652756Y-218504D01*
X650394Y-222047D02*
Y-220866D01*
X635433Y-289764D02*
X637795Y-287402D01*
X635433Y-300787D02*
Y-289764D01*
Y-300787D02*
X639370Y-304724D01*
X648563D01*
X650787Y-302500D01*
X635827Y-282283D02*
X636221Y-281890D01*
X635827Y-286614D02*
Y-282283D01*
X633858Y-288583D02*
X635827Y-286614D01*
X633858Y-302362D02*
Y-288583D01*
Y-302362D02*
X638996Y-307500D01*
X650787D01*
X683858Y-310630D02*
X683858D01*
X683858D02*
Y-306299D01*
X643307Y-292126D02*
X650787D01*
Y-292500D02*
Y-292126D01*
X643307D02*
Y-286614D01*
X643701D01*
X549213Y-207874D02*
X551181Y-205906D01*
X558268D01*
X561417Y-209055D01*
X547244Y-203150D02*
X548032Y-203937D01*
X559842D01*
X561417Y-205512D01*
X545276Y-275197D02*
X545669Y-274803D01*
X548819D01*
X545276Y-270866D02*
X548819D01*
X556988Y-261319D02*
X557087Y-261417D01*
X552953Y-261319D02*
X556988D01*
X556558Y-257972D02*
X556628Y-258042D01*
X552953Y-257972D02*
X556558D01*
X551439Y-279921D02*
X551968Y-280451D01*
Y-285039D02*
Y-280451D01*
X557972Y-275886D02*
X562205D01*
X553937Y-279921D02*
X557972Y-275886D01*
X551439Y-279921D02*
X553937D01*
X552658Y-257677D02*
X552953Y-257972D01*
X547835Y-257677D02*
X552658D01*
X547835Y-261614D02*
X548130Y-261319D01*
X552953D01*
X552067Y-262205D02*
X552953Y-261319D01*
X552067Y-265945D02*
Y-262205D01*
Y-265945D02*
X554331Y-268209D01*
X562205D01*
X562106Y-270866D02*
X562205Y-270768D01*
X551968Y-270866D02*
X562106D01*
X551968Y-274803D02*
X555905D01*
X557382Y-273327D01*
X562205D01*
X563386Y-257874D02*
X564665Y-259154D01*
Y-262598D02*
Y-259154D01*
X569783Y-260925D02*
X572441Y-258268D01*
X569783Y-262598D02*
Y-260925D01*
X627165Y-300787D02*
X639259Y-312881D01*
X518898Y-297638D02*
X591773D01*
X594488Y-300787D02*
X627165D01*
X594488D02*
Y-300353D01*
X591773Y-297638D02*
X594488Y-300353D01*
X501968Y-300000D02*
X591470D01*
X624213Y-302559D02*
X626772Y-305118D01*
X591470Y-300000D02*
X594029Y-302559D01*
X624213D01*
X431102Y-209842D02*
X518898Y-297638D01*
X415748Y-213779D02*
X501968Y-300000D01*
X640454Y-312881D02*
X641450Y-313877D01*
X639259Y-312881D02*
X640454D01*
X641450Y-315072D02*
X648425Y-322047D01*
Y-336614D02*
Y-322047D01*
X641450Y-315072D02*
Y-313877D01*
X475984Y-127165D02*
X477756Y-125394D01*
X479872D01*
X480118Y-132363D02*
X480120Y-132365D01*
X480118Y-132363D02*
Y-128593D01*
X469685Y-133465D02*
X470866Y-134646D01*
X472835D01*
X488965Y-141328D02*
X493701Y-146063D01*
X482666Y-141328D02*
X488965D01*
X475984Y-134646D02*
X482666Y-141328D01*
X475984Y-134646D02*
Y-134252D01*
X472441Y-130709D02*
X475984Y-134252D01*
X472441Y-130709D02*
Y-128347D01*
X473228Y-105905D02*
X473622D01*
X476772Y-109055D01*
X447647Y-172843D02*
X449150Y-174346D01*
X447647Y-172843D02*
Y-168449D01*
X449213Y-177953D02*
Y-174894D01*
X449150Y-174831D02*
X449213Y-174894D01*
X449150Y-174831D02*
Y-174346D01*
X445669Y-168458D02*
X445679Y-168449D01*
X445669Y-173228D02*
Y-168458D01*
Y-173228D02*
X446457Y-174016D01*
X453543Y-168458D02*
X453552Y-168449D01*
X453543Y-177559D02*
Y-168458D01*
Y-177559D02*
X464961Y-188976D01*
X488583D01*
X489764Y-190157D01*
X500787D01*
X503150Y-187795D01*
Y-183465D01*
X508780Y-191613D02*
X522835Y-177559D01*
X449213Y-177953D02*
X462873Y-191613D01*
X508780D01*
X522835Y-177559D02*
Y-151181D01*
X525197Y-178740D02*
Y-150000D01*
X459842Y-192913D02*
X511024D01*
X525197Y-178740D01*
X503150Y-183465D02*
X520866Y-165748D01*
Y-156693D01*
X510236Y-146063D02*
X520866Y-156693D01*
X493701Y-146063D02*
X510236D01*
X512992Y-141339D02*
X522835Y-151181D01*
X512598Y-137402D02*
X525197Y-150000D01*
X499764Y-141339D02*
X512992D01*
X499764Y-137402D02*
X512598D01*
X467717Y-123622D02*
X472441Y-128347D01*
X467717Y-123622D02*
Y-114567D01*
X470866Y-111417D01*
X478346D01*
X482087Y-115157D01*
Y-116289D02*
Y-115157D01*
X446457Y-179528D02*
Y-174016D01*
Y-179528D02*
X459842Y-192913D01*
X491929Y-136969D02*
Y-128593D01*
Y-136969D02*
X496299Y-141339D01*
X493898Y-135000D02*
X496299Y-137402D01*
X493898Y-135000D02*
Y-128593D01*
X498032Y-132283D02*
X499213Y-133465D01*
X502205D01*
X495866Y-130118D02*
X498032Y-132283D01*
X495866Y-130118D02*
Y-128593D01*
X505669Y-123858D02*
X505905Y-123622D01*
X502756Y-123858D02*
X505669D01*
X502323Y-123425D02*
X502756Y-123858D01*
X498081Y-123425D02*
X502323D01*
X470472Y-115748D02*
X472441Y-113779D01*
X470472Y-116929D02*
Y-115748D01*
X483465Y-105859D02*
X483484Y-105840D01*
X483465Y-109055D02*
Y-105859D01*
X504724Y-109843D02*
X508661D01*
X504703Y-106672D02*
X504724Y-106693D01*
Y-109843D02*
Y-106693D01*
X505905Y-119685D02*
X508268Y-117323D01*
X500984Y-121457D02*
X502756Y-119685D01*
X498081Y-121457D02*
X500984D01*
X506693Y-114961D02*
X508661Y-112992D01*
X503150Y-114961D02*
X506693D01*
X502362Y-114173D02*
X503150Y-114961D01*
X496457Y-114173D02*
X502362D01*
X495866Y-114764D02*
X496457Y-114173D01*
X495866Y-116289D02*
Y-114764D01*
X504450Y-112717D02*
X504724Y-112992D01*
X495550Y-112717D02*
X504450D01*
X493898Y-114370D02*
X495550Y-112717D01*
X493898Y-116289D02*
Y-114370D01*
X495754Y-111417D02*
X497329Y-109843D01*
X493307Y-111417D02*
X495754D01*
X491929Y-112795D02*
X493307Y-111417D01*
X491929Y-116289D02*
Y-112795D01*
X489961Y-109252D02*
X490158Y-109055D01*
X489961Y-116289D02*
Y-109252D01*
X481890Y-111024D02*
X486524D01*
X487992Y-116289D02*
Y-114149D01*
X486524Y-112680D02*
Y-111024D01*
Y-112680D02*
X487992Y-114149D01*
X479921Y-109055D02*
X481890Y-111024D01*
X486614Y-110630D02*
Y-109055D01*
X473622Y-116929D02*
X473622Y-116929D01*
Y-120472D02*
Y-116929D01*
Y-120472D02*
X473622Y-120472D01*
X475984D01*
X476968Y-121457D01*
X479872D01*
X424024Y-175993D02*
Y-168449D01*
Y-175993D02*
X426378Y-178347D01*
Y-183858D02*
Y-178347D01*
X103495Y-26427D02*
X110236Y-19685D01*
X91536Y-26427D02*
X103495D01*
X103101Y-34301D02*
X111811Y-25591D01*
X91536Y-34301D02*
X103101D01*
X59055Y-32677D02*
X60756Y-34378D01*
X73959D01*
X64173Y-18110D02*
Y-16535D01*
X64616Y-18553D02*
X74036D01*
X64173Y-18110D02*
X64616Y-18553D01*
X63435Y-26427D02*
X74036D01*
X61811Y-24803D02*
X63435Y-26427D01*
X111811Y-25591D02*
X130315D01*
X110236Y-19685D02*
X129134D01*
X66142Y-14567D02*
X129528D01*
X197244Y-82284D01*
X64173Y-16535D02*
X66142Y-14567D01*
X135433Y-11811D02*
X203543Y-79921D01*
X64567Y-11811D02*
X135433D01*
X61811Y-14567D02*
X64567Y-11811D01*
X139764Y-9055D02*
X205906Y-75197D01*
X59055Y-14173D02*
X64173Y-9055D01*
X139764D01*
X197244Y-82284D02*
X319685D01*
X61811Y-24803D02*
Y-14567D01*
X203543Y-79921D02*
X322047D01*
X59055Y-32677D02*
Y-14173D01*
X205906Y-75197D02*
X325197D01*
X509884Y-151181D02*
X518337Y-159634D01*
X486614Y-151181D02*
X509884D01*
X475591Y-140157D02*
X486614Y-151181D01*
X467323Y-140157D02*
X475591D01*
X466032Y-141449D02*
X467323Y-140157D01*
X466032Y-147748D02*
Y-141449D01*
X465364Y-148416D02*
X466032Y-147748D01*
X465364Y-152505D02*
Y-148416D01*
X515165Y-162803D02*
X515702D01*
X505905Y-153543D02*
X515165Y-162803D01*
X485039Y-153543D02*
X505905D01*
X473228Y-141732D02*
X485039Y-153543D01*
X468504Y-141732D02*
X473228D01*
X467332Y-142905D02*
X468504Y-141732D01*
X467332Y-152505D02*
Y-142905D01*
X496169Y-185827D02*
X498693Y-188351D01*
X464567Y-185827D02*
X496169D01*
X455521Y-176780D02*
X464567Y-185827D01*
X455521Y-176780D02*
Y-168449D01*
X497638Y-182677D02*
X498819Y-183858D01*
X466929Y-182677D02*
X497638D01*
X463394Y-179143D02*
X466929Y-182677D01*
X463394Y-179143D02*
Y-168449D01*
X499110Y-179528D02*
X499111Y-179528D01*
X467323Y-179528D02*
X499110D01*
X465364Y-177568D02*
X467323Y-179528D01*
X465364Y-177568D02*
Y-168449D01*
X325197Y-75197D02*
X338583Y-88583D01*
Y-137795D02*
Y-88583D01*
Y-137795D02*
X352362Y-151575D01*
X380709D01*
X388976Y-143307D01*
X392913D01*
X394498Y-144891D01*
Y-152505D02*
Y-144891D01*
X322047Y-79921D02*
X335827Y-93701D01*
Y-143701D02*
Y-93701D01*
Y-143701D02*
X340158D01*
X351969Y-155512D01*
X380709D01*
X389764Y-146457D01*
X391339D01*
X392529Y-147647D01*
Y-152505D02*
Y-147647D01*
X319685Y-82284D02*
X331890Y-94488D01*
Y-146850D02*
Y-94488D01*
Y-146850D02*
X333071Y-148031D01*
X340945D01*
X359842Y-166929D01*
X361811D01*
X327559Y-161024D02*
Y-115748D01*
X345669Y-179134D02*
X394094D01*
X327559Y-161024D02*
X345669Y-179134D01*
X325590Y-163386D02*
Y-116535D01*
X343701Y-181496D02*
X394488D01*
X325590Y-163386D02*
X343701Y-181496D01*
X394488D02*
X396465Y-179519D01*
X361811Y-166929D02*
X371654Y-176772D01*
X392126D01*
X392529Y-176369D01*
Y-168449D01*
X320472Y-108661D02*
X327559Y-115748D01*
X394094Y-179134D02*
X394498Y-178731D01*
Y-168449D01*
X319685Y-110630D02*
X325590Y-116535D01*
X396465Y-179519D02*
Y-168449D01*
X654795Y-53395D02*
X658114Y-56714D01*
X649390Y-53395D02*
X654795D01*
X655189Y-61269D02*
X657445Y-63525D01*
X649390Y-61269D02*
X655189D01*
X656008Y-69143D02*
X658053Y-71188D01*
X649390Y-69143D02*
X656008D01*
X623511Y-62552D02*
X624794Y-61269D01*
X631890D01*
X623228Y-55118D02*
X624951Y-53395D01*
X631890D01*
X73959Y-34378D02*
X74036Y-34301D01*
X423228Y-179102D02*
X423461Y-178869D01*
X423228Y-183858D02*
Y-179102D01*
X144364Y-131102D02*
X144871Y-131609D01*
X140157Y-131102D02*
X144364D01*
X140157Y-127953D02*
X141496Y-126614D01*
Y-120079D01*
X119833Y-263632D02*
X120079Y-263386D01*
X116142Y-263632D02*
X119833D01*
X314417Y-228445D02*
Y-228033D01*
X313268Y-229593D02*
X314417Y-228445D01*
X309193Y-229593D02*
X313268D01*
X314623Y-231439D02*
Y-231391D01*
X314470Y-231593D02*
X314623Y-231439D01*
X309193Y-231593D02*
X314470D01*
X416123Y-152551D02*
Y-144197D01*
X313839Y-245593D02*
X314658Y-244775D01*
X309193Y-245593D02*
X313839D01*
X313610Y-233593D02*
X315097Y-235081D01*
X309193Y-233593D02*
X313610D01*
X312089Y-227593D02*
X314503Y-225180D01*
X309193Y-227593D02*
X312089D01*
X288057Y-233478D02*
X288173Y-233593D01*
X293445D01*
X288189Y-231102D02*
X288680Y-231593D01*
X293445D01*
X288189Y-228740D02*
X289042Y-229593D01*
X293445D01*
X288583Y-225590D02*
X290585Y-227593D01*
X293445D01*
X288189Y-247638D02*
X290233Y-245593D01*
X293445D01*
X289559Y-243593D02*
X293445D01*
X288057Y-245095D02*
X289559Y-243593D01*
X288166Y-241593D02*
X293445D01*
X287941Y-241819D02*
X288166Y-241593D01*
X288189Y-235827D02*
X288422Y-235593D01*
X293445D01*
X471654Y-292520D02*
X502869Y-323735D01*
X469291Y-292520D02*
X471654D01*
X502869Y-353233D02*
Y-323735D01*
X648425Y-336614D02*
X650394Y-338583D01*
X655118D01*
X626772Y-334252D02*
X631496Y-338976D01*
X637008D01*
X368110Y-209842D02*
X431102D01*
X368504Y-213779D02*
X415748D01*
X626772Y-334252D02*
Y-305118D01*
X528338Y-331738D02*
X532619D01*
X524056D02*
X528338D01*
X532619D02*
Y-328288D01*
X525591Y-321260D02*
X532619Y-328288D01*
X507480Y-321260D02*
X525591D01*
X400394Y-223622D02*
X469291Y-292520D01*
X369291Y-223622D02*
X400394D01*
X405905Y-219685D02*
X507480Y-321260D01*
X369685Y-219685D02*
X405905D01*
X358661Y-208661D02*
X369685Y-219685D01*
X362598Y-201181D02*
X367717Y-206299D01*
X358661Y-201181D02*
X358661Y-201181D01*
X362598D01*
X367717Y-206299D02*
X370079D01*
X358661Y-208661D02*
Y-201181D01*
X370079Y-206299D02*
Y-201969D01*
X364961Y-196850D02*
X370079Y-201969D01*
X355512Y-196850D02*
X364961D01*
X354739Y-197623D02*
X355512Y-196850D01*
X348876Y-197623D02*
X354739D01*
X355906Y-210236D02*
Y-198425D01*
X362598D02*
X366535Y-202362D01*
X355906Y-198425D02*
X362598D01*
X355906Y-210236D02*
X369291Y-223622D01*
X523958Y-347880D02*
X532225D01*
X532283Y-347938D01*
Y-353150D02*
Y-347938D01*
X528346Y-357087D02*
X532283Y-353150D01*
X506723Y-357087D02*
X528346D01*
X502869Y-353233D02*
X506723Y-357087D01*
X655118Y-329921D02*
X655709Y-329331D01*
X655118Y-338583D02*
Y-329921D01*
X637008Y-338976D02*
Y-329232D01*
X609291Y-350630D02*
Y-343543D01*
Y-350630D02*
X613779Y-355118D01*
X628740D01*
X637008Y-346850D01*
X642913Y-358661D02*
X655118Y-346457D01*
X593701Y-358661D02*
X642913D01*
X589291Y-354252D02*
X593701Y-358661D01*
X589291Y-354252D02*
Y-343543D01*
X540099Y-347880D02*
X549700Y-357480D01*
X576378D01*
X579291Y-354567D01*
Y-343543D01*
X540493Y-331738D02*
X552298Y-343543D01*
X569291D01*
X609291D02*
X609449Y-343701D01*
X589291Y-343543D02*
X589372Y-343624D01*
X579134Y-343701D02*
X579291Y-343543D01*
X116142Y-263632D02*
X116142Y-263632D01*
X116142Y-308268D02*
Y-263632D01*
X95669Y-328740D02*
X116142Y-308268D01*
X95669Y-342126D02*
Y-328740D01*
Y-342126D02*
X103150Y-349606D01*
X173622Y-380315D02*
X184252D01*
X187156Y-377411D01*
X190354D01*
X531526Y-262617D02*
X536337D01*
X536367Y-262587D01*
X531496Y-262647D02*
X531526Y-262617D01*
X461417Y-316584D02*
Y-311289D01*
X461811Y-310895D01*
Y-310679D01*
X449606Y-300640D02*
Y-294360D01*
X450000Y-293966D02*
Y-293750D01*
X449606Y-294360D02*
X450000Y-293966D01*
X422047Y-300640D02*
Y-294399D01*
X422441Y-294005D01*
Y-293789D01*
X531526Y-213405D02*
X536338D01*
X536367Y-213375D01*
X531496Y-213435D02*
X531526Y-213405D01*
X520437Y-233074D02*
X525576D01*
X520423Y-233060D02*
X520437Y-233074D01*
X525576D02*
X525591Y-233088D01*
X439730Y-168479D02*
Y-162582D01*
Y-168479D02*
X439762Y-168512D01*
X439697Y-162549D02*
X439730Y-162582D01*
X420077Y-157114D02*
Y-152568D01*
Y-157114D02*
X420669Y-157706D01*
Y-157923D02*
Y-157706D01*
X531526Y-223247D02*
X536337D01*
X536367Y-223217D01*
X531496Y-223277D02*
X531526Y-223247D01*
X332932Y-235024D02*
X333024Y-235116D01*
X338462D01*
X338583Y-235236D01*
X520423Y-242902D02*
X520453Y-242932D01*
X525561D01*
X525591Y-242962D01*
X429920Y-168512D02*
Y-162699D01*
X430150Y-162470D01*
Y-162253D01*
X410235Y-157414D02*
Y-152568D01*
X410528Y-157923D02*
Y-157706D01*
X410235Y-157414D02*
X410528Y-157706D01*
X443700Y-300640D02*
Y-294360D01*
X444095Y-293966D02*
Y-293750D01*
X443700Y-294360D02*
X444095Y-293966D01*
X422047Y-316584D02*
Y-312076D01*
X422835Y-311289D01*
Y-311072D01*
X531510Y-233074D02*
X536353D01*
X536367Y-233060D01*
X531496Y-233088D02*
X531510Y-233074D01*
X430012Y-157786D02*
Y-152660D01*
X429920Y-152568D02*
X430012Y-152660D01*
Y-157786D02*
X430150Y-157923D01*
X402362Y-316584D02*
Y-311683D01*
X402756Y-311289D01*
Y-311072D01*
X520515Y-252837D02*
X524243D01*
X520423Y-252745D02*
X520515Y-252837D01*
X524243D02*
X525374Y-253969D01*
X525591D01*
X420078Y-168511D02*
Y-162549D01*
X420077Y-168512D02*
X420078Y-168511D01*
Y-162549D02*
X420079Y-162549D01*
X520423Y-203532D02*
X520453Y-203562D01*
X525561D01*
X525591Y-203592D01*
X400392Y-157727D02*
Y-152568D01*
X400295Y-157824D02*
X400392Y-157727D01*
X531526Y-242932D02*
X536337D01*
X536367Y-242902D01*
X531496Y-242962D02*
X531526Y-242932D01*
X402362Y-300640D02*
Y-293750D01*
X520454Y-262617D02*
X525560D01*
X520423Y-262587D02*
X520454Y-262617D01*
X525560D02*
X525591Y-262647D01*
X410235Y-168512D02*
Y-163652D01*
X410913Y-162974D01*
Y-162758D01*
X455511Y-300640D02*
Y-294754D01*
X456299Y-293966D01*
Y-293750D01*
X437795Y-300640D02*
Y-293750D01*
X437795Y-293750D02*
X437795Y-293750D01*
X520453Y-213405D02*
X525561D01*
X520423Y-213375D02*
X520453Y-213405D01*
X525561D02*
X525591Y-213435D01*
X459383Y-168448D02*
Y-162575D01*
Y-168448D02*
X459447Y-168512D01*
X459319Y-162510D02*
X459383Y-162575D01*
Y-157858D02*
Y-152632D01*
X459447Y-152568D01*
X459319Y-157922D02*
X459383Y-157858D01*
X412204Y-316584D02*
Y-311683D01*
X412598Y-311289D02*
Y-311072D01*
X412204Y-311683D02*
X412598Y-311289D01*
X532844Y-252837D02*
X536275D01*
X536367Y-252745D01*
X531713Y-253969D02*
X532844Y-252837D01*
X531496Y-253969D02*
X531713D01*
X449697Y-157817D02*
Y-152660D01*
X449605Y-152568D02*
X449697Y-152660D01*
Y-157817D02*
X449803Y-157923D01*
X536337Y-203562D02*
X536367Y-203532D01*
X531526Y-203562D02*
X536337D01*
X531496Y-203592D02*
X531526Y-203562D01*
X400392Y-168512D02*
Y-163613D01*
X401279Y-162726D01*
Y-162509D01*
X439854Y-157817D02*
Y-152660D01*
X439762Y-152568D02*
X439854Y-152660D01*
Y-157817D02*
X439961Y-157923D01*
X461417Y-300640D02*
Y-293750D01*
X520453Y-223247D02*
X525561D01*
X520423Y-223217D02*
X520453Y-223247D01*
X525561D02*
X525591Y-223277D01*
X449513Y-168420D02*
Y-165540D01*
X449508Y-165534D02*
X449513Y-165540D01*
X449508Y-165534D02*
Y-162549D01*
X449513Y-168420D02*
X449605Y-168512D01*
X343624Y-235116D02*
X348784D01*
X348876Y-235024D01*
X343504Y-235236D02*
X343624Y-235116D01*
X412204Y-300640D02*
X412205Y-300640D01*
Y-293750D01*
X412205Y-293750D01*
X232894Y-129399D02*
X234252Y-130757D01*
Y-133742D02*
Y-130757D01*
X263779Y-111860D02*
Y-106151D01*
X83661Y-315945D02*
X85630Y-313976D01*
X81004Y-315945D02*
X83661D01*
X85630Y-260827D02*
Y-260059D01*
X86614Y-259075D02*
Y-258858D01*
X85630Y-260059D02*
X86614Y-259075D01*
X84646Y-261811D02*
X85630Y-260827D01*
X81988Y-261811D02*
X84646D01*
Y-205709D02*
X85630Y-206693D01*
X81693Y-205709D02*
X84646D01*
X85630Y-208661D02*
Y-206693D01*
X84646Y-209646D02*
X85630Y-208661D01*
X81988Y-209646D02*
X84646D01*
X360171Y-268521D02*
X360236Y-268586D01*
X348908Y-268521D02*
X360171D01*
X348876Y-268489D02*
X348908Y-268521D01*
X26495Y-8991D02*
Y-4705D01*
X26575Y-4626D01*
X68701Y-227362D02*
X68898Y-227165D01*
X63976Y-227362D02*
X68701D01*
X68898Y-285433D02*
Y-281299D01*
X67913Y-340551D02*
Y-335433D01*
Y-178444D02*
X68573Y-179104D01*
Y-179321D02*
Y-179104D01*
X67913Y-178444D02*
Y-175000D01*
X44291Y-326772D02*
Y-322736D01*
Y-311122D02*
Y-307087D01*
X27185Y-291732D02*
X31496D01*
X26791Y-291339D02*
X27185Y-291732D01*
X26575Y-291339D02*
X26791D01*
X31496Y-189961D02*
Y-184055D01*
X44291Y-151673D02*
Y-147638D01*
Y-167323D02*
Y-163287D01*
Y-204823D02*
Y-200787D01*
Y-220472D02*
Y-216437D01*
Y-272638D02*
Y-268602D01*
Y-256988D02*
Y-252953D01*
X326311Y-242898D02*
X332932D01*
X326004Y-243205D02*
X326311Y-242898D01*
X325787Y-243205D02*
X326004D01*
X326310Y-233056D02*
X332932D01*
X326004Y-233362D02*
X326310Y-233056D01*
X325787Y-233362D02*
X326004D01*
X103409Y-141732D02*
Y-138935D01*
X103347Y-116831D02*
Y-110236D01*
X116298Y-126047D02*
X119095D01*
X116235Y-125984D02*
X116298Y-126047D01*
X112500Y-125984D02*
X116235D01*
X103347Y-138872D02*
Y-135138D01*
Y-138872D02*
X103409Y-138935D01*
X518701Y-115994D02*
Y-104214D01*
X513681Y-128691D02*
X519685Y-134695D01*
X528543Y-112057D02*
Y-104214D01*
X649390Y-21899D02*
X658465D01*
X625000Y-29773D02*
X631890D01*
X441929Y-122883D02*
X447638D01*
X263779Y-111860D02*
X263976Y-112057D01*
X227756Y-129399D02*
X232894D01*
X447638Y-122883D02*
X448622Y-123868D01*
X451772D01*
X123819Y-78789D02*
X124606Y-79576D01*
X451772Y-123868D02*
X453740Y-125836D01*
X459646D01*
X460630Y-124852D01*
Y-121639D01*
X511713Y-128691D02*
X513681D01*
X519685Y-120915D02*
X519783Y-121013D01*
X515748Y-120915D02*
X519685D01*
X512002Y-123284D02*
X513379D01*
X515748Y-120915D01*
X511713Y-123572D02*
X512002Y-123284D01*
X519783Y-121013D02*
Y-117076D01*
X518701Y-115994D02*
X519783Y-117076D01*
X67913Y-281299D02*
X68110Y-281496D01*
X512658Y-270462D02*
X520423D01*
X512657Y-270462D02*
X512658Y-270462D01*
X520423D02*
X520423Y-270461D01*
X536397Y-199625D02*
X544261D01*
X536367Y-199595D02*
X536397Y-199625D01*
X544261D02*
X544291Y-199655D01*
X509872Y-197657D02*
X520394D01*
X520423Y-197627D01*
X509842Y-197687D02*
X509872Y-197657D01*
X536397Y-201594D02*
X544262D01*
X536367Y-201564D02*
X536397Y-201594D01*
X544262D02*
X544291Y-201624D01*
X509873Y-199625D02*
X520393D01*
X520423Y-199595D01*
X509842Y-199655D02*
X509873Y-199625D01*
X509872Y-201594D02*
X520394D01*
X520423Y-201564D01*
X509842Y-201624D02*
X509872Y-201594D01*
X348908Y-250766D02*
X348915Y-250758D01*
X536397Y-197657D02*
X544262D01*
X536367Y-197627D02*
X536397Y-197657D01*
X544262D02*
X544291Y-197687D01*
X509873Y-195688D02*
X520393D01*
X520423Y-195658D01*
X509842Y-195718D02*
X509873Y-195688D01*
X361811Y-207087D02*
X368504Y-213779D01*
X361417Y-203150D02*
X368110Y-209842D01*
X346503Y-195640D02*
X354776D01*
X355928Y-194488D01*
X358661D01*
X199898Y-119399D02*
X209252D01*
X199311Y-119931D02*
X199803Y-119439D01*
X326966Y-195171D02*
X327183D01*
X327666Y-195654D01*
X105362Y-140064D02*
Y-135185D01*
X101394Y-140095D02*
X101409Y-140111D01*
X109331Y-140032D02*
Y-135216D01*
X97409Y-140111D02*
X97425Y-140095D01*
X105362Y-140064D02*
X105409Y-140111D01*
X109331Y-140032D02*
X109409Y-140111D01*
X101394Y-140095D02*
Y-135153D01*
X97425Y-140095D02*
Y-135153D01*
X65945Y-57923D02*
X74036D01*
X348945Y-252757D02*
X357804D01*
X358032Y-252984D01*
X360204D01*
X354634Y-229027D02*
X356425Y-227237D01*
Y-225400D02*
X356578Y-225247D01*
X356425Y-227237D02*
Y-225400D01*
X354541Y-225672D02*
Y-223636D01*
X353709Y-236993D02*
X354299Y-236403D01*
X354178Y-226036D02*
X354541Y-225672D01*
X354299Y-235389D02*
X354452Y-235236D01*
X354299Y-236403D02*
Y-235389D01*
X354178Y-226531D02*
Y-226036D01*
X326993Y-197598D02*
X332908D01*
X326969Y-197573D02*
X326993Y-197598D01*
X327666Y-195654D02*
X332932D01*
X332908Y-197598D02*
X332932Y-197623D01*
X82677Y-169291D02*
X86614D01*
X361499Y-236802D02*
Y-235358D01*
X361652Y-235205D01*
X79724Y-168307D02*
X82677D01*
X359131Y-226369D02*
Y-223425D01*
X361531Y-225808D02*
Y-223425D01*
X348876Y-233056D02*
X354282D01*
X361531Y-225808D01*
X354413Y-231087D02*
X359131Y-226369D01*
X38287Y-157480D02*
X54331D01*
X359623Y-262583D02*
X360020Y-262186D01*
X348876Y-262583D02*
X359623D01*
X360020Y-262186D02*
X360236D01*
X358499Y-266032D02*
X358500Y-266033D01*
X360083D01*
X360236Y-266186D01*
X357836Y-266032D02*
X358499D01*
X357348Y-266520D02*
X357836Y-266032D01*
X348876Y-266520D02*
X357348D01*
X81111Y-317806D02*
X85309D01*
X81004Y-317913D02*
X81111Y-317806D01*
X85309D02*
X85416Y-317699D01*
X81988Y-263779D02*
X85630D01*
X86409Y-211336D02*
X86562Y-211183D01*
X81988Y-211614D02*
X84861D01*
X85140Y-211336D02*
X86409D01*
X84861Y-211614D02*
X85140Y-211336D01*
X411196Y-174821D02*
Y-173804D01*
X411043Y-174974D02*
X411196Y-174821D01*
X416142Y-173742D02*
Y-168513D01*
X413440Y-174850D02*
Y-174634D01*
X411196Y-173804D02*
X412203Y-172797D01*
X416142Y-173742D02*
X417596Y-175197D01*
X413440Y-174634D02*
X414172Y-173901D01*
X421443Y-174881D02*
X421596Y-175034D01*
X420262Y-174881D02*
X421443D01*
X418109Y-172728D02*
X420262Y-174881D01*
X414172Y-173901D02*
Y-168512D01*
X406528Y-157767D02*
Y-157550D01*
X406298Y-157321D02*
Y-152568D01*
Y-157321D02*
X406528Y-157550D01*
X408266Y-156677D02*
Y-152568D01*
X408528Y-159169D02*
Y-156938D01*
X408266Y-156677D02*
X408528Y-156938D01*
X407480Y-160217D02*
X408528Y-159169D01*
X404528Y-163386D02*
X406206Y-165065D01*
Y-168420D02*
Y-165065D01*
X407480Y-160433D02*
Y-160217D01*
X418109Y-172728D02*
Y-168512D01*
X412203Y-172797D02*
Y-168512D01*
X82677Y-221457D02*
X86614D01*
X428043Y-172580D02*
X430807Y-175344D01*
X427165Y-175246D02*
Y-175029D01*
X425983Y-173847D02*
X427165Y-175029D01*
X428043Y-172580D02*
Y-168604D01*
X89567Y-166370D02*
Y-161418D01*
X86614Y-158465D02*
X89567Y-161418D01*
X81004Y-158465D02*
X86614D01*
X87167Y-166377D02*
Y-162955D01*
X81004Y-160433D02*
X84646D01*
X87167Y-162955D01*
X81988Y-213583D02*
X85630D01*
X85630Y-213583D01*
X81988Y-265748D02*
X84982D01*
X85413Y-266179D01*
X85630D01*
X85413Y-320313D02*
X85630D01*
X81004Y-319882D02*
X84982D01*
X85413Y-320313D01*
X536367Y-236997D02*
X540562D01*
X544291Y-233268D01*
X542496Y-227154D02*
X543059Y-226591D01*
X536367Y-227154D02*
X542496D01*
X543059Y-226591D02*
X543276D01*
X536367Y-225186D02*
X541079D01*
X542017Y-224248D01*
X544294D01*
X348876Y-236993D02*
X353709D01*
X356852Y-237636D02*
Y-235236D01*
X355527Y-238961D02*
X356852Y-237636D01*
X355403Y-242898D02*
X361499Y-236802D01*
X359099Y-235389D02*
X359252Y-235236D01*
X359099Y-237228D02*
Y-235389D01*
X355397Y-240930D02*
X359099Y-237228D01*
X348876Y-240930D02*
X355397D01*
X348876Y-238961D02*
X355527D01*
X348876Y-242898D02*
X355403D01*
X353559Y-227150D02*
X354178Y-226531D01*
X348876Y-227150D02*
X348876Y-227150D01*
X353559D01*
X348968Y-229027D02*
X354634D01*
X348876Y-231087D02*
X354413D01*
X348876Y-229119D02*
X348968Y-229027D01*
X406206Y-168420D02*
X406298Y-168512D01*
X407480Y-163475D02*
X408266Y-164261D01*
Y-168512D02*
Y-164261D01*
X407480Y-163475D02*
Y-163386D01*
X33465Y-8858D02*
Y-4626D01*
X40354Y-8858D02*
Y-4626D01*
X47244Y-8858D02*
Y-4626D01*
Y14764D02*
Y19685D01*
X40354Y14764D02*
Y19685D01*
X26575Y14764D02*
Y19685D01*
X33465Y14764D02*
Y19833D01*
X47244Y689D02*
Y8858D01*
X40354Y689D02*
Y8858D01*
X33465Y689D02*
Y8858D01*
X26575Y689D02*
Y8858D01*
X80709Y-232283D02*
X82677D01*
X79232Y-230807D02*
Y-221949D01*
Y-230807D02*
X80709Y-232283D01*
X75787Y-221457D02*
X78740D01*
X79232Y-221949D01*
X83661Y-275590D02*
X87598D01*
X79724Y-285433D02*
X81693Y-287402D01*
X79724Y-285433D02*
Y-276575D01*
X75787Y-275590D02*
X78740D01*
X79724Y-276575D01*
X78740Y-340551D02*
Y-330193D01*
X78272Y-329724D02*
X78740Y-330193D01*
X74803Y-329724D02*
X78272D01*
X80266Y-328298D02*
X81207D01*
X77756Y-325787D02*
X80266Y-328298D01*
X77756Y-325787D02*
Y-322835D01*
X81207Y-328298D02*
X81568Y-328659D01*
Y-329600D02*
Y-328659D01*
X86614Y-169291D02*
X86614Y-169291D01*
X74803Y-169488D02*
X75000Y-169291D01*
X78740Y-178150D02*
X80709Y-180118D01*
X78740Y-178150D02*
Y-170276D01*
X77756Y-169291D02*
X78740Y-170276D01*
X74803Y-169291D02*
X77756D01*
X80813Y-322041D02*
X81004Y-321850D01*
X78550Y-322041D02*
X80813D01*
X77756Y-322835D02*
X78550Y-322041D01*
X68602Y-319882D02*
X73819D01*
X74803Y-329724D02*
Y-320866D01*
X73819Y-319882D02*
X74803Y-320866D01*
X78740Y-271654D02*
X82677Y-275590D01*
X78740Y-271654D02*
Y-268701D01*
X81798Y-267907D02*
X81988Y-267717D01*
X79534Y-267907D02*
X81798D01*
X78740Y-268701D02*
X79534Y-267907D01*
X75787Y-275590D02*
Y-266732D01*
X69587Y-265748D02*
X74803D01*
X75787Y-266732D01*
X38139Y-316781D02*
X38189Y-316831D01*
Y-291732D01*
Y-316831D02*
X38287Y-316929D01*
X38189Y-263630D02*
Y-262894D01*
Y-283071D02*
Y-263630D01*
X38780Y-263287D02*
X39272Y-262795D01*
X-8465Y-263630D02*
X38189D01*
Y-262894D02*
X38287Y-262795D01*
X39272D02*
X55315D01*
X78740Y-218504D02*
X81693Y-221457D01*
X78740Y-216020D02*
X79209Y-215551D01*
X81988D01*
X78740Y-218504D02*
Y-216020D01*
X69587Y-213583D02*
X69587Y-213583D01*
X73819D01*
X75787Y-215551D01*
Y-221457D02*
Y-215551D01*
X38138Y-210480D02*
X38189Y-210429D01*
X38138Y-210480D02*
X38287Y-210630D01*
X55315D01*
X38189Y-210429D02*
Y-184055D01*
Y-175394D02*
X38287Y-175295D01*
Y-157480D01*
X80955Y-162450D02*
X81004Y-162402D01*
X77756Y-163386D02*
X78692Y-162450D01*
X80955D01*
X77756Y-166339D02*
Y-163386D01*
Y-166339D02*
X79724Y-168307D01*
X68602Y-160433D02*
X72835D01*
X74803Y-169291D02*
Y-162402D01*
X72835Y-160433D02*
X74803Y-162402D01*
X65945Y-158465D02*
X68602D01*
X64961Y-157480D02*
X65945Y-158465D01*
X64961Y-157480D02*
X65945Y-156496D01*
X68602D01*
X59842Y-157480D02*
X64961D01*
X66929Y-209646D02*
X69587D01*
X65945Y-210630D02*
X66929Y-209646D01*
X65945Y-210630D02*
X66929Y-211614D01*
X60827Y-210630D02*
X65945D01*
X66929Y-211614D02*
X69587D01*
X65729Y-262795D02*
X66713Y-263779D01*
X69587D01*
X66713Y-261811D02*
X69587D01*
X65729Y-262795D02*
X66713Y-261811D01*
X60827Y-262795D02*
X65729D01*
X64961Y-316929D02*
X65945Y-317913D01*
X68602D01*
X65945Y-315945D02*
X68602D01*
X64961Y-316929D02*
X65945Y-315945D01*
X59646Y-316929D02*
X64961D01*
X38287D02*
X54134D01*
X-8465Y-316781D02*
X38139D01*
X-8465Y-210480D02*
X38138D01*
X38139Y-157332D02*
X38287Y-157480D01*
X-8465Y-157332D02*
X38139D01*
X323850Y-241173D02*
X323882Y-241205D01*
X327144D01*
X323850Y-237205D02*
X327175D01*
X323819Y-227362D02*
X327175D01*
X328387Y-229119D02*
X332932D01*
X327418Y-231087D02*
X332932D01*
X328144Y-229362D02*
X328387Y-229119D01*
X327143Y-231362D02*
X327418Y-231087D01*
X323819Y-231299D02*
X323882Y-231362D01*
X325787Y-229362D02*
X328144D01*
X323882Y-231362D02*
X327143D01*
X327418Y-240930D02*
X332932D01*
X327144Y-241205D02*
X327418Y-240930D01*
X328387Y-238961D02*
X332932D01*
X328143Y-239205D02*
X328387Y-238961D01*
X325787Y-239205D02*
X328143D01*
X327387Y-236993D02*
X332932D01*
X327175Y-237205D02*
X327387Y-236993D01*
X327175Y-227362D02*
X327387Y-227150D01*
X332932D01*
X-20122Y-342673D02*
X-19685Y-343110D01*
X-23469Y-342673D02*
X-20122D01*
X-23622Y-342520D02*
X-23469Y-342673D01*
X101378Y-135138D02*
X101394Y-135153D01*
X87254Y-133218D02*
X90551Y-129921D01*
X87254Y-139629D02*
Y-133218D01*
X89567Y-140270D02*
Y-132874D01*
X112579Y-131968D02*
X117047D01*
X112500Y-131890D02*
X112579Y-131968D01*
X116298Y-130047D02*
X119095D01*
X117047Y-131968D02*
X117126Y-132047D01*
X105331Y-112221D02*
X105347Y-112205D01*
X105331Y-116815D02*
Y-112221D01*
X107346Y-116768D02*
Y-110236D01*
X99283Y-113033D02*
Y-110299D01*
X99347Y-110236D01*
X109331Y-116752D02*
Y-112315D01*
X109409Y-112236D01*
X112501Y-122047D02*
X119095D01*
X112500Y-122047D02*
X112501Y-122047D01*
X-23622Y-290354D02*
X-19685D01*
X-23469Y-286570D02*
X-19926D01*
X-19685Y-286811D01*
X-23622Y-286417D02*
X-23469Y-286570D01*
Y-282633D02*
X-18843D01*
X-23622Y-282480D02*
X-23469Y-282633D01*
X-18843D02*
X-18406Y-283071D01*
X-23469Y-237052D02*
X-19926D01*
X-23622Y-237205D02*
X-23469Y-237052D01*
X-19926D02*
X-19685Y-236811D01*
X-23622Y-233268D02*
X-19685D01*
X-23622Y-229331D02*
X-23524Y-229429D01*
X-18504D02*
X-18406Y-229528D01*
X-23524Y-229429D02*
X-18504D01*
X-23622Y-339567D02*
X-19685D01*
X-23622Y-335630D02*
X-23524Y-335728D01*
X-18504D02*
X-18406Y-335827D01*
X-23524Y-335728D02*
X-18504D01*
X109252Y-116831D02*
X109331Y-116752D01*
X107409Y-141732D02*
Y-138935D01*
X99410Y-141732D02*
Y-135138D01*
X-23622Y-184055D02*
X-19685D01*
X-23622Y-181102D02*
X-23469Y-180949D01*
X-20122D02*
X-19685Y-180512D01*
X-23469Y-180949D02*
X-20122D01*
X-23469Y-177012D02*
X-18646D01*
X-18406Y-176772D01*
X-23622Y-177165D02*
X-23469Y-177012D01*
X-23622Y-110236D02*
X-19685D01*
X-23469Y-106452D02*
X-19926D01*
X-19685Y-106693D01*
X-23622Y-106299D02*
X-23469Y-106452D01*
X-18843Y-102515D02*
X-18406Y-102953D01*
X-23469Y-102515D02*
X-18843D01*
X-23622Y-102362D02*
X-23469Y-102515D01*
X-23622Y-66929D02*
X-19685D01*
X-23469Y-63145D02*
X-19926D01*
X-19685Y-63386D01*
X-23622Y-62992D02*
X-23469Y-63145D01*
Y-59886D02*
X-18646D01*
X-23622Y-60039D02*
X-23469Y-59886D01*
X-18646D02*
X-18406Y-59646D01*
X116172Y-129921D02*
X116298Y-130047D01*
X117111Y-124031D02*
X117126Y-124047D01*
X112500Y-129921D02*
X116172D01*
X117079Y-128000D02*
X117126Y-128047D01*
X112547Y-128000D02*
X117079D01*
X112500Y-127953D02*
X112547Y-128000D01*
X112515Y-124031D02*
X117111D01*
X112500Y-124016D02*
X112515Y-124031D01*
X112579Y-120000D02*
X117047D01*
X112500Y-120079D02*
X112579Y-120000D01*
X117047D02*
X117126Y-119921D01*
X99283Y-113033D02*
X99410Y-113159D01*
Y-116831D02*
Y-113159D01*
X107283Y-116831D02*
X107346Y-116768D01*
X105315Y-116831D02*
X105331Y-116815D01*
X97284Y-112205D02*
X97362Y-112284D01*
X101284Y-112205D02*
X101331Y-112252D01*
X97362Y-116752D02*
Y-112284D01*
X101331Y-116783D02*
X101378Y-116831D01*
X97362Y-116752D02*
X97441Y-116831D01*
X101331Y-116783D02*
Y-112252D01*
X109252Y-135138D02*
X109331Y-135216D01*
X107283Y-138809D02*
Y-135138D01*
Y-138809D02*
X107409Y-138935D01*
X105315Y-135138D02*
X105362Y-135185D01*
X97425Y-135153D02*
X97441Y-135138D01*
X89567Y-132874D02*
X90551Y-131890D01*
X94193D01*
X90551Y-129921D02*
X94193D01*
X544261Y-195688D02*
X544291Y-195718D01*
X536397Y-195688D02*
X544261D01*
X536367Y-195658D02*
X536397Y-195688D01*
X528691Y-117716D02*
X533878D01*
X524459Y-125984D02*
X524606Y-125836D01*
X519808Y-128715D02*
X524533D01*
X519931Y-125984D02*
X524459D01*
X524533Y-128715D02*
X524557Y-128740D01*
X450850Y-174127D02*
Y-173910D01*
X451573Y-173187D01*
Y-168512D01*
X519783Y-123572D02*
X527264D01*
X528445Y-122391D02*
Y-117667D01*
X516634Y-123572D02*
X519783D01*
X527264D02*
X528445Y-122391D01*
X512795Y-111663D02*
X513189Y-112057D01*
X512795Y-111663D02*
Y-104214D01*
Y-104183D01*
X463551Y-116210D02*
X464370Y-117029D01*
X463551Y-116210D02*
Y-116025D01*
X649390Y-37647D02*
X658465D01*
X649390Y-29773D02*
X658465D01*
X625000Y-21899D02*
X631890D01*
X298425Y-118947D02*
X314961D01*
X298484Y-128887D02*
X306616D01*
X306844Y-128659D01*
X309016D01*
X418898Y-144360D02*
Y-144143D01*
X418109Y-145148D02*
X418898Y-144360D01*
X418109Y-152568D02*
Y-145148D01*
X416106Y-144180D02*
X416123Y-144197D01*
X398424Y-152568D02*
Y-145227D01*
X398568Y-145083D01*
X416123Y-152551D02*
X416140Y-152568D01*
X519783Y-128691D02*
X519808Y-128715D01*
X59842Y-157480D02*
X60236Y-157874D01*
X74803Y-170472D02*
Y-170466D01*
X447835Y-132726D02*
Y-128592D01*
Y-132726D02*
X452756Y-137647D01*
X456398D01*
X456890Y-137155D02*
Y-130034D01*
X456398Y-137647D02*
X456890Y-137155D01*
X528543Y-117569D02*
X528691Y-117716D01*
X528445Y-117667D02*
X528543Y-117569D01*
X513189Y-117667D02*
Y-112057D01*
X443699Y-174634D02*
Y-168512D01*
X443898Y-175049D02*
Y-174832D01*
X443699Y-174634D02*
X443898Y-174832D01*
X91536Y-57923D02*
X99410D01*
X91536Y-65797D02*
X99410D01*
X65945Y-50049D02*
X74036D01*
X65945Y-65797D02*
X74036D01*
X464370Y-121639D02*
Y-117029D01*
X519783Y-126131D02*
X519931Y-125984D01*
X456742Y-116043D02*
X456816Y-116117D01*
Y-121565D02*
X456890Y-121639D01*
X456816Y-121565D02*
Y-116117D01*
X464328Y-146613D02*
Y-146397D01*
X463384Y-147557D02*
X464328Y-146613D01*
X463384Y-152568D02*
Y-147557D01*
X469291Y-143849D02*
X469291Y-143848D01*
X461368Y-152519D02*
Y-143798D01*
X469291Y-152568D02*
Y-143849D01*
X461319Y-143750D02*
X461368Y-143798D01*
X460925Y-137647D02*
X461024Y-137746D01*
X463189Y-137647D02*
X469488D01*
X460925D02*
X463189D01*
X469340Y-175098D02*
X469390Y-175147D01*
X457283D02*
X457387Y-175043D01*
X469340Y-175098D02*
Y-168562D01*
X457387Y-175043D02*
Y-168604D01*
X469290Y-168512D02*
X469340Y-168562D01*
X425983Y-173847D02*
Y-168512D01*
X402313Y-175295D02*
Y-168561D01*
X402361Y-168512D01*
X402264Y-175344D02*
X402313Y-175295D01*
X461368Y-152519D02*
X461416Y-152568D01*
X536397Y-215373D02*
X544261D01*
X544291Y-215403D01*
X536367Y-215343D02*
X536397Y-215373D01*
X514075Y-126131D02*
X516634Y-123572D01*
X511713Y-126131D02*
X514075D01*
X511713Y-121013D02*
X511811Y-120915D01*
Y-119045D01*
X513189Y-117667D01*
X464370Y-136466D02*
Y-130034D01*
X463189Y-137647D02*
X464370Y-136466D01*
X512402Y-261958D02*
X514999Y-264556D01*
X520423D01*
X513818Y-266524D02*
X520423D01*
X512402Y-265108D02*
X513818Y-266524D01*
X512759Y-268065D02*
X513187Y-268493D01*
X512543Y-268065D02*
X512759D01*
X513187Y-268493D02*
X520423D01*
X457387Y-168604D02*
X457479Y-168512D01*
X437746Y-168561D02*
X437794Y-168512D01*
X437746Y-175197D02*
Y-168561D01*
X437697Y-175246D02*
X437746Y-175197D01*
X433858Y-175245D02*
Y-168512D01*
X433857Y-168512D02*
X433858Y-168512D01*
Y-175245D02*
X433858Y-175246D01*
X427951Y-168512D02*
X428043Y-168604D01*
X416140Y-168512D02*
X416142Y-168513D01*
X404329Y-174634D02*
Y-168512D01*
Y-174634D02*
X404823Y-175128D01*
Y-175344D02*
Y-175128D01*
X469290Y-152568D02*
X469291Y-152568D01*
X298465Y-113986D02*
X309016D01*
X309055Y-114025D01*
X199311Y-115009D02*
X199803Y-114517D01*
X200088Y-114399D02*
X209252D01*
X193898Y-115009D02*
X199311D01*
X193898Y-119931D02*
X199311D01*
X298425Y-128946D02*
X298484Y-128887D01*
X298465Y-123907D02*
X309016D01*
X309055Y-123868D01*
X298425Y-123946D02*
X298465Y-123907D01*
X298425Y-113946D02*
X298465Y-113986D01*
X348915Y-252727D02*
X348945Y-252757D01*
X276969Y-399280D02*
X277165Y-399477D01*
X222047Y-401427D02*
X222244Y-401230D01*
Y-388041D01*
X225394Y-384891D02*
Y-372293D01*
X222244Y-388041D02*
X225394Y-384891D01*
X277244Y-402150D02*
X277441Y-401953D01*
X134744Y-347244D02*
X134941Y-347441D01*
D28*
X55118Y-43307D02*
X55905Y-42520D01*
X47244Y-43307D02*
X55118D01*
X64518Y-42175D02*
X74036D01*
X64173Y-42520D02*
X64518Y-42175D01*
X64173Y-42520D02*
X64173Y-42520D01*
X55905Y-42520D02*
X64173D01*
X659449Y-49213D02*
X661319D01*
X663287Y-47244D02*
X665354D01*
X661319Y-49213D02*
X663287Y-47244D01*
X665748Y-23622D02*
X666142Y-23228D01*
Y-16142D01*
X664961Y-14961D02*
X666142Y-16142D01*
X660236Y-14961D02*
X664961D01*
X659301Y-14025D02*
X660236Y-14961D01*
X649390Y-14025D02*
X659301D01*
X665354Y-55118D02*
Y-47244D01*
X663779Y-56693D02*
X665354Y-55118D01*
X655758Y-45521D02*
X659449Y-49213D01*
X649390Y-45521D02*
X655758D01*
X171791Y-344590D02*
Y-349588D01*
X173458Y-351254D01*
X175124Y-349588D01*
X176790Y-351254D01*
X178456Y-349588D01*
Y-344590D01*
X181788D02*
Y-349588D01*
X183454Y-351254D01*
X185120Y-349588D01*
X186786Y-351254D01*
X188453Y-349588D01*
Y-344590D01*
X191785D02*
Y-349588D01*
X193451Y-351254D01*
X195117Y-349588D01*
X196783Y-351254D01*
X198449Y-349588D01*
Y-344590D01*
X201782Y-351254D02*
Y-349588D01*
X203448D01*
Y-351254D01*
X201782D01*
X211778Y-342924D02*
Y-344590D01*
X210112D01*
X213444D01*
X211778D01*
Y-349588D01*
X213444Y-351254D01*
X218443D02*
X221775D01*
X220109D01*
Y-344590D01*
X218443D01*
X226774Y-351254D02*
Y-344590D01*
X228440D01*
X230106Y-346256D01*
Y-351254D01*
Y-346256D01*
X231772Y-344590D01*
X233438Y-346256D01*
Y-351254D01*
X236770D02*
X240103D01*
X238437D01*
Y-344590D01*
X236770D01*
X245101Y-351254D02*
Y-344590D01*
X250099D01*
X251765Y-346256D01*
Y-351254D01*
X258430Y-354587D02*
X260096D01*
X261762Y-352921D01*
Y-344590D01*
X256764D01*
X255098Y-346256D01*
Y-349588D01*
X256764Y-351254D01*
X261762D01*
X271759Y-344590D02*
X266761D01*
X265094Y-346256D01*
Y-349588D01*
X266761Y-351254D01*
X271759D01*
X276757Y-344590D02*
X280090D01*
X281756Y-346256D01*
Y-351254D01*
X276757D01*
X275091Y-349588D01*
X276757Y-347922D01*
X281756D01*
X285088Y-344590D02*
Y-351254D01*
Y-347922D01*
X286754Y-346256D01*
X288420Y-344590D01*
X290086D01*
X301749Y-341258D02*
Y-351254D01*
X296751D01*
X295085Y-349588D01*
Y-346256D01*
X296751Y-344590D01*
X301749D01*
X305082Y-351254D02*
Y-349588D01*
X306748D01*
Y-351254D01*
X305082D01*
X320077Y-344590D02*
X315078D01*
X313412Y-346256D01*
Y-349588D01*
X315078Y-351254D01*
X320077D01*
X325075D02*
X328407D01*
X330073Y-349588D01*
Y-346256D01*
X328407Y-344590D01*
X325075D01*
X323409Y-346256D01*
Y-349588D01*
X325075Y-351254D01*
X333406D02*
Y-344590D01*
X335072D01*
X336738Y-346256D01*
Y-351254D01*
Y-346256D01*
X338404Y-344590D01*
X340070Y-346256D01*
Y-351254D01*
D34*
X82677Y-128740D02*
D03*
Y-123228D02*
D03*
X55905Y-42520D02*
D03*
Y-37008D02*
D03*
X111417Y-43307D02*
D03*
Y-37795D02*
D03*
X568110Y-117717D02*
D03*
Y-123228D02*
D03*
X67913Y-335433D02*
D03*
Y-329921D02*
D03*
X114173Y-73868D02*
D03*
Y-79379D02*
D03*
X98425Y-92568D02*
D03*
Y-98080D02*
D03*
X348106Y-104238D02*
D03*
Y-98726D02*
D03*
X447835Y-128592D02*
D03*
Y-123080D02*
D03*
X67913Y-169488D02*
D03*
Y-175000D02*
D03*
X68898Y-275787D02*
D03*
Y-281299D02*
D03*
X68898Y-221654D02*
D03*
Y-227165D02*
D03*
X528543Y-112057D02*
D03*
Y-117569D02*
D03*
D35*
X66142Y-113779D02*
D03*
X69291D02*
D03*
X66142Y-110236D02*
D03*
X69291D02*
D03*
X69291Y-117717D02*
D03*
X66142D02*
D03*
X551968Y-270866D02*
D03*
X548819D02*
D03*
X672047Y-242126D02*
D03*
X675197D02*
D03*
X561417Y-205512D02*
D03*
X564567D02*
D03*
X561417Y-209055D02*
D03*
X564567D02*
D03*
X550394Y-109055D02*
D03*
X553543D02*
D03*
X565748Y-109449D02*
D03*
X562598D02*
D03*
X548819Y-274803D02*
D03*
X551968D02*
D03*
X683858Y-301969D02*
D03*
X680709D02*
D03*
X683858Y-306299D02*
D03*
X680709D02*
D03*
X493307Y-109055D02*
D03*
X490158D02*
D03*
X473622Y-116929D02*
D03*
X470472D02*
D03*
X486614Y-109055D02*
D03*
X483465D02*
D03*
X505905Y-119685D02*
D03*
X502756D02*
D03*
X472835Y-134646D02*
D03*
X475984D02*
D03*
X479921Y-109055D02*
D03*
X476772D02*
D03*
X426378Y-183858D02*
D03*
X423228D02*
D03*
D36*
X685827Y-29577D02*
D03*
Y-25541D02*
D03*
D37*
X662598Y-82638D02*
D03*
Y-79567D02*
D03*
X675591Y-79882D02*
D03*
Y-76811D02*
D03*
D38*
X553504Y-244882D02*
D03*
X577205D02*
D03*
X605472Y-191339D02*
D03*
X629173D02*
D03*
X655158Y-254331D02*
D03*
X631457D02*
D03*
D39*
X601492Y-275984D02*
D03*
X624492D02*
D03*
X628035Y-215748D02*
D03*
X605035D02*
D03*
D40*
X608268Y-81890D02*
D03*
X611811D02*
D03*
X604528Y-101181D02*
D03*
X608071D02*
D03*
X581693Y-80709D02*
D03*
X585236D02*
D03*
X574016Y-106299D02*
D03*
X577559D02*
D03*
X629331Y-86614D02*
D03*
X625787D02*
D03*
X604921Y-89764D02*
D03*
X608465D02*
D03*
X629724Y-99606D02*
D03*
X626181D02*
D03*
X604921Y-95276D02*
D03*
X608465D02*
D03*
X572244Y-88189D02*
D03*
X575787D02*
D03*
X596260Y-98032D02*
D03*
X592717D02*
D03*
X571850Y-100394D02*
D03*
X575394D02*
D03*
X682087Y-41339D02*
D03*
X678543D02*
D03*
D41*
X235039Y-116831D02*
D03*
Y-113878D02*
D03*
X259842Y-118996D02*
D03*
Y-121949D02*
D03*
D42*
X240453Y-122441D02*
D03*
X237500D02*
D03*
X259350Y-104724D02*
D03*
X256398D02*
D03*
X678051Y-67716D02*
D03*
X681004D02*
D03*
X439665Y-111024D02*
D03*
X436713D02*
D03*
X406693Y-110630D02*
D03*
X409646D02*
D03*
X242618Y-114173D02*
D03*
X245571D02*
D03*
X242618Y-130709D02*
D03*
X245571D02*
D03*
X256988Y-115354D02*
D03*
X254035D02*
D03*
X255413Y-130709D02*
D03*
X252461D02*
D03*
D43*
X688197Y-322441D02*
D03*
X684243D02*
D03*
X688197Y-315748D02*
D03*
X684243D02*
D03*
D44*
X675787Y-323228D02*
D03*
X669882D02*
D03*
X675787Y-315748D02*
D03*
X669882D02*
D03*
D45*
X169488Y-109449D02*
D03*
X163583D02*
D03*
X82677Y-135827D02*
D03*
X76772D02*
D03*
X148622Y-109449D02*
D03*
X154527D02*
D03*
D46*
X266535Y-118898D02*
D03*
X271654D02*
D03*
X269488Y-129134D02*
D03*
X264370D02*
D03*
D47*
X239764Y-108268D02*
D03*
X234252D02*
D03*
X665354Y-47244D02*
D03*
X670866D02*
D03*
X608268Y-44882D02*
D03*
X602756D02*
D03*
X666142Y-16142D02*
D03*
X671654D02*
D03*
X615522Y-14017D02*
D03*
X610010D02*
D03*
X263976Y-112057D02*
D03*
X269488D02*
D03*
X518701D02*
D03*
X513189D02*
D03*
D48*
X681102Y-83858D02*
D03*
Y-86417D02*
D03*
Y-88976D02*
D03*
Y-91535D02*
D03*
Y-94095D02*
D03*
D49*
X681004Y-47577D02*
D03*
X682776D02*
D03*
X684547D02*
D03*
X686319D02*
D03*
X688091D02*
D03*
X689862D02*
D03*
Y-58723D02*
D03*
X688091D02*
D03*
X686319D02*
D03*
X684547D02*
D03*
X682776D02*
D03*
D50*
X681004D02*
D03*
D51*
X672441Y-106992D02*
D03*
Y-100882D02*
D03*
D52*
X671260Y-82874D02*
D03*
Y-79331D02*
D03*
X594095Y-83268D02*
D03*
Y-86811D02*
D03*
X667717Y-82874D02*
D03*
Y-79331D02*
D03*
X696457Y-44685D02*
D03*
Y-48228D02*
D03*
D53*
X662683Y-110630D02*
D03*
X665664D02*
D03*
X589848Y-237402D02*
D03*
X592829D02*
D03*
X500309Y-109843D02*
D03*
X497329D02*
D03*
D54*
X695140Y-66142D02*
D03*
X692262D02*
D03*
X628998Y-93307D02*
D03*
X626120D02*
D03*
X551439Y-279921D02*
D03*
X548561D02*
D03*
X640293Y-277953D02*
D03*
X643171D02*
D03*
D55*
X667717Y-94488D02*
D03*
X671654D02*
D03*
D56*
X679528Y-29921D02*
D03*
Y-33858D02*
D03*
X560236Y-201575D02*
D03*
Y-197638D02*
D03*
X547835Y-261614D02*
D03*
Y-257677D02*
D03*
D57*
X686614Y-36356D02*
D03*
Y-39234D02*
D03*
X694095Y-36492D02*
D03*
Y-39370D02*
D03*
X597244Y-90687D02*
D03*
Y-93565D02*
D03*
X250394Y-109191D02*
D03*
Y-112069D02*
D03*
X681890Y-208661D02*
D03*
Y-205783D02*
D03*
X562598Y-213128D02*
D03*
Y-216006D02*
D03*
D58*
X421122Y-112697D02*
D03*
X426122D02*
D03*
Y-136909D02*
D03*
X421122D02*
D03*
D59*
X409842Y-132874D02*
D03*
Y-126969D02*
D03*
X436614Y-132480D02*
D03*
Y-126575D02*
D03*
X40354Y14764D02*
D03*
Y8858D02*
D03*
X33465Y14764D02*
D03*
Y8858D02*
D03*
X26575Y14764D02*
D03*
Y8858D02*
D03*
X47244Y14764D02*
D03*
Y8858D02*
D03*
D60*
X409730Y-119764D02*
D03*
Y-115810D02*
D03*
X436614Y-120866D02*
D03*
Y-116912D02*
D03*
D61*
X548524Y-265945D02*
D03*
X551870D02*
D03*
X134744Y-347244D02*
D03*
X131398D02*
D03*
X134744Y-342913D02*
D03*
X131398D02*
D03*
D62*
X660236Y-195315D02*
D03*
Y-171614D02*
D03*
D63*
X683362Y-183296D02*
D03*
Y-187064D02*
D03*
D64*
X640945Y-211122D02*
D03*
Y-200689D02*
D03*
X576772Y-150492D02*
D03*
Y-140059D02*
D03*
D65*
X634862Y-233858D02*
D03*
X626555D02*
D03*
X623839Y-296063D02*
D03*
X615531D02*
D03*
D66*
X650394Y-227559D02*
D03*
Y-222047D02*
D03*
X674409Y-210236D02*
D03*
Y-204724D02*
D03*
X643307Y-297638D02*
D03*
Y-292126D02*
D03*
D67*
X614961Y-239764D02*
D03*
X618898D02*
D03*
X558661Y-286614D02*
D03*
X562598D02*
D03*
D68*
X588793Y-207929D02*
D03*
X577618Y-266535D02*
D03*
D69*
X588793Y-215409D02*
D03*
X577618Y-274016D02*
D03*
D70*
X559533Y-221654D02*
D03*
X563301D02*
D03*
X548116Y-291732D02*
D03*
X551884D02*
D03*
X666451Y-276378D02*
D03*
X662683D02*
D03*
D71*
X567717Y-220079D02*
D03*
Y-224016D02*
D03*
X607874Y-293307D02*
D03*
Y-297244D02*
D03*
D72*
X594488Y-231398D02*
D03*
Y-228445D02*
D03*
X594095Y-285335D02*
D03*
Y-282382D02*
D03*
D73*
X599213Y-242717D02*
D03*
Y-236811D02*
D03*
D74*
X613976Y-233465D02*
D03*
X619882D02*
D03*
X597441Y-295669D02*
D03*
X603346D02*
D03*
X569488Y-291732D02*
D03*
X575394D02*
D03*
D75*
X608563Y-232283D02*
D03*
X604823D02*
D03*
X550098Y-200394D02*
D03*
X553839D02*
D03*
X581595Y-289764D02*
D03*
X585335D02*
D03*
X548228Y-285039D02*
D03*
X551968D02*
D03*
D76*
X675591Y-178150D02*
D03*
Y-191142D02*
D03*
D77*
X666929Y-209317D02*
D03*
Y-205643D02*
D03*
X553543Y-221391D02*
D03*
Y-225065D02*
D03*
D78*
X658661Y-235846D02*
D03*
Y-230847D02*
D03*
Y-225847D02*
D03*
Y-220847D02*
D03*
X679921D02*
D03*
Y-225847D02*
D03*
Y-230847D02*
D03*
Y-235846D02*
D03*
X650787Y-307500D02*
D03*
Y-302500D02*
D03*
Y-297500D02*
D03*
Y-292500D02*
D03*
X672047D02*
D03*
Y-297500D02*
D03*
Y-302500D02*
D03*
Y-307500D02*
D03*
D79*
X667717Y-245276D02*
D03*
Y-242126D02*
D03*
X504724Y-109843D02*
D03*
Y-112992D02*
D03*
X508661Y-109843D02*
D03*
Y-112992D02*
D03*
X473622Y-123622D02*
D03*
Y-120472D02*
D03*
X140157Y-131102D02*
D03*
Y-127953D02*
D03*
D80*
X596063Y-183560D02*
D03*
Y-193605D02*
D03*
X586614Y-183560D02*
D03*
Y-193605D02*
D03*
X594488Y-248521D02*
D03*
Y-258566D02*
D03*
X605512Y-248914D02*
D03*
Y-258960D02*
D03*
D81*
X599213Y-231594D02*
D03*
Y-228248D02*
D03*
X566142Y-201279D02*
D03*
Y-197933D02*
D03*
X552953Y-261319D02*
D03*
Y-257972D02*
D03*
D82*
X643701Y-223858D02*
D03*
Y-227323D02*
D03*
X502756Y-123858D02*
D03*
Y-127323D02*
D03*
D83*
X554724Y-211516D02*
D03*
Y-215256D02*
D03*
D84*
X596063Y-147343D02*
D03*
Y-121161D02*
D03*
D85*
X551968Y-169291D02*
D03*
X577953D02*
D03*
D86*
X634154Y-269291D02*
D03*
X644587D02*
D03*
D87*
X558137Y-292520D02*
D03*
X561811D02*
D03*
X667217Y-252303D02*
D03*
X663543D02*
D03*
D88*
X581791Y-285433D02*
D03*
X585138D02*
D03*
D89*
X591732Y-292829D02*
D03*
Y-289848D02*
D03*
D90*
X670669Y-268504D02*
D03*
X657677D02*
D03*
D91*
X668110Y-260236D02*
D03*
X662598D02*
D03*
X531890Y-133858D02*
D03*
X537402D02*
D03*
D92*
X662835Y-283071D02*
D03*
X666299D02*
D03*
X535984Y-141339D02*
D03*
X532520D02*
D03*
X496299D02*
D03*
X499764D02*
D03*
X496299Y-137402D02*
D03*
X499764D02*
D03*
X502205Y-133465D02*
D03*
X505669D02*
D03*
D93*
X558681Y-137008D02*
D03*
X553681D02*
D03*
X548681D02*
D03*
X543681D02*
D03*
Y-115748D02*
D03*
X548681D02*
D03*
X553681D02*
D03*
X558681D02*
D03*
D94*
X479872Y-125394D02*
D03*
Y-123425D02*
D03*
Y-121457D02*
D03*
Y-119488D02*
D03*
X498081D02*
D03*
Y-121457D02*
D03*
Y-123425D02*
D03*
Y-125394D02*
D03*
D95*
X497835Y-128593D02*
D03*
X495866D02*
D03*
X493898D02*
D03*
X491929D02*
D03*
X489961D02*
D03*
X487992D02*
D03*
X486024D02*
D03*
X484055D02*
D03*
X482087D02*
D03*
X480118D02*
D03*
Y-116289D02*
D03*
X482087D02*
D03*
X484055D02*
D03*
X486024D02*
D03*
X487992D02*
D03*
X489961D02*
D03*
X491929D02*
D03*
X493898D02*
D03*
X495866D02*
D03*
X497835D02*
D03*
D96*
X47244Y-35433D02*
D03*
Y-43307D02*
D03*
X124409Y-37008D02*
D03*
Y-44882D02*
D03*
X89567Y-98277D02*
D03*
Y-90403D02*
D03*
X123031Y-79970D02*
D03*
Y-72096D02*
D03*
D97*
X671654Y-56693D02*
D03*
X663779D02*
D03*
X601575Y-53937D02*
D03*
X609449D02*
D03*
X673622Y-23622D02*
D03*
X665748D02*
D03*
X609252Y-21506D02*
D03*
X617126D02*
D03*
D98*
X631890Y-61269D02*
D03*
Y-53395D02*
D03*
Y-45521D02*
D03*
Y-37647D02*
D03*
X649390Y-61269D02*
D03*
Y-53395D02*
D03*
Y-45521D02*
D03*
Y-69143D02*
D03*
Y-14025D02*
D03*
Y-29773D02*
D03*
Y-21899D02*
D03*
Y-37647D02*
D03*
X631890Y-14025D02*
D03*
Y-21899D02*
D03*
Y-29773D02*
D03*
Y-69143D02*
D03*
X91536Y-26427D02*
D03*
Y-34301D02*
D03*
Y-42175D02*
D03*
Y-50049D02*
D03*
X74036Y-26427D02*
D03*
Y-34301D02*
D03*
Y-42175D02*
D03*
Y-18553D02*
D03*
Y-73671D02*
D03*
Y-57923D02*
D03*
Y-65797D02*
D03*
Y-50049D02*
D03*
X91536Y-73671D02*
D03*
Y-65797D02*
D03*
Y-57923D02*
D03*
Y-18553D02*
D03*
X649390Y-14025D02*
D03*
Y-29773D02*
D03*
Y-21899D02*
D03*
Y-37647D02*
D03*
X631890Y-14025D02*
D03*
Y-21899D02*
D03*
Y-29773D02*
D03*
Y-37647D02*
D03*
X74036Y-73671D02*
D03*
Y-57923D02*
D03*
Y-65797D02*
D03*
Y-50049D02*
D03*
X91536Y-73671D02*
D03*
Y-65797D02*
D03*
Y-57923D02*
D03*
Y-50049D02*
D03*
D99*
X474906Y-308553D02*
D03*
X386914D02*
D03*
Y-160521D02*
D03*
X474906D02*
D03*
D100*
X437795Y-300625D02*
D03*
X439763D02*
D03*
X414173D02*
D03*
X398425D02*
D03*
X410236D02*
D03*
X418110D02*
D03*
X406299D02*
D03*
X427952D02*
D03*
X424015D02*
D03*
X408267Y-316569D02*
D03*
X416141D02*
D03*
X410236D02*
D03*
X398425D02*
D03*
X400393Y-300625D02*
D03*
X404330D02*
D03*
X455511D02*
D03*
X433858D02*
D03*
X414173Y-316569D02*
D03*
X404330D02*
D03*
X408267Y-300625D02*
D03*
X416141D02*
D03*
X420078D02*
D03*
X435826D02*
D03*
X400393Y-316569D02*
D03*
X425984Y-300625D02*
D03*
X429921D02*
D03*
X406299Y-316569D02*
D03*
X445669Y-300625D02*
D03*
X443700D02*
D03*
X449606Y-316569D02*
D03*
X455511D02*
D03*
X420078D02*
D03*
X418110D02*
D03*
X457480Y-300625D02*
D03*
X465354Y-316569D02*
D03*
X467322Y-300625D02*
D03*
X443700Y-316569D02*
D03*
X457480D02*
D03*
X447637D02*
D03*
X445669D02*
D03*
X439763D02*
D03*
X427952D02*
D03*
X433858D02*
D03*
X463385D02*
D03*
X453543D02*
D03*
X459448D02*
D03*
X425984D02*
D03*
X465354Y-300625D02*
D03*
X467322Y-316569D02*
D03*
X437795D02*
D03*
X424015D02*
D03*
X463385Y-300625D02*
D03*
X469291D02*
D03*
X459448D02*
D03*
X469291Y-316569D02*
D03*
X453543Y-300625D02*
D03*
X429921Y-316569D02*
D03*
X435826D02*
D03*
X449606Y-300625D02*
D03*
X396456Y-316569D02*
D03*
Y-300625D02*
D03*
X461417D02*
D03*
X451574D02*
D03*
X441732D02*
D03*
X431889D02*
D03*
X422047D02*
D03*
X412204D02*
D03*
X402362D02*
D03*
X461417Y-316569D02*
D03*
X451574D02*
D03*
X441732D02*
D03*
X431889D02*
D03*
X422047D02*
D03*
X412204D02*
D03*
X402362D02*
D03*
X392519D02*
D03*
Y-300625D02*
D03*
X394488D02*
D03*
X447637D02*
D03*
X394488Y-316569D02*
D03*
X424024Y-168449D02*
D03*
X422056D02*
D03*
X447647D02*
D03*
X463394D02*
D03*
X451584D02*
D03*
X443710D02*
D03*
X455521D02*
D03*
X433868D02*
D03*
X437805D02*
D03*
X453552Y-152505D02*
D03*
X445679D02*
D03*
X451584D02*
D03*
X463394D02*
D03*
X461427Y-168449D02*
D03*
X457489D02*
D03*
X406309D02*
D03*
X427961D02*
D03*
X447647Y-152505D02*
D03*
X457489D02*
D03*
X453552Y-168449D02*
D03*
X445679D02*
D03*
X441742D02*
D03*
X425993D02*
D03*
X461427Y-152505D02*
D03*
X435836Y-168449D02*
D03*
X431898D02*
D03*
X455521Y-152505D02*
D03*
X416151Y-168449D02*
D03*
X418119D02*
D03*
X412214Y-152505D02*
D03*
X406309D02*
D03*
X441742D02*
D03*
X443710D02*
D03*
X404340Y-168449D02*
D03*
X396465Y-152505D02*
D03*
X394498Y-168449D02*
D03*
X418119Y-152505D02*
D03*
X404340D02*
D03*
X414183D02*
D03*
X416151D02*
D03*
X422056D02*
D03*
X433868D02*
D03*
X427961D02*
D03*
X398434D02*
D03*
X408277D02*
D03*
X402372D02*
D03*
X435836D02*
D03*
X396465Y-168449D02*
D03*
X394498Y-152505D02*
D03*
X424024D02*
D03*
X437805D02*
D03*
X398434Y-168449D02*
D03*
X392529D02*
D03*
X402372D02*
D03*
X392529Y-152505D02*
D03*
X408277Y-168449D02*
D03*
X431898Y-152505D02*
D03*
X425993D02*
D03*
X412214Y-168449D02*
D03*
X465364Y-152505D02*
D03*
Y-168449D02*
D03*
X400403D02*
D03*
X410246D02*
D03*
X420088D02*
D03*
X429931D02*
D03*
X439773D02*
D03*
X449615D02*
D03*
X459457D02*
D03*
X400403Y-152505D02*
D03*
X410246D02*
D03*
X420088D02*
D03*
X429931D02*
D03*
X439773D02*
D03*
X449615D02*
D03*
X459457D02*
D03*
X469301D02*
D03*
Y-168449D02*
D03*
X467332D02*
D03*
X414183D02*
D03*
X467332Y-152505D02*
D03*
D101*
X340949Y-278041D02*
D03*
Y-190049D02*
D03*
X528351D02*
D03*
Y-278041D02*
D03*
D102*
X348876Y-240930D02*
D03*
Y-242898D02*
D03*
Y-217308D02*
D03*
Y-201560D02*
D03*
Y-213371D02*
D03*
Y-221245D02*
D03*
Y-209434D02*
D03*
Y-231087D02*
D03*
Y-227150D02*
D03*
X332932Y-211402D02*
D03*
Y-219276D02*
D03*
Y-213371D02*
D03*
Y-201560D02*
D03*
X348876Y-203528D02*
D03*
Y-207465D02*
D03*
Y-258646D02*
D03*
Y-236993D02*
D03*
X332932Y-217308D02*
D03*
Y-207465D02*
D03*
X348876Y-211402D02*
D03*
Y-219276D02*
D03*
Y-223213D02*
D03*
Y-238961D02*
D03*
X332932Y-203528D02*
D03*
X348876Y-229119D02*
D03*
Y-233056D02*
D03*
X332932Y-209434D02*
D03*
X348876Y-248804D02*
D03*
Y-246835D02*
D03*
X332932Y-252741D02*
D03*
Y-258646D02*
D03*
Y-223213D02*
D03*
Y-221245D02*
D03*
X348876Y-260615D02*
D03*
X332932Y-268489D02*
D03*
X348876Y-270457D02*
D03*
X332932Y-246835D02*
D03*
Y-260615D02*
D03*
Y-250772D02*
D03*
Y-248804D02*
D03*
Y-242898D02*
D03*
Y-231087D02*
D03*
Y-236993D02*
D03*
Y-266520D02*
D03*
Y-256678D02*
D03*
Y-262583D02*
D03*
Y-229119D02*
D03*
X348876Y-268489D02*
D03*
X332932Y-270457D02*
D03*
Y-240930D02*
D03*
Y-227150D02*
D03*
X348876Y-266520D02*
D03*
Y-272426D02*
D03*
Y-262583D02*
D03*
X332932Y-272426D02*
D03*
X348876Y-256678D02*
D03*
X332932Y-233056D02*
D03*
Y-238961D02*
D03*
X348876Y-252741D02*
D03*
X332932Y-199591D02*
D03*
X348876D02*
D03*
Y-264552D02*
D03*
Y-254709D02*
D03*
Y-244867D02*
D03*
Y-235024D02*
D03*
Y-225182D02*
D03*
Y-215339D02*
D03*
Y-205497D02*
D03*
X332932Y-264552D02*
D03*
Y-254709D02*
D03*
Y-244867D02*
D03*
Y-235024D02*
D03*
Y-225182D02*
D03*
Y-215339D02*
D03*
Y-205497D02*
D03*
Y-195654D02*
D03*
X348876D02*
D03*
Y-197623D02*
D03*
Y-250772D02*
D03*
X332932Y-197623D02*
D03*
X520423Y-227160D02*
D03*
Y-225192D02*
D03*
Y-250782D02*
D03*
Y-266530D02*
D03*
Y-254719D02*
D03*
Y-246845D02*
D03*
Y-258656D02*
D03*
Y-237003D02*
D03*
Y-240940D02*
D03*
X536367Y-256688D02*
D03*
Y-248814D02*
D03*
Y-254719D02*
D03*
Y-266530D02*
D03*
X520423Y-264562D02*
D03*
Y-260625D02*
D03*
Y-209444D02*
D03*
Y-231097D02*
D03*
X536367Y-250782D02*
D03*
Y-260625D02*
D03*
X520423Y-256688D02*
D03*
Y-248814D02*
D03*
Y-244877D02*
D03*
Y-229129D02*
D03*
X536367Y-264562D02*
D03*
X520423Y-238971D02*
D03*
Y-235034D02*
D03*
X536367Y-258656D02*
D03*
X520423Y-219286D02*
D03*
Y-221255D02*
D03*
X536367Y-215349D02*
D03*
Y-209444D02*
D03*
Y-244877D02*
D03*
Y-246845D02*
D03*
X520423Y-207475D02*
D03*
X536367Y-199601D02*
D03*
X520423Y-197633D02*
D03*
X536367Y-221255D02*
D03*
Y-207475D02*
D03*
Y-217318D02*
D03*
Y-219286D02*
D03*
Y-225192D02*
D03*
Y-237003D02*
D03*
Y-231097D02*
D03*
Y-201570D02*
D03*
Y-211412D02*
D03*
Y-205507D02*
D03*
Y-238971D02*
D03*
X520423Y-199601D02*
D03*
X536367Y-197633D02*
D03*
Y-227160D02*
D03*
Y-240940D02*
D03*
X520423Y-201570D02*
D03*
Y-195664D02*
D03*
Y-205507D02*
D03*
X536367Y-195664D02*
D03*
X520423Y-211412D02*
D03*
X536367Y-235034D02*
D03*
Y-229129D02*
D03*
X520423Y-215349D02*
D03*
X536367Y-268499D02*
D03*
X520423D02*
D03*
Y-203538D02*
D03*
Y-213381D02*
D03*
Y-223223D02*
D03*
Y-233066D02*
D03*
Y-242908D02*
D03*
Y-252751D02*
D03*
Y-262593D02*
D03*
X536367Y-203538D02*
D03*
Y-213381D02*
D03*
Y-223223D02*
D03*
Y-233066D02*
D03*
Y-242908D02*
D03*
Y-252751D02*
D03*
Y-262593D02*
D03*
Y-272436D02*
D03*
X520423D02*
D03*
Y-270467D02*
D03*
Y-217318D02*
D03*
X536367Y-270467D02*
D03*
D103*
X293445Y-245593D02*
D03*
X309193D02*
D03*
X293445Y-243593D02*
D03*
X309193D02*
D03*
X293445Y-241593D02*
D03*
X309193D02*
D03*
X293445Y-239593D02*
D03*
X309193D02*
D03*
X293445Y-237593D02*
D03*
X309193D02*
D03*
X293445Y-235593D02*
D03*
X309193D02*
D03*
X293445Y-233593D02*
D03*
X309193D02*
D03*
X293445Y-231593D02*
D03*
X309193D02*
D03*
X293445Y-229593D02*
D03*
X309193D02*
D03*
Y-227593D02*
D03*
X293445D02*
D03*
Y-245593D02*
D03*
X309193D02*
D03*
X293445Y-243593D02*
D03*
X309193D02*
D03*
X293445Y-241593D02*
D03*
X309193D02*
D03*
X293445Y-239593D02*
D03*
X309193D02*
D03*
X293445Y-237593D02*
D03*
X309193D02*
D03*
X293445Y-235593D02*
D03*
X309193D02*
D03*
X293445Y-233593D02*
D03*
X309193D02*
D03*
X293445Y-231593D02*
D03*
X309193D02*
D03*
X293445Y-229593D02*
D03*
X309193D02*
D03*
Y-227593D02*
D03*
X293445D02*
D03*
D104*
X371107Y-112598D02*
D03*
X359493D02*
D03*
Y-136221D02*
D03*
X371107D02*
D03*
X601083Y-167717D02*
D03*
X589468D02*
D03*
X359493Y-124803D02*
D03*
X371107D02*
D03*
D105*
X638287Y-168504D02*
D03*
X612106D02*
D03*
D106*
X609291Y-316535D02*
D03*
Y-343543D02*
D03*
X599291Y-316535D02*
D03*
Y-343543D02*
D03*
X589291Y-316535D02*
D03*
Y-343543D02*
D03*
X579291Y-316535D02*
D03*
Y-343543D02*
D03*
X569291Y-316535D02*
D03*
Y-343543D02*
D03*
D107*
X540493Y-331738D02*
D03*
X532619D02*
D03*
X540099Y-347880D02*
D03*
X532225D02*
D03*
D108*
X655118Y-346457D02*
D03*
Y-338583D02*
D03*
X637008Y-346850D02*
D03*
Y-338976D02*
D03*
D109*
X515198Y-329179D02*
D03*
Y-334297D02*
D03*
X524056Y-331738D02*
D03*
X515099Y-345321D02*
D03*
Y-350439D02*
D03*
X523958Y-347880D02*
D03*
D110*
X639567Y-320374D02*
D03*
X634449D02*
D03*
X637008Y-329232D02*
D03*
X658268Y-320473D02*
D03*
X653150D02*
D03*
X655709Y-329331D02*
D03*
D111*
X577559Y-117323D02*
D03*
Y-124409D02*
D03*
X357480Y-96850D02*
D03*
Y-103937D02*
D03*
D112*
X81988Y-215551D02*
D03*
Y-213583D02*
D03*
Y-211614D02*
D03*
Y-209646D02*
D03*
X69587D02*
D03*
Y-211614D02*
D03*
Y-213583D02*
D03*
Y-215551D02*
D03*
X81004Y-162402D02*
D03*
Y-160433D02*
D03*
Y-158465D02*
D03*
Y-156496D02*
D03*
X68602D02*
D03*
Y-158465D02*
D03*
Y-160433D02*
D03*
Y-162402D02*
D03*
X81988Y-267717D02*
D03*
Y-265748D02*
D03*
Y-263779D02*
D03*
Y-261811D02*
D03*
X69587D02*
D03*
Y-263779D02*
D03*
Y-265748D02*
D03*
Y-267717D02*
D03*
X81004Y-321850D02*
D03*
Y-319882D02*
D03*
Y-317913D02*
D03*
Y-315945D02*
D03*
X68602D02*
D03*
Y-317913D02*
D03*
Y-319882D02*
D03*
Y-321850D02*
D03*
D113*
X47244Y-4626D02*
D03*
Y689D02*
D03*
X40354Y-4626D02*
D03*
Y689D02*
D03*
X33465Y-4626D02*
D03*
Y689D02*
D03*
X26575Y-4626D02*
D03*
Y689D02*
D03*
X199803Y-119439D02*
D03*
Y-114517D02*
D03*
D114*
X94193Y-120079D02*
D03*
Y-122047D02*
D03*
Y-124016D02*
D03*
Y-125984D02*
D03*
Y-127953D02*
D03*
Y-129921D02*
D03*
Y-131890D02*
D03*
X112500D02*
D03*
Y-129921D02*
D03*
Y-127953D02*
D03*
Y-125984D02*
D03*
Y-124016D02*
D03*
Y-122047D02*
D03*
Y-120079D02*
D03*
D115*
X97441Y-135138D02*
D03*
X99410D02*
D03*
X101378D02*
D03*
X103347D02*
D03*
X105315D02*
D03*
X107283D02*
D03*
X109252D02*
D03*
X109252Y-116831D02*
D03*
X107283D02*
D03*
X105315D02*
D03*
X103347D02*
D03*
X101378D02*
D03*
X99410D02*
D03*
X97441D02*
D03*
D116*
X103347Y-125984D02*
D03*
D117*
X-18406Y-187795D02*
D03*
Y-176772D02*
D03*
Y-240551D02*
D03*
Y-229528D02*
D03*
Y-294094D02*
D03*
Y-283071D02*
D03*
Y-346850D02*
D03*
Y-335827D02*
D03*
Y-113976D02*
D03*
Y-102953D02*
D03*
Y-70669D02*
D03*
Y-59646D02*
D03*
D118*
X-19685Y-184055D02*
D03*
Y-180512D02*
D03*
Y-236811D02*
D03*
Y-233268D02*
D03*
Y-290354D02*
D03*
Y-286811D02*
D03*
Y-343110D02*
D03*
Y-339567D02*
D03*
Y-110236D02*
D03*
Y-106693D02*
D03*
Y-66929D02*
D03*
Y-63386D02*
D03*
D119*
X83268Y-110236D02*
D03*
X76575D02*
D03*
D120*
X75787Y-127756D02*
D03*
Y-123031D02*
D03*
D121*
X44291Y-256988D02*
D03*
Y-268602D02*
D03*
Y-151673D02*
D03*
Y-163287D02*
D03*
Y-311122D02*
D03*
Y-322736D02*
D03*
Y-204823D02*
D03*
Y-216437D02*
D03*
D122*
X38287Y-262795D02*
D03*
Y-157480D02*
D03*
Y-316929D02*
D03*
Y-210630D02*
D03*
D123*
X74803Y-335630D02*
D03*
Y-329724D02*
D03*
X82677Y-335630D02*
D03*
Y-329724D02*
D03*
X75787Y-227362D02*
D03*
Y-221457D02*
D03*
X82677Y-227362D02*
D03*
Y-221457D02*
D03*
X83661Y-281496D02*
D03*
Y-275590D02*
D03*
X75787Y-281496D02*
D03*
Y-275590D02*
D03*
X74803Y-175197D02*
D03*
Y-169291D02*
D03*
X82677Y-175197D02*
D03*
Y-169291D02*
D03*
D124*
X59646Y-316929D02*
D03*
X54134D02*
D03*
X60827Y-210630D02*
D03*
X55315D02*
D03*
X60827Y-262795D02*
D03*
X55315D02*
D03*
X54331Y-157480D02*
D03*
X59842D02*
D03*
D125*
X460925Y-137647D02*
D03*
X456398D02*
D03*
D126*
X31496Y-184055D02*
D03*
Y-291732D02*
D03*
D127*
X38189Y-184055D02*
D03*
Y-175394D02*
D03*
X30709D02*
D03*
X38189Y-291732D02*
D03*
Y-283071D02*
D03*
X30709D02*
D03*
D128*
X281102Y-401427D02*
D03*
X159055D02*
D03*
X155118D02*
D03*
X151181D02*
D03*
X178740D02*
D03*
X222047D02*
D03*
X265354D02*
D03*
X261417D02*
D03*
X249606D02*
D03*
X245669D02*
D03*
X233858D02*
D03*
X229921D02*
D03*
X214173D02*
D03*
X210236D02*
D03*
X186614D02*
D03*
X182677D02*
D03*
X202362D02*
D03*
X273228D02*
D03*
X166929D02*
D03*
X170866D02*
D03*
X190551D02*
D03*
X269291D02*
D03*
X257480D02*
D03*
X241732D02*
D03*
X237795D02*
D03*
X174803D02*
D03*
X162992D02*
D03*
X253543D02*
D03*
X206299D02*
D03*
X218110D02*
D03*
X225984D02*
D03*
D129*
X277165Y-399477D02*
D03*
D130*
X279528Y-113946D02*
D03*
Y-118947D02*
D03*
Y-123946D02*
D03*
Y-128946D02*
D03*
X298425Y-113946D02*
D03*
Y-118947D02*
D03*
Y-123946D02*
D03*
Y-128946D02*
D03*
D131*
X209252Y-114399D02*
D03*
Y-119399D02*
D03*
Y-124399D02*
D03*
Y-129399D02*
D03*
X227756Y-114399D02*
D03*
Y-119399D02*
D03*
Y-124399D02*
D03*
Y-129399D02*
D03*
D132*
X597598Y-159449D02*
D03*
X592165D02*
D03*
X110709Y-263632D02*
D03*
X116142D02*
D03*
D133*
X519783Y-126131D02*
D03*
Y-128691D02*
D03*
X511713D02*
D03*
Y-126131D02*
D03*
Y-123572D02*
D03*
Y-121013D02*
D03*
X519783D02*
D03*
Y-123572D02*
D03*
D134*
X464370Y-130034D02*
D03*
X456890D02*
D03*
Y-121639D02*
D03*
X460630D02*
D03*
D135*
X464370D02*
D03*
D155*
X692421Y-72342D02*
D03*
Y-105610D02*
D03*
D156*
X685433Y-53150D02*
D03*
D158*
X619685Y-90158D02*
D03*
Y-91732D02*
D03*
Y-93307D02*
D03*
Y-94882D02*
D03*
Y-96457D02*
D03*
X614567D02*
D03*
Y-94882D02*
D03*
Y-93307D02*
D03*
Y-91732D02*
D03*
X586811Y-90158D02*
D03*
Y-91732D02*
D03*
Y-93307D02*
D03*
Y-94882D02*
D03*
Y-96457D02*
D03*
X581693D02*
D03*
Y-94882D02*
D03*
Y-93307D02*
D03*
Y-91732D02*
D03*
D159*
X617126Y-96457D02*
D03*
Y-90158D02*
D03*
X584252Y-96457D02*
D03*
Y-90158D02*
D03*
D160*
X615354D02*
D03*
X582480D02*
D03*
X245276Y-123031D02*
D03*
D161*
Y-118701D02*
D03*
X246850D02*
D03*
X248425D02*
D03*
X250000D02*
D03*
X251575D02*
D03*
Y-123819D02*
D03*
X250000D02*
D03*
X248425D02*
D03*
X246850D02*
D03*
D162*
X251575Y-121260D02*
D03*
X245276D02*
D03*
D167*
X573379Y-219838D02*
D03*
Y-217279D02*
D03*
Y-214720D02*
D03*
Y-212161D02*
D03*
Y-209602D02*
D03*
Y-207043D02*
D03*
X596214D02*
D03*
Y-209602D02*
D03*
Y-212161D02*
D03*
Y-214720D02*
D03*
Y-217279D02*
D03*
Y-219838D02*
D03*
X562205Y-278445D02*
D03*
Y-275886D02*
D03*
Y-273327D02*
D03*
Y-270768D02*
D03*
Y-268209D02*
D03*
Y-265650D02*
D03*
X585039D02*
D03*
Y-268209D02*
D03*
Y-270768D02*
D03*
Y-273327D02*
D03*
Y-275886D02*
D03*
Y-278445D02*
D03*
D168*
X575840Y-203992D02*
D03*
X578399D02*
D03*
X580958D02*
D03*
X583517D02*
D03*
X586076D02*
D03*
X588635D02*
D03*
X591194D02*
D03*
X593753D02*
D03*
Y-222889D02*
D03*
X591194D02*
D03*
X588635D02*
D03*
X586076D02*
D03*
X583517D02*
D03*
X580958D02*
D03*
X578399D02*
D03*
X575840D02*
D03*
X564665Y-262598D02*
D03*
X567224D02*
D03*
X569783D02*
D03*
X572342D02*
D03*
X574902D02*
D03*
X577461D02*
D03*
X580020D02*
D03*
X582579D02*
D03*
Y-281496D02*
D03*
X580020D02*
D03*
X577461D02*
D03*
X574902D02*
D03*
X572342D02*
D03*
X569783D02*
D03*
X567224D02*
D03*
X564665D02*
D03*
D169*
X578694Y-213440D02*
D03*
X567520Y-272047D02*
D03*
D212*
X695866Y-105610D02*
D03*
Y-72342D02*
D03*
X688976D02*
D03*
Y-105610D02*
D03*
D213*
X682283Y-74803D02*
D03*
Y-103150D02*
D03*
D214*
X672401Y-135695D02*
D03*
D215*
X643701Y-127445D02*
D03*
D216*
Y-143945D02*
D03*
X622001Y-127445D02*
D03*
Y-143945D02*
D03*
D234*
X588189Y-282382D02*
X594095D01*
X585138Y-285433D02*
X588189Y-282382D01*
X585138Y-285433D02*
X585335Y-285630D01*
Y-289764D02*
Y-285630D01*
D235*
X623622Y-70866D02*
X625345Y-69143D01*
X631890D01*
X55905Y-37008D02*
Y-31496D01*
X43701Y-29921D02*
X47244Y-33465D01*
Y-35433D02*
Y-33465D01*
X101132Y-18553D02*
X101181Y-18504D01*
X91536Y-18553D02*
X101132D01*
X124409Y-33465D02*
X125591Y-32283D01*
X124409Y-37008D02*
Y-33465D01*
X111024Y-33071D02*
X111417Y-33465D01*
Y-37795D02*
Y-33465D01*
X112992Y-44882D02*
X124409D01*
X111417Y-43307D02*
X112992Y-44882D01*
X102756Y-43307D02*
X111417D01*
X101575Y-42126D02*
X102756Y-43307D01*
X101526Y-42175D02*
X101575Y-42126D01*
X91536Y-42175D02*
X101526D01*
X670079Y-9449D02*
X671654Y-11024D01*
Y-16142D02*
Y-11024D01*
X673228Y-29528D02*
X673622Y-29134D01*
Y-23622D01*
X671654Y-62598D02*
X671654Y-62598D01*
Y-56693D01*
X670866Y-42126D02*
X671654Y-41339D01*
X670866Y-47244D02*
Y-42126D01*
X602756Y-39764D02*
X602756Y-39764D01*
X602756Y-44882D02*
Y-39764D01*
X596063Y-53937D02*
X601575D01*
X608268Y-44882D02*
X609449Y-46063D01*
Y-53937D02*
Y-46063D01*
X631250Y-44882D02*
X631890Y-45521D01*
X614567Y-44882D02*
X631250D01*
X608268D02*
X614567D01*
X562598Y-306693D02*
X569291D01*
Y-316535D02*
Y-306693D01*
X609291Y-305512D02*
X615748D01*
X609291Y-316535D02*
Y-305512D01*
X348106Y-98726D02*
Y-89891D01*
X348211D01*
X357480Y-96850D02*
Y-89963D01*
X357798D01*
X623000Y-37402D02*
X625586D01*
X625832Y-37647D02*
X631890D01*
X625586Y-37402D02*
X625832Y-37647D01*
X610010Y-14017D02*
Y-9246D01*
X610236Y-9021D01*
Y-8858D01*
X609252Y-26575D02*
Y-21506D01*
X89567Y-102362D02*
Y-98277D01*
X98425Y-102362D02*
Y-98080D01*
X114173Y-83088D02*
Y-79379D01*
X124606Y-79576D02*
X129921D01*
X91536Y-50049D02*
X99410D01*
X615158Y-9075D02*
Y-8858D01*
X615522Y-14017D02*
Y-9440D01*
X615158Y-9075D02*
X615522Y-9440D01*
X615530Y-14025D02*
X617126Y-15621D01*
X615522Y-14017D02*
X615530Y-14025D01*
X631890D01*
X617126Y-21506D02*
Y-15621D01*
D236*
X155526Y-370989D02*
D03*
D237*
X155364Y-388287D02*
D03*
D238*
X182687Y-388238D02*
D03*
D239*
X181496Y-120079D02*
D03*
D240*
X171496D02*
D03*
X161496D02*
D03*
X151496D02*
D03*
X141496D02*
D03*
D241*
X270472Y-327165D02*
D03*
X282283D02*
D03*
X142520Y-156693D02*
D03*
X294094Y-327165D02*
D03*
X142520Y-316535D02*
D03*
X302362Y-156693D02*
D03*
X142520Y-236614D02*
D03*
X258472Y-327165D02*
D03*
X302362Y-316535D02*
D03*
X246472Y-327165D02*
D03*
X258472D02*
D03*
X282283D02*
D03*
X294094D02*
D03*
X302362Y-156693D02*
D03*
Y-316535D02*
D03*
X142520D02*
D03*
Y-236614D02*
D03*
Y-156693D02*
D03*
X270472Y-327165D02*
D03*
X246472D02*
D03*
D242*
X470275Y-308597D02*
D03*
X391535D02*
D03*
X340904Y-273410D02*
D03*
Y-194670D02*
D03*
X391545Y-160477D02*
D03*
X470285D02*
D03*
X528395Y-194680D02*
D03*
Y-273420D02*
D03*
D243*
X285128Y-308632D02*
D03*
X160020Y-314535D02*
D03*
X162520Y-152693D02*
D03*
X284862Y-164793D02*
D03*
D244*
X604291Y-330039D02*
D03*
X574291D02*
D03*
D245*
X-18464Y-326781D02*
D03*
X1535D02*
D03*
Y-306781D02*
D03*
X-18464D02*
D03*
X-18465Y-273630D02*
D03*
X1535D02*
D03*
Y-253630D02*
D03*
X-18465D02*
D03*
Y-220480D02*
D03*
X1535D02*
D03*
Y-200480D02*
D03*
X-18465D02*
D03*
X-18464Y-167332D02*
D03*
X1535D02*
D03*
Y-147332D02*
D03*
X-18464D02*
D03*
D246*
X-8465Y-316781D02*
D03*
X-8465Y-263630D02*
D03*
Y-210480D02*
D03*
X-8465Y-157332D02*
D03*
D247*
X589055Y13937D02*
D03*
D248*
X579055D02*
D03*
X569055D02*
D03*
X559055D02*
D03*
X549055D02*
D03*
X539055D02*
D03*
X589055Y3937D02*
D03*
X579055D02*
D03*
X569055D02*
D03*
X559055D02*
D03*
X549055D02*
D03*
X539055D02*
D03*
D249*
X0Y0D02*
D03*
X0Y-378395D02*
D03*
X685039Y-340551D02*
D03*
X685039Y0D02*
D03*
X486221Y-340551D02*
D03*
D250*
X670538Y-74409D02*
D03*
X668438D02*
D03*
X676772Y-54331D02*
D03*
Y-51575D02*
D03*
X84079Y-105653D02*
D03*
X62986Y-112803D02*
D03*
X62499Y-117255D02*
D03*
X141981Y-347043D02*
D03*
X142520Y-342913D02*
D03*
X198392Y-366842D02*
D03*
X196701Y-370523D02*
D03*
X680709Y-216929D02*
D03*
X671654Y-217323D02*
D03*
X585433Y-114961D02*
D03*
X584252Y-117717D02*
D03*
X366929Y-75984D02*
D03*
Y-83071D02*
D03*
Y-86614D02*
D03*
Y-89370D02*
D03*
Y-79528D02*
D03*
X679921Y-160236D02*
D03*
X684646Y-161811D02*
D03*
X689370Y-161417D02*
D03*
X689764Y-164567D02*
D03*
Y-168110D02*
D03*
X625000Y-48080D02*
D03*
X476945Y-173228D02*
D03*
X555512Y-218504D02*
D03*
X381496Y-127165D02*
D03*
X378740Y-123622D02*
D03*
X377559Y-135433D02*
D03*
X381890Y-137402D02*
D03*
X377559Y-142126D02*
D03*
X381496Y-140945D02*
D03*
X474016Y-176378D02*
D03*
X460186Y-175448D02*
D03*
X578168Y-80778D02*
D03*
X530027Y-172987D02*
D03*
X533044Y-176225D02*
D03*
X495669Y-222047D02*
D03*
X500394Y-222835D02*
D03*
X157480Y-361811D02*
D03*
X153543Y-358661D02*
D03*
Y-361811D02*
D03*
X155512D02*
D03*
Y-358661D02*
D03*
X157480D02*
D03*
X644488Y-170472D02*
D03*
X644619Y-166285D02*
D03*
X644569Y-162910D02*
D03*
X644488Y-159843D02*
D03*
X435827Y-103543D02*
D03*
X402719Y-112334D02*
D03*
X409900Y-136559D02*
D03*
X430492Y-136473D02*
D03*
X414567Y-137402D02*
D03*
X436614Y-136614D02*
D03*
X443307Y-111024D02*
D03*
X664966Y-316582D02*
D03*
X664961Y-325984D02*
D03*
X692037Y-315878D02*
D03*
X692126Y-322441D02*
D03*
X256897Y-112001D02*
D03*
X255118Y-118504D02*
D03*
X254376Y-125747D02*
D03*
X241250Y-126247D02*
D03*
X238189Y-116142D02*
D03*
X246063Y-111024D02*
D03*
X248425Y-129134D02*
D03*
X241077Y-118805D02*
D03*
X255512Y-121260D02*
D03*
X253713Y-109190D02*
D03*
X253690Y-111960D02*
D03*
X267717Y-123622D02*
D03*
X271654Y-122835D02*
D03*
X267323Y-132677D02*
D03*
X272047Y-131496D02*
D03*
X244664Y-106952D02*
D03*
X228824Y-104850D02*
D03*
X577953Y-83858D02*
D03*
X618898Y-82284D02*
D03*
X612205Y-87008D02*
D03*
X609055Y-92520D02*
D03*
X620959Y-100047D02*
D03*
X612598Y-100000D02*
D03*
X629134Y-102756D02*
D03*
X631814Y-83784D02*
D03*
X629101Y-90137D02*
D03*
X623228Y-93307D02*
D03*
X616535Y-84646D02*
D03*
X616929Y-100000D02*
D03*
X599279Y-82981D02*
D03*
X597227Y-77103D02*
D03*
X601745Y-98051D02*
D03*
X588372Y-100945D02*
D03*
X567323Y-94095D02*
D03*
X569291Y-91339D02*
D03*
X568504Y-88189D02*
D03*
X579921Y-101969D02*
D03*
X584763Y-100116D02*
D03*
X588976Y-86221D02*
D03*
X600394Y-87795D02*
D03*
X592520Y-93307D02*
D03*
X666929Y-98032D02*
D03*
X662539Y-107066D02*
D03*
X667717Y-106693D02*
D03*
X696762Y-63288D02*
D03*
X696577Y-51453D02*
D03*
X675591Y-42520D02*
D03*
X685716Y-22157D02*
D03*
X679517Y-26553D02*
D03*
Y-37023D02*
D03*
X693915Y-33393D02*
D03*
X686728Y-33442D02*
D03*
X686319Y-43553D02*
D03*
X683127Y-66209D02*
D03*
X689466Y-66165D02*
D03*
X680082Y-64183D02*
D03*
X675926Y-72691D02*
D03*
X660719Y-75726D02*
D03*
X694095Y-62205D02*
D03*
X693977Y-53201D02*
D03*
X676378Y-83858D02*
D03*
X538583Y-111811D02*
D03*
X539233Y-115729D02*
D03*
X569092Y-108048D02*
D03*
X546386Y-109024D02*
D03*
X548093Y-185219D02*
D03*
X548425Y-181890D02*
D03*
X548819Y-178740D02*
D03*
X547244Y-157087D02*
D03*
Y-144488D02*
D03*
X524409Y-135827D02*
D03*
X531801Y-127495D02*
D03*
X539900Y-140766D02*
D03*
X570472Y-137795D02*
D03*
X579921Y-133465D02*
D03*
X574409D02*
D03*
X570866D02*
D03*
X572047Y-129921D02*
D03*
X576378D02*
D03*
X580315D02*
D03*
X646457Y-156693D02*
D03*
X642520D02*
D03*
X635039Y-216142D02*
D03*
X608661Y-236221D02*
D03*
X572441Y-227165D02*
D03*
X678441Y-292586D02*
D03*
X678346Y-297244D02*
D03*
X639764Y-283858D02*
D03*
X554724Y-294882D02*
D03*
X565354Y-292913D02*
D03*
X630577Y-278001D02*
D03*
X582874Y-294291D02*
D03*
X680709Y-212205D02*
D03*
X673622Y-213779D02*
D03*
X669685D02*
D03*
X666142Y-212992D02*
D03*
X599564Y-178940D02*
D03*
X594882Y-179134D02*
D03*
X589764D02*
D03*
X584646Y-178740D02*
D03*
X635827Y-187795D02*
D03*
X635433Y-184252D02*
D03*
X652756Y-164961D02*
D03*
X657480Y-164567D02*
D03*
X662992Y-164961D02*
D03*
X668504D02*
D03*
X681496Y-179528D02*
D03*
X677165Y-172441D02*
D03*
X673228D02*
D03*
X675197Y-200000D02*
D03*
X678740D02*
D03*
X681890D02*
D03*
Y-196850D02*
D03*
X678740D02*
D03*
X675591Y-196457D02*
D03*
X652756Y-218504D02*
D03*
X650000Y-231102D02*
D03*
X646434Y-231245D02*
D03*
X598425Y-198819D02*
D03*
X595276D02*
D03*
X592126D02*
D03*
X589764D02*
D03*
X587008D02*
D03*
X570079Y-200000D02*
D03*
X549298Y-191988D02*
D03*
X600000Y-248425D02*
D03*
X616535Y-255512D02*
D03*
X612205Y-251575D02*
D03*
X624803Y-255906D02*
D03*
Y-251575D02*
D03*
X624409Y-248031D02*
D03*
X611417Y-247638D02*
D03*
X605118Y-244488D02*
D03*
X673228Y-251181D02*
D03*
X672835Y-257087D02*
D03*
X673622Y-261417D02*
D03*
X676378Y-266142D02*
D03*
X676772Y-270866D02*
D03*
X671260Y-274803D02*
D03*
Y-278740D02*
D03*
X671654Y-283071D02*
D03*
X683858Y-310630D02*
D03*
X683716Y-298538D02*
D03*
X651575Y-275197D02*
D03*
X648819Y-278740D02*
D03*
X652362Y-279528D02*
D03*
X657087D02*
D03*
X654331Y-283858D02*
D03*
X650000D02*
D03*
X646457D02*
D03*
X637795Y-297638D02*
D03*
X585039Y-249606D02*
D03*
X590551Y-266535D02*
D03*
X588189Y-263386D02*
D03*
X585433Y-253937D02*
D03*
Y-257480D02*
D03*
X581496D02*
D03*
X577953D02*
D03*
X559842Y-257087D02*
D03*
X579134Y-195276D02*
D03*
X574803D02*
D03*
X577953Y-198819D02*
D03*
X590158Y-226378D02*
D03*
X586221Y-226772D02*
D03*
X579921Y-227559D02*
D03*
X576772Y-228740D02*
D03*
X637008Y-238583D02*
D03*
X608661Y-242126D02*
D03*
X590551Y-242520D02*
D03*
X586537Y-234843D02*
D03*
X546850Y-213779D02*
D03*
X548819Y-196063D02*
D03*
X547244Y-203150D02*
D03*
X554724Y-207874D02*
D03*
X549213D02*
D03*
X569291Y-194095D02*
D03*
X581496Y-198819D02*
D03*
X573622D02*
D03*
X571162Y-284136D02*
D03*
X577953Y-284646D02*
D03*
X574803Y-284252D02*
D03*
X568110D02*
D03*
X567717Y-259055D02*
D03*
X566535Y-255906D02*
D03*
X570079D02*
D03*
X548425Y-253543D02*
D03*
X545669Y-253937D02*
D03*
X545128Y-280872D02*
D03*
X544909Y-287437D02*
D03*
X545276Y-294094D02*
D03*
Y-275197D02*
D03*
Y-270866D02*
D03*
X544488Y-265748D02*
D03*
X557087Y-261417D02*
D03*
X556628Y-258042D02*
D03*
X569548Y-287223D02*
D03*
X595276Y-291732D02*
D03*
X612598D02*
D03*
X627559Y-296457D02*
D03*
X563386Y-257874D02*
D03*
X572441Y-258268D02*
D03*
X475984Y-127165D02*
D03*
X480120Y-132365D02*
D03*
X469685Y-133465D02*
D03*
X473228Y-105905D02*
D03*
X488583Y-132283D02*
D03*
X506299Y-129921D02*
D03*
X498032Y-132283D02*
D03*
X506207Y-127333D02*
D03*
X505905Y-123622D02*
D03*
X472441Y-113779D02*
D03*
X483484Y-105840D02*
D03*
X504703Y-106672D02*
D03*
X508268Y-117323D02*
D03*
X501669Y-116601D02*
D03*
X500313Y-105734D02*
D03*
X476772Y-123622D02*
D03*
X470472Y-123622D02*
D03*
X444507Y-309009D02*
D03*
X448819Y-309055D02*
D03*
X457480Y-306693D02*
D03*
X451575Y-309055D02*
D03*
X437048Y-308863D02*
D03*
X431102Y-308268D02*
D03*
X461811Y-327165D02*
D03*
X456693D02*
D03*
X454724D02*
D03*
X450394D02*
D03*
X448032D02*
D03*
X443701D02*
D03*
X441732D02*
D03*
X436614D02*
D03*
X429528Y-326772D02*
D03*
X434646Y-327559D02*
D03*
X518337Y-159634D02*
D03*
X515702Y-162803D02*
D03*
X498693Y-188351D02*
D03*
X498819Y-183858D02*
D03*
X499111Y-179528D02*
D03*
X658114Y-56714D02*
D03*
X657445Y-63525D02*
D03*
X658053Y-71188D02*
D03*
X623511Y-62552D02*
D03*
X623228Y-55118D02*
D03*
X623622Y-70866D02*
D03*
X43701Y-29921D02*
D03*
X55905Y-31496D02*
D03*
X111024Y-33071D02*
D03*
X125591Y-32283D02*
D03*
X64173Y-42520D02*
D03*
X101181Y-18504D02*
D03*
X101575Y-42126D02*
D03*
X670079Y-9449D02*
D03*
X673228Y-29528D02*
D03*
X671654Y-62598D02*
D03*
Y-41339D02*
D03*
X659449Y-49213D02*
D03*
X596063Y-53937D02*
D03*
X602756Y-39764D02*
D03*
X660236Y-14961D02*
D03*
X614567Y-44882D02*
D03*
X423461Y-178869D02*
D03*
X144871Y-131609D02*
D03*
X120079Y-263386D02*
D03*
X314417Y-228033D02*
D03*
X314623Y-231391D02*
D03*
X325984Y-272441D02*
D03*
X416835Y-196581D02*
D03*
X411811Y-196850D02*
D03*
X570866Y-70472D02*
D03*
Y-72441D02*
D03*
Y-74410D02*
D03*
X574016Y-70472D02*
D03*
Y-72441D02*
D03*
Y-74410D02*
D03*
X350787Y-116929D02*
D03*
X352756D02*
D03*
X354724D02*
D03*
X350787Y-113779D02*
D03*
X352756D02*
D03*
X354724D02*
D03*
X379134Y-137795D02*
D03*
X378740Y-127165D02*
D03*
X375532Y-123610D02*
D03*
X314658Y-244775D02*
D03*
X315097Y-235081D02*
D03*
X314503Y-225180D02*
D03*
X288583Y-225590D02*
D03*
X288189Y-228740D02*
D03*
Y-231102D02*
D03*
X288057Y-233478D02*
D03*
X288057Y-245095D02*
D03*
X288189Y-247638D02*
D03*
X287941Y-241819D02*
D03*
X288189Y-235827D02*
D03*
X588976Y-302756D02*
D03*
X579528Y-303150D02*
D03*
X615748Y-305512D02*
D03*
X562598Y-306693D02*
D03*
X377165Y-107283D02*
D03*
X383465Y-107480D02*
D03*
X375590Y-127165D02*
D03*
X106299Y-263632D02*
D03*
X380339Y-107321D02*
D03*
X154724Y-389616D02*
D03*
X156693D02*
D03*
X158661D02*
D03*
X154724Y-386466D02*
D03*
X156693D02*
D03*
X158661D02*
D03*
X531496Y-262647D02*
D03*
X461811Y-310679D02*
D03*
X450000Y-293750D02*
D03*
X422441Y-293789D02*
D03*
X531496Y-213435D02*
D03*
X338525Y-243567D02*
D03*
X525591Y-233088D02*
D03*
X439697Y-162549D02*
D03*
X343144Y-225173D02*
D03*
X420669Y-157923D02*
D03*
X531496Y-223277D02*
D03*
X338583Y-235236D02*
D03*
X525591Y-242962D02*
D03*
X430150Y-162253D02*
D03*
X343444Y-215373D02*
D03*
X432283Y-293750D02*
D03*
X410528Y-157923D02*
D03*
X342944Y-264473D02*
D03*
X444095Y-293750D02*
D03*
X422835Y-311072D02*
D03*
X531496Y-233088D02*
D03*
X430150Y-157923D02*
D03*
X338444Y-225173D02*
D03*
X402756Y-311072D02*
D03*
X525591Y-253969D02*
D03*
X420079Y-162549D02*
D03*
X343403Y-205651D02*
D03*
X525591Y-203592D02*
D03*
X400295Y-157824D02*
D03*
X343144Y-254773D02*
D03*
X431928Y-311189D02*
D03*
X531496Y-242962D02*
D03*
X338844Y-215273D02*
D03*
X402362Y-293750D02*
D03*
X525591Y-262647D02*
D03*
X410913Y-162758D02*
D03*
X338444Y-264473D02*
D03*
X456299Y-293750D02*
D03*
X437795Y-293750D02*
D03*
X525591Y-213435D02*
D03*
X459319Y-162510D02*
D03*
Y-157922D02*
D03*
X342744Y-243747D02*
D03*
X412598Y-311072D02*
D03*
X531496Y-253969D02*
D03*
X449803Y-157923D02*
D03*
X338744Y-205473D02*
D03*
X531496Y-203592D02*
D03*
X401279Y-162509D02*
D03*
X439961Y-157923D02*
D03*
X338444Y-254773D02*
D03*
X461417Y-293750D02*
D03*
X525591Y-223277D02*
D03*
X449508Y-162549D02*
D03*
X343504Y-235236D02*
D03*
X412205Y-293750D02*
D03*
X639750Y-314581D02*
D03*
X658647Y-314581D02*
D03*
X509405Y-345138D02*
D03*
X509011Y-330177D02*
D03*
X56441Y-143600D02*
D03*
Y-151600D02*
D03*
Y-191600D02*
D03*
Y-199600D02*
D03*
Y-215600D02*
D03*
Y-223600D02*
D03*
Y-231600D02*
D03*
Y-247600D02*
D03*
Y-255600D02*
D03*
Y-271600D02*
D03*
Y-279600D02*
D03*
Y-287600D02*
D03*
Y-303600D02*
D03*
Y-311600D02*
D03*
Y-327600D02*
D03*
Y-335600D02*
D03*
Y-343600D02*
D03*
Y-351600D02*
D03*
X54441Y-139600D02*
D03*
X52441Y-143600D02*
D03*
X54441Y-147600D02*
D03*
X52441Y-151600D02*
D03*
Y-191600D02*
D03*
X54441Y-195600D02*
D03*
X52441Y-199600D02*
D03*
X54441Y-203600D02*
D03*
X52441Y-215600D02*
D03*
X54441Y-219600D02*
D03*
X52441Y-223600D02*
D03*
X54441Y-227600D02*
D03*
X52441Y-231600D02*
D03*
X54441Y-235600D02*
D03*
Y-243600D02*
D03*
X52441Y-247600D02*
D03*
X54441Y-251600D02*
D03*
X52441Y-255600D02*
D03*
X54441Y-267600D02*
D03*
X52441Y-271600D02*
D03*
X54441Y-275600D02*
D03*
X52441Y-279600D02*
D03*
Y-287600D02*
D03*
X54441Y-291600D02*
D03*
Y-299600D02*
D03*
X52441Y-303600D02*
D03*
X54441Y-307600D02*
D03*
X52441Y-311600D02*
D03*
X54441Y-323600D02*
D03*
X52441Y-327600D02*
D03*
X54441Y-331600D02*
D03*
X52441Y-335600D02*
D03*
X54441Y-339600D02*
D03*
X52441Y-343600D02*
D03*
Y-351600D02*
D03*
X50441Y-139600D02*
D03*
X48441Y-143600D02*
D03*
X50441Y-195600D02*
D03*
X48441Y-199600D02*
D03*
Y-223600D02*
D03*
X50441Y-227600D02*
D03*
X48441Y-231600D02*
D03*
X50441Y-235600D02*
D03*
Y-243600D02*
D03*
X48441Y-247600D02*
D03*
X50441Y-251600D02*
D03*
Y-275600D02*
D03*
X48441Y-279600D02*
D03*
Y-287600D02*
D03*
X50441Y-291600D02*
D03*
Y-299600D02*
D03*
X48441Y-303600D02*
D03*
X50441Y-331600D02*
D03*
X48441Y-335600D02*
D03*
X50441Y-339600D02*
D03*
X48441Y-343600D02*
D03*
Y-351600D02*
D03*
X46441Y-139600D02*
D03*
X44441Y-143600D02*
D03*
X46441Y-227600D02*
D03*
X44441Y-231600D02*
D03*
X46441Y-235600D02*
D03*
Y-243600D02*
D03*
X44441Y-247600D02*
D03*
Y-279600D02*
D03*
Y-287600D02*
D03*
X46441Y-291600D02*
D03*
Y-299600D02*
D03*
Y-331600D02*
D03*
X44441Y-335600D02*
D03*
X46441Y-339600D02*
D03*
X44441Y-343600D02*
D03*
Y-351600D02*
D03*
X42441Y-139600D02*
D03*
X40441Y-143600D02*
D03*
Y-223600D02*
D03*
X42441Y-227600D02*
D03*
X40441Y-231600D02*
D03*
X42441Y-235600D02*
D03*
Y-243600D02*
D03*
X40441Y-247600D02*
D03*
X42441Y-299600D02*
D03*
Y-331600D02*
D03*
X40441Y-335600D02*
D03*
X42441Y-339600D02*
D03*
X40441Y-343600D02*
D03*
Y-351600D02*
D03*
X38441Y-139600D02*
D03*
X36441Y-143600D02*
D03*
Y-151600D02*
D03*
Y-215600D02*
D03*
Y-223600D02*
D03*
X38441Y-227600D02*
D03*
X36441Y-231600D02*
D03*
X38441Y-235600D02*
D03*
Y-243600D02*
D03*
X36441Y-247600D02*
D03*
X38441Y-251600D02*
D03*
X36441Y-255600D02*
D03*
Y-327600D02*
D03*
X38441Y-331600D02*
D03*
X36441Y-335600D02*
D03*
X38441Y-339600D02*
D03*
X36441Y-343600D02*
D03*
Y-351600D02*
D03*
X34441Y-139600D02*
D03*
X32441Y-143600D02*
D03*
X34441Y-147600D02*
D03*
X32441Y-151600D02*
D03*
X34441Y-163600D02*
D03*
Y-219600D02*
D03*
Y-227600D02*
D03*
Y-235600D02*
D03*
Y-243600D02*
D03*
Y-251600D02*
D03*
Y-267600D02*
D03*
Y-275600D02*
D03*
Y-299600D02*
D03*
Y-307600D02*
D03*
Y-323600D02*
D03*
X32441Y-327600D02*
D03*
X34441Y-331600D02*
D03*
X32441Y-335600D02*
D03*
X34441Y-339600D02*
D03*
X32441Y-343600D02*
D03*
Y-351600D02*
D03*
X30441Y-139600D02*
D03*
X28441Y-143600D02*
D03*
X30441Y-147600D02*
D03*
X28441Y-151600D02*
D03*
X30441Y-163600D02*
D03*
X28441Y-167600D02*
D03*
Y-327600D02*
D03*
X30441Y-331600D02*
D03*
X28441Y-335600D02*
D03*
X30441Y-339600D02*
D03*
X28441Y-343600D02*
D03*
Y-351600D02*
D03*
X26441Y-139600D02*
D03*
X24441Y-143600D02*
D03*
X26441Y-147600D02*
D03*
X24441Y-151600D02*
D03*
X26441Y-163600D02*
D03*
X24441Y-167600D02*
D03*
Y-191600D02*
D03*
X26441Y-195600D02*
D03*
X24441Y-287600D02*
D03*
X26441Y-299600D02*
D03*
X24441Y-303600D02*
D03*
X26441Y-307600D02*
D03*
X24441Y-311600D02*
D03*
X26441Y-331600D02*
D03*
X24441Y-335600D02*
D03*
X26441Y-339600D02*
D03*
X24441Y-343600D02*
D03*
Y-351600D02*
D03*
X22441Y-139600D02*
D03*
X20441Y-143600D02*
D03*
X22441Y-147600D02*
D03*
X20441Y-151600D02*
D03*
X22441Y-163600D02*
D03*
X20441Y-167600D02*
D03*
X22441Y-171600D02*
D03*
X20441Y-191600D02*
D03*
X22441Y-195600D02*
D03*
X20441Y-199600D02*
D03*
Y-231600D02*
D03*
X22441Y-235600D02*
D03*
Y-243600D02*
D03*
X20441Y-247600D02*
D03*
X22441Y-251600D02*
D03*
X20441Y-255600D02*
D03*
X22441Y-259600D02*
D03*
Y-267600D02*
D03*
X20441Y-271600D02*
D03*
X22441Y-283600D02*
D03*
X20441Y-287600D02*
D03*
X22441Y-291600D02*
D03*
Y-299600D02*
D03*
X20441Y-303600D02*
D03*
X22441Y-307600D02*
D03*
X20441Y-311600D02*
D03*
X22441Y-323600D02*
D03*
X20441Y-335600D02*
D03*
X22441Y-339600D02*
D03*
X20441Y-343600D02*
D03*
Y-351600D02*
D03*
X18441Y-139600D02*
D03*
X16441Y-143600D02*
D03*
X18441Y-147600D02*
D03*
X16441Y-151600D02*
D03*
X18441Y-163600D02*
D03*
X16441Y-167600D02*
D03*
X18441Y-171600D02*
D03*
X16441Y-191600D02*
D03*
X18441Y-195600D02*
D03*
X16441Y-199600D02*
D03*
X18441Y-203600D02*
D03*
X16441Y-215600D02*
D03*
X18441Y-219600D02*
D03*
X16441Y-223600D02*
D03*
X18441Y-235600D02*
D03*
Y-243600D02*
D03*
X16441Y-247600D02*
D03*
X18441Y-251600D02*
D03*
X16441Y-255600D02*
D03*
X18441Y-259600D02*
D03*
Y-267600D02*
D03*
X16441Y-271600D02*
D03*
X18441Y-275600D02*
D03*
X16441Y-279600D02*
D03*
X18441Y-291600D02*
D03*
Y-299600D02*
D03*
X16441Y-303600D02*
D03*
X18441Y-307600D02*
D03*
X16441Y-311600D02*
D03*
X18441Y-323600D02*
D03*
X16441Y-327600D02*
D03*
X18441Y-339600D02*
D03*
X16441Y-343600D02*
D03*
Y-351600D02*
D03*
X14441Y-139600D02*
D03*
X12441Y-143600D02*
D03*
X14441Y-147600D02*
D03*
X12441Y-151600D02*
D03*
X14441Y-163600D02*
D03*
X12441Y-167600D02*
D03*
X14441Y-171600D02*
D03*
X12441Y-191600D02*
D03*
X14441Y-195600D02*
D03*
X12441Y-199600D02*
D03*
X14441Y-203600D02*
D03*
X12441Y-215600D02*
D03*
X14441Y-219600D02*
D03*
X12441Y-223600D02*
D03*
X14441Y-243600D02*
D03*
X12441Y-247600D02*
D03*
X14441Y-251600D02*
D03*
X12441Y-255600D02*
D03*
X14441Y-259600D02*
D03*
Y-267600D02*
D03*
X12441Y-271600D02*
D03*
X14441Y-275600D02*
D03*
X12441Y-279600D02*
D03*
X14441Y-291600D02*
D03*
Y-299600D02*
D03*
X12441Y-303600D02*
D03*
X14441Y-307600D02*
D03*
X12441Y-311600D02*
D03*
X14441Y-323600D02*
D03*
X12441Y-327600D02*
D03*
X14441Y-331600D02*
D03*
X12441Y-343600D02*
D03*
Y-351600D02*
D03*
X10441Y-139600D02*
D03*
Y-163600D02*
D03*
Y-171600D02*
D03*
X8441Y-191600D02*
D03*
X10441Y-195600D02*
D03*
Y-203600D02*
D03*
Y-227600D02*
D03*
Y-243600D02*
D03*
X8441Y-247600D02*
D03*
X10441Y-251600D02*
D03*
Y-259600D02*
D03*
Y-267600D02*
D03*
Y-275600D02*
D03*
X8441Y-279600D02*
D03*
X10441Y-299600D02*
D03*
Y-323600D02*
D03*
Y-331600D02*
D03*
X8441Y-351600D02*
D03*
X6441Y-139600D02*
D03*
X4441Y-191600D02*
D03*
X6441Y-243600D02*
D03*
X4441Y-351600D02*
D03*
X2441Y-243600D02*
D03*
X441Y-351600D02*
D03*
X-3559Y-191600D02*
D03*
X-1559Y-243600D02*
D03*
X-3559Y-351600D02*
D03*
X-5559Y-139600D02*
D03*
X-7559Y-143600D02*
D03*
Y-167600D02*
D03*
Y-191600D02*
D03*
Y-199600D02*
D03*
Y-223600D02*
D03*
X-5559Y-227600D02*
D03*
Y-243600D02*
D03*
X-7559Y-247600D02*
D03*
Y-279600D02*
D03*
X-5559Y-299600D02*
D03*
X-7559Y-303600D02*
D03*
Y-327600D02*
D03*
Y-351600D02*
D03*
X-9559Y-139600D02*
D03*
Y-171600D02*
D03*
X-11559Y-191600D02*
D03*
X-9559Y-195600D02*
D03*
Y-227600D02*
D03*
Y-243600D02*
D03*
X-11559Y-247600D02*
D03*
X-9559Y-251600D02*
D03*
Y-275600D02*
D03*
X-11559Y-279600D02*
D03*
X-9559Y-299600D02*
D03*
Y-331600D02*
D03*
X-11559Y-351600D02*
D03*
X-13559Y-139600D02*
D03*
X-15559Y-191600D02*
D03*
X-13559Y-243600D02*
D03*
X-15559Y-351600D02*
D03*
X-19559Y-263600D02*
D03*
Y-351600D02*
D03*
X-23559Y-159600D02*
D03*
Y-191600D02*
D03*
X-21559Y-211600D02*
D03*
X-23559Y-263600D02*
D03*
X-21559Y-315600D02*
D03*
X-23559Y-351600D02*
D03*
X-25559Y-139600D02*
D03*
Y-155600D02*
D03*
Y-211600D02*
D03*
Y-259600D02*
D03*
Y-267600D02*
D03*
Y-299600D02*
D03*
Y-315600D02*
D03*
X234252Y-133742D02*
D03*
X263779Y-106151D02*
D03*
X71850Y-147638D02*
D03*
X75787Y-131890D02*
D03*
X623000Y-37402D02*
D03*
X610236Y-8858D02*
D03*
X609252Y-26575D02*
D03*
X98425Y-102362D02*
D03*
X89567D02*
D03*
X85630Y-313976D02*
D03*
X86614Y-258858D02*
D03*
X81693Y-205709D02*
D03*
X360236Y-268586D02*
D03*
Y-272490D02*
D03*
X63976Y-227362D02*
D03*
X68898Y-285433D02*
D03*
X67913Y-340551D02*
D03*
X68573Y-179321D02*
D03*
X44291Y-252953D02*
D03*
Y-272638D02*
D03*
Y-326772D02*
D03*
Y-307087D02*
D03*
X26575Y-291339D02*
D03*
X31496Y-189961D02*
D03*
X44291Y-147638D02*
D03*
Y-167323D02*
D03*
Y-200787D02*
D03*
Y-220472D02*
D03*
X325787Y-243205D02*
D03*
Y-233362D02*
D03*
X103409Y-141732D02*
D03*
X103347Y-110236D02*
D03*
X119095Y-126047D02*
D03*
X518701Y-104214D02*
D03*
X519587Y-134596D02*
D03*
X528543Y-104214D02*
D03*
X658465Y-21899D02*
D03*
X625000Y-29773D02*
D03*
X114173Y-83088D02*
D03*
X441929Y-122883D02*
D03*
X129921Y-79576D02*
D03*
X163071Y-390730D02*
D03*
X99410Y-50049D02*
D03*
X26495Y-8991D02*
D03*
X512657Y-270462D02*
D03*
X259285Y-390247D02*
D03*
X267204Y-390009D02*
D03*
X216162Y-390947D02*
D03*
X235144Y-390416D02*
D03*
X251456Y-390009D02*
D03*
X226063Y-390722D02*
D03*
X281201Y-390009D02*
D03*
X174941Y-390600D02*
D03*
X202441D02*
D03*
X544291Y-199655D02*
D03*
X509842Y-197687D02*
D03*
X544291Y-201624D02*
D03*
X509842Y-199655D02*
D03*
Y-201624D02*
D03*
X544291Y-197687D02*
D03*
X509842Y-195718D02*
D03*
X361811Y-207087D02*
D03*
X361417Y-203150D02*
D03*
X326969Y-197573D02*
D03*
X326966Y-195171D02*
D03*
X366535Y-202362D02*
D03*
X358661Y-194488D02*
D03*
X634252Y-314567D02*
D03*
X653150Y-314567D02*
D03*
X509391Y-350636D02*
D03*
X508997Y-335675D02*
D03*
X447244Y-324852D02*
D03*
X451181D02*
D03*
X433858D02*
D03*
X460630D02*
D03*
X437795D02*
D03*
X431102D02*
D03*
X444488D02*
D03*
X457480D02*
D03*
X453937D02*
D03*
X440551D02*
D03*
X222638Y-374655D02*
D03*
X218445Y-374108D02*
D03*
X453937Y-306742D02*
D03*
X451181D02*
D03*
X109409Y-140111D02*
D03*
X105409D02*
D03*
X101409D02*
D03*
X97409D02*
D03*
X65945Y-57923D02*
D03*
X615158Y-8858D02*
D03*
X70866Y-122047D02*
D03*
X360204Y-252984D02*
D03*
X417596Y-175197D02*
D03*
X377921Y-203740D02*
D03*
X372016Y-200787D02*
D03*
X354541Y-223636D02*
D03*
X354452Y-235236D02*
D03*
X356578Y-225247D02*
D03*
X379921Y-201740D02*
D03*
X102528Y-211583D02*
D03*
X97125Y-219488D02*
D03*
X99410Y-216535D02*
D03*
X101378Y-214567D02*
D03*
X86614Y-175197D02*
D03*
X361652Y-235205D02*
D03*
X359131Y-223425D02*
D03*
X361531D02*
D03*
X360236Y-262186D02*
D03*
Y-266186D02*
D03*
X85416Y-317699D02*
D03*
X85630Y-263779D02*
D03*
X86562Y-211183D02*
D03*
X411043Y-174974D02*
D03*
X413440Y-174850D02*
D03*
X421596Y-175034D02*
D03*
X406528Y-157767D02*
D03*
X404528Y-163386D02*
D03*
X407480Y-160433D02*
D03*
X86614Y-221457D02*
D03*
X427165Y-175246D02*
D03*
X75787Y-232283D02*
D03*
X87167Y-166377D02*
D03*
X89567Y-166370D02*
D03*
X85630Y-213583D02*
D03*
Y-266179D02*
D03*
Y-320313D02*
D03*
X543276Y-226591D02*
D03*
X544294Y-224248D02*
D03*
X544291Y-233268D02*
D03*
X359252Y-235236D02*
D03*
X356852D02*
D03*
X407480Y-163386D02*
D03*
X47244Y-8858D02*
D03*
X40354D02*
D03*
X33465D02*
D03*
X26575Y19685D02*
D03*
X86614Y-227362D02*
D03*
X63976Y-221457D02*
D03*
X82677Y-232283D02*
D03*
X63976Y-275590D02*
D03*
X75787Y-285433D02*
D03*
X87598Y-275590D02*
D03*
Y-281496D02*
D03*
X81880Y-287582D02*
D03*
X62992Y-329724D02*
D03*
X74803Y-339567D02*
D03*
X78740Y-340551D02*
D03*
X87598Y-335630D02*
D03*
Y-329724D02*
D03*
X63976Y-179134D02*
D03*
X74803D02*
D03*
X86562Y-169257D02*
D03*
X80709Y-180118D02*
D03*
X26575Y-283465D02*
D03*
X30512Y-170276D02*
D03*
X323850Y-241173D02*
D03*
Y-237205D02*
D03*
X323819Y-231299D02*
D03*
X325787Y-229362D02*
D03*
X323819Y-227362D02*
D03*
X325787Y-239205D02*
D03*
X-23622Y-342520D02*
D03*
X89567Y-140270D02*
D03*
X87254Y-139629D02*
D03*
X119095Y-130047D02*
D03*
X117126Y-132047D02*
D03*
X107346Y-110236D02*
D03*
X105347Y-112205D02*
D03*
X99347Y-110236D02*
D03*
X109409Y-112236D02*
D03*
X119095Y-122047D02*
D03*
X-23622Y-229331D02*
D03*
Y-233268D02*
D03*
Y-237205D02*
D03*
Y-241142D02*
D03*
Y-282480D02*
D03*
Y-286417D02*
D03*
Y-290354D02*
D03*
Y-294291D02*
D03*
Y-335630D02*
D03*
Y-339567D02*
D03*
Y-346457D02*
D03*
X107409Y-141732D02*
D03*
X99410D02*
D03*
X-23622Y-70866D02*
D03*
Y-66929D02*
D03*
Y-62992D02*
D03*
Y-60039D02*
D03*
Y-102362D02*
D03*
Y-106299D02*
D03*
Y-110236D02*
D03*
Y-114173D02*
D03*
Y-187992D02*
D03*
Y-184055D02*
D03*
Y-181102D02*
D03*
Y-177165D02*
D03*
X117126Y-128047D02*
D03*
Y-124047D02*
D03*
Y-119921D02*
D03*
X101284Y-112205D02*
D03*
X97284D02*
D03*
X544291Y-195718D02*
D03*
X469521Y-137615D02*
D03*
X533878Y-117716D02*
D03*
X524606Y-125836D02*
D03*
X524557Y-128740D02*
D03*
X450850Y-174127D02*
D03*
X512795Y-104214D02*
D03*
X463551Y-116025D02*
D03*
X658465Y-37647D02*
D03*
Y-29773D02*
D03*
X625000Y-21899D02*
D03*
X190354Y-377411D02*
D03*
X314961Y-118947D02*
D03*
X430807Y-175344D02*
D03*
X309016Y-128659D02*
D03*
X418898Y-144143D02*
D03*
X416106Y-144180D02*
D03*
X398568Y-145083D02*
D03*
X210433Y-374655D02*
D03*
X206496D02*
D03*
X442126Y-306742D02*
D03*
X439370D02*
D03*
X237992Y-374655D02*
D03*
X241929D02*
D03*
X253655Y-374421D02*
D03*
X256890Y-374655D02*
D03*
X273425D02*
D03*
X269502Y-374291D02*
D03*
X246339Y-386975D02*
D03*
X249410Y-387253D02*
D03*
X232480D02*
D03*
X229331D02*
D03*
X436221Y-306742D02*
D03*
X212795Y-387253D02*
D03*
X433465Y-306742D02*
D03*
X215945Y-387253D02*
D03*
X262006Y-387255D02*
D03*
X448032Y-306742D02*
D03*
X265158Y-387253D02*
D03*
X445276Y-306742D02*
D03*
X104528Y-92175D02*
D03*
X269685Y-106151D02*
D03*
X131890Y-72687D02*
D03*
X179134Y-386466D02*
D03*
Y-389616D02*
D03*
X178543Y-377411D02*
D03*
X443898Y-175049D02*
D03*
X99410Y-65797D02*
D03*
Y-57923D02*
D03*
X65945Y-65797D02*
D03*
Y-50049D02*
D03*
X78740Y-238041D02*
D03*
X33465Y19833D02*
D03*
X40354Y19685D02*
D03*
X47244D02*
D03*
X456742Y-116043D02*
D03*
X464328Y-146397D02*
D03*
X469291Y-143848D02*
D03*
X461319Y-143750D02*
D03*
X457283Y-175147D02*
D03*
X469390D02*
D03*
X544291Y-215403D02*
D03*
X512402Y-261958D02*
D03*
Y-265108D02*
D03*
X512543Y-268065D02*
D03*
X437697Y-175246D02*
D03*
X433858D02*
D03*
X404823Y-175344D02*
D03*
X402264D02*
D03*
X309016Y-113986D02*
D03*
X193898Y-115009D02*
D03*
Y-119931D02*
D03*
X309055Y-123868D02*
D03*
X182677Y-386466D02*
D03*
X186614D02*
D03*
X182677Y-389616D02*
D03*
X186614D02*
D03*
D251*
X348211Y-89891D02*
D03*
X357798Y-89963D02*
D03*
D252*
X651545Y-95108D02*
D03*
X413356Y7254D02*
D03*
Y-95108D02*
D03*
X651545Y7254D02*
D03*
X71880Y7412D02*
D03*
X310069Y-94950D02*
D03*
Y7412D02*
D03*
X71880Y-94950D02*
D03*
D253*
X99016Y-121653D02*
D03*
X103347D02*
D03*
X107677D02*
D03*
X99016Y-125984D02*
D03*
X103347D02*
D03*
X107677D02*
D03*
X99016Y-130315D02*
D03*
X103347D02*
D03*
X107677D02*
D03*
M02*
